G04 ================== begin FILE IDENTIFICATION RECORD ==================*
G04 Layout Name:  D:/<user>/Wistron_project/16318-2/gbr/16318-2.brd*
G04 Film Name:    BSILK*
G04 File Format:  Gerber RS274X*
G04 File Origin:  Cadence Allegro 16.5-S056*
G04 Origin Date:  Mon Aug 07 11:09:14 2017*
G04 *
G04 Layer:  VIA CLASS/FILMMASKBOTTOM*
G04 Layer:  REF DES/ASSEMBLY_BOTTOM*
G04 Layer:  PACKAGE GEOMETRY/SILKSCREEN_BOTTOM*
G04 Layer:  DRAWING FORMAT/LAYER_PCB_STORY*
G04 Layer:  DRAWING FORMAT/LAYER_SILK_B*
G04 Layer:  BOARD GEOMETRY/SILKSCREEN_BOTTOM*
G04 *
G04 Offset:    (0.00 0.00)*
G04 Mirror:    No*
G04 Mode:      Positive*
G04 Rotation:  0*
G04 FullContactRelief:  No*
G04 UndefLineWidth:     6.00*
G04 ================== end FILE IDENTIFICATION RECORD ====================*
%FSLAX35Y35*MOIN*%
%IR0*IPPOS*OFA0.00000B0.00000*MIA0B0*SFA1.00000B1.00000*%
%ADD10C,.026*%
%ADD11C,.02*%
%ADD12C,.013*%
%ADD13C,.015*%
%ADD14C,.001*%
%ADD15C,.006*%
%ADD16C,.008*%
G75*
%LPD*%
G75*
G36*
G01X169472Y476503D02*
X177472D01*
Y467403D01*
X169472D01*
Y476503D01*
G37*
G36*
G01X604450Y356650D02*
X607450Y359650D01*
Y356650D01*
X604450D01*
G37*
G54D10*
X65900Y671000D03*
X65700Y660900D03*
X70600Y665800D03*
X60700Y665900D03*
X70800Y660700D03*
X60800Y660900D03*
X70700Y671000D03*
X60600Y670900D03*
X65714Y665850D03*
X135019Y706095D03*
X130019D03*
X139916Y705822D03*
X130019Y724095D03*
X135019Y714845D03*
Y719095D03*
Y723595D03*
Y710595D03*
X130019Y720495D03*
Y716895D03*
Y713295D03*
Y709695D03*
X139916Y723822D03*
Y720222D03*
Y716622D03*
Y713022D03*
Y709422D03*
X306486Y643750D03*
X306286Y633650D03*
X311186Y638550D03*
X301286Y638650D03*
X311386Y633450D03*
X301386Y633650D03*
X311286Y643750D03*
X301186Y643650D03*
X306300Y638600D03*
X295634Y710070D03*
X290520Y715120D03*
X300620Y715220D03*
X290720Y705120D03*
X300720Y704920D03*
X290620Y710120D03*
X300520Y710020D03*
X295620Y705120D03*
X295820Y715220D03*
X371400Y606400D03*
X358900Y612800D03*
X358800Y606300D03*
X365300Y606500D03*
X371400Y612700D03*
X371300Y618800D03*
X365500Y619000D03*
X358900Y618800D03*
X365164Y612620D03*
X468000Y35400D03*
X464000Y35500D03*
X468000Y39500D03*
Y31500D03*
X472000Y35500D03*
X629200Y536040D03*
X629080Y539920D03*
X625500Y536100D03*
X625300Y539900D03*
X700546Y577599D03*
X691796D03*
X691296Y572599D03*
X705696D03*
X696296Y577599D03*
X709296Y572599D03*
Y577599D03*
X702096Y572599D03*
X694896D03*
X698496D03*
X704796Y577599D03*
X709569Y582496D03*
X698769D03*
X695169D03*
X691569D03*
X702369D03*
X705969D03*
X810200Y494900D03*
X815100Y499800D03*
X805200Y499900D03*
X815300Y494700D03*
X805300Y494900D03*
X815200Y505000D03*
X805100Y504900D03*
X810214Y499850D03*
X810400Y505000D03*
G54D11*
G01X-13131Y-65072D02*
Y-145072D01*
G01D02*
X1244069D01*
G01X-29131Y-65072D02*
Y-33072D01*
G01X-13131Y-65072D02*
X1244069D01*
G01X-13131Y-100572D02*
X1244069D01*
G01X-17131Y-49072D02*
G02I-12000J0D01*
G01X-22281D02*
G02I-6850J0D01*
G01X-13131D02*
X-45131D01*
G01X50300Y588850D02*
Y583850D01*
G01X140324Y548546D02*
X135324D01*
G01X137949Y562749D02*
X132949D01*
G01X96300Y708200D02*
Y703200D01*
G01X177772Y478953D02*
X185472D01*
G01X188710Y619520D02*
Y624520D01*
G01X217800Y521900D02*
X222800D01*
G01X249570Y622940D02*
X244570D01*
G01X324822Y186794D02*
Y181794D01*
G01X314772Y196544D02*
X309772D01*
G01X324848Y194494D02*
Y189494D01*
G01X314249Y218907D02*
Y223907D01*
G01X314279Y226657D02*
Y231657D01*
G01X330112Y235554D02*
X325112D01*
G01X325052Y221384D02*
X330052D01*
G01X353400Y679100D02*
X343900D01*
G01X456569Y-65072D02*
Y-145072D01*
G01X480443Y37965D02*
X475443D01*
G01X594069Y-65072D02*
Y-145072D01*
G01X619600Y282800D02*
Y291600D01*
G01X618500Y483500D02*
Y478500D01*
G01Y475500D02*
Y470500D01*
G01X709069Y-65072D02*
Y-145072D01*
G01X682000Y306500D02*
X677000D01*
G01X725100Y462200D02*
Y467200D01*
G01Y454400D02*
Y459400D01*
G01X701176Y551929D02*
Y556929D01*
G01X777800Y198500D02*
Y193500D01*
G01X792037Y198518D02*
Y193518D01*
G01X757500Y201800D02*
Y196800D01*
G01Y194000D02*
Y189000D01*
G01X776410Y239450D02*
Y244450D01*
G01X767590Y223080D02*
X772590D01*
G01X735400Y263650D02*
Y258650D01*
G01X758150Y232270D02*
X763150D01*
G01X739150Y231800D02*
X744150D01*
G01X772800Y273800D02*
X767800D01*
G01X803726Y365556D02*
X798726D01*
G01X806362Y198483D02*
Y193483D01*
G01X834000Y336500D02*
Y341500D01*
G01X839400Y479000D02*
Y484000D01*
G01X876569Y-65072D02*
Y-145072D01*
G01X1046569Y-65072D02*
Y-145072D01*
G01X1244069Y-65072D02*
Y-145072D01*
G01X1272069Y-49072D02*
G02I-12000J0D01*
G01X1266919D02*
G02I-6850J0D01*
G01X1276069D02*
X1244069D01*
G01X1260069Y-65072D02*
Y-33072D01*
G54D12*
G01X130700Y490250D02*
Y493100D01*
X128000D01*
G01X214000Y508080D02*
X211150D01*
Y505380D01*
G01X324500Y514600D02*
Y517450D01*
X321800D01*
G01X373200Y522500D02*
Y525350D01*
X370500D01*
G01X368780Y535000D02*
Y537850D01*
X366080D01*
G01X378520Y706100D02*
Y703250D01*
X381220D01*
G01X350720Y702000D02*
Y699150D01*
X353420D01*
G01X350620Y689400D02*
Y686550D01*
X353320D01*
G01X569900Y64900D02*
Y62050D01*
X572600D01*
G01X547400Y69900D02*
Y67050D01*
X550100D01*
G54D13*
G01X120197Y59055D02*
Y98425D01*
G01X184173Y433268D02*
X223543D01*
G01X287520Y98425D02*
Y59055D01*
G01X408268Y347638D02*
Y316929D01*
G01Y690803D02*
Y721512D01*
G01X568110Y316929D02*
Y347638D01*
G01Y721512D02*
Y690803D01*
G54D14*
G01X339200Y676900D02*
Y659350D01*
G01X339250Y659310D02*
Y676900D01*
G01X339350Y659310D02*
Y676900D01*
G01X339300D02*
Y659350D01*
G01X339450Y659310D02*
Y676900D01*
G01X339400D02*
Y659350D01*
G01X339550Y659310D02*
Y676900D01*
G01X339500D02*
Y659350D01*
G01X339650Y659310D02*
Y676900D01*
G01X339600D02*
Y659350D01*
G01X339750Y659310D02*
Y676900D01*
G01X339700D02*
Y659350D01*
G01X339850Y659310D02*
Y676900D01*
G01X339800D02*
Y659350D01*
G01X339950Y659310D02*
Y676900D01*
G01X339900D02*
Y659350D01*
G01X340000Y676900D02*
Y659350D01*
G01X338300Y676900D02*
Y659350D01*
G01X338350Y659310D02*
Y676900D01*
G01X338450Y659310D02*
Y676900D01*
G01X338400D02*
Y659350D01*
G01X338550Y659310D02*
Y676900D01*
G01X338500D02*
Y659350D01*
G01X338650Y659310D02*
Y676900D01*
G01X338600D02*
Y659350D01*
G01X338750Y659310D02*
Y676900D01*
G01X338700D02*
Y659350D01*
G01X338850Y659310D02*
Y676900D01*
G01X338800D02*
Y659350D01*
G01X338950Y659310D02*
Y676900D01*
G01X338900D02*
Y659350D01*
G01X339050Y659310D02*
Y676900D01*
G01X339000D02*
Y659350D01*
G01X339150Y659310D02*
Y676900D01*
G01X339100D02*
Y659350D01*
G01X337400Y676900D02*
Y659350D01*
G01X337450Y659310D02*
Y676900D01*
G01X337550Y659310D02*
Y676900D01*
G01X337500D02*
Y659350D01*
G01X337650Y659310D02*
Y676900D01*
G01X337600D02*
Y659350D01*
G01X337750Y659310D02*
Y676900D01*
G01X337700D02*
Y659350D01*
G01X337850Y659310D02*
Y676900D01*
G01X337800D02*
Y659350D01*
G01X337950Y659310D02*
Y676900D01*
G01X337900D02*
Y659350D01*
G01X338050Y659310D02*
Y676900D01*
G01X338000D02*
Y659350D01*
G01X338150Y659310D02*
Y676900D01*
G01X338100D02*
Y659350D01*
G01X338250Y659310D02*
Y676900D01*
G01X338200D02*
Y659350D01*
G01X336500Y676900D02*
Y659350D01*
G01X336550Y659310D02*
Y676900D01*
G01X336650Y659310D02*
Y676900D01*
G01X336600D02*
Y659350D01*
G01X336750Y659310D02*
Y676900D01*
G01X336700D02*
Y659350D01*
G01X336850Y659310D02*
Y676900D01*
G01X336800D02*
Y659350D01*
G01X336950Y659310D02*
Y676900D01*
G01X336900D02*
Y659350D01*
G01X337050Y659310D02*
Y676900D01*
G01X337000D02*
Y659350D01*
G01X337150Y659310D02*
Y676900D01*
G01X337100D02*
Y659350D01*
G01X337250Y659310D02*
Y676900D01*
G01X337200D02*
Y659350D01*
G01X337350Y659310D02*
Y676900D01*
G01X337300D02*
Y659350D01*
G01X335600Y676900D02*
Y659350D01*
G01X335650Y659310D02*
Y676900D01*
G01X335750Y659310D02*
Y676900D01*
G01X335700D02*
Y659350D01*
G01X335850Y659310D02*
Y676900D01*
G01X335800D02*
Y659350D01*
G01X335950Y659310D02*
Y676900D01*
G01X335900D02*
Y659350D01*
G01X336050Y659310D02*
Y676900D01*
G01X336000D02*
Y659350D01*
G01X336150Y659310D02*
Y676900D01*
G01X336100D02*
Y659350D01*
G01X336250Y659310D02*
Y676900D01*
G01X336200D02*
Y659350D01*
G01X336350Y659310D02*
Y676900D01*
G01X336300D02*
Y659350D01*
G01X336450Y659310D02*
Y676900D01*
G01X336400D02*
Y659350D01*
G01X334700Y676900D02*
Y659350D01*
G01X334750Y659310D02*
Y676900D01*
G01X334850Y659310D02*
Y676900D01*
G01X334800D02*
Y659350D01*
G01X334950Y659310D02*
Y676900D01*
G01X334900D02*
Y659350D01*
G01X335050Y659310D02*
Y676900D01*
G01X335000D02*
Y659350D01*
G01X335150Y659310D02*
Y676900D01*
G01X335100D02*
Y659350D01*
G01X335250Y659310D02*
Y676900D01*
G01X335200D02*
Y659350D01*
G01X335350Y659310D02*
Y676900D01*
G01X335300D02*
Y659350D01*
G01X335450Y659310D02*
Y676900D01*
G01X335400D02*
Y659350D01*
G01X335550Y659310D02*
Y676900D01*
G01X335500D02*
Y659350D01*
G01X333800Y676900D02*
Y659350D01*
G01X333850Y659310D02*
Y676900D01*
G01X333950Y659310D02*
Y676900D01*
G01X333900D02*
Y659350D01*
G01X334050Y659310D02*
Y676900D01*
G01X334000D02*
Y659350D01*
G01X334150Y659310D02*
Y676900D01*
G01X334100D02*
Y659350D01*
G01X334250Y659310D02*
Y676900D01*
G01X334200D02*
Y659350D01*
G01X334350Y659310D02*
Y676900D01*
G01X334300D02*
Y659350D01*
G01X334450Y659310D02*
Y676900D01*
G01X334400D02*
Y659350D01*
G01X334550Y659310D02*
Y676900D01*
G01X334500D02*
Y659350D01*
G01X334650Y659310D02*
Y676900D01*
G01X334600D02*
Y659350D01*
G01X332900Y676900D02*
Y659350D01*
G01X332950Y659310D02*
Y676900D01*
G01X333050Y659310D02*
Y676900D01*
G01X333000D02*
Y659350D01*
G01X333150Y659310D02*
Y676900D01*
G01X333100D02*
Y659350D01*
G01X333250Y659310D02*
Y676900D01*
G01X333200D02*
Y659350D01*
G01X333350Y659310D02*
Y676900D01*
G01X333300D02*
Y659350D01*
G01X333450Y659310D02*
Y676900D01*
G01X333400D02*
Y659350D01*
G01X333550Y659310D02*
Y676900D01*
G01X333500D02*
Y659350D01*
G01X333650Y659310D02*
Y676900D01*
G01X333600D02*
Y659350D01*
G01X333750Y659310D02*
Y676900D01*
G01X333700D02*
Y659350D01*
G01X332000Y676900D02*
Y659350D01*
G01X332050Y659310D02*
Y676900D01*
G01X332150Y659310D02*
Y676900D01*
G01X332100D02*
Y659350D01*
G01X332250Y659310D02*
Y676900D01*
G01X332200D02*
Y659350D01*
G01X332350Y659310D02*
Y676900D01*
G01X332300D02*
Y659350D01*
G01X332450Y659310D02*
Y676900D01*
G01X332400D02*
Y659350D01*
G01X332550Y659310D02*
Y676900D01*
G01X332500D02*
Y659350D01*
G01X332650Y659310D02*
Y676900D01*
G01X332600D02*
Y659350D01*
G01X332750Y659310D02*
Y676900D01*
G01X332700D02*
Y659350D01*
G01X332850Y659310D02*
Y676900D01*
G01X332800D02*
Y659350D01*
G01X331100Y676900D02*
Y659350D01*
G01X331150Y659310D02*
Y676900D01*
G01X331250Y659310D02*
Y676900D01*
G01X331200D02*
Y659350D01*
G01X331350Y659310D02*
Y676900D01*
G01X331300D02*
Y659350D01*
G01X331450Y659310D02*
Y676900D01*
G01X331400D02*
Y659350D01*
G01X331550Y659310D02*
Y676900D01*
G01X331500D02*
Y659350D01*
G01X331650Y659310D02*
Y676900D01*
G01X331600D02*
Y659350D01*
G01X331750Y659310D02*
Y676900D01*
G01X331700D02*
Y659350D01*
G01X331850Y659310D02*
Y676900D01*
G01X331800D02*
Y659350D01*
G01X331950Y659310D02*
Y676900D01*
G01X331900D02*
Y659350D01*
G01X331000Y676900D02*
Y659350D01*
G01X331050Y659310D02*
Y676900D01*
G01X330900D02*
Y659350D01*
G01X330950Y659310D02*
Y676900D01*
G01X330800D02*
Y659350D01*
G01X330850Y659310D02*
Y676900D01*
G01X330700D02*
Y659350D01*
G01X330750Y659310D02*
Y676900D01*
G01X330600D02*
Y659350D01*
G01X330650Y659310D02*
Y676900D01*
G01X330500D02*
Y659350D01*
G01X330550Y659310D02*
Y676900D01*
G01X330400D02*
Y659350D01*
G01X330450Y659310D02*
Y676900D01*
G01X330300D02*
Y659350D01*
G01X330350Y659310D02*
Y676900D01*
G01X330250Y659310D02*
Y676900D01*
G01X330200D02*
Y659350D01*
G01X330150Y676900D02*
Y659300D01*
X344650D01*
Y676900D01*
X330150D01*
G01X344600Y659310D02*
Y676900D01*
G01X343700D02*
Y659350D01*
G01X343750Y659310D02*
Y676900D01*
G01X343850Y659310D02*
Y676900D01*
G01X343800D02*
Y659350D01*
G01X343950Y659310D02*
Y676900D01*
G01X343900D02*
Y659350D01*
G01X344050Y659310D02*
Y676900D01*
G01X344000D02*
Y659350D01*
G01X344150Y659310D02*
Y676900D01*
G01X344100D02*
Y659350D01*
G01X344250Y659310D02*
Y676900D01*
G01X344200D02*
Y659350D01*
G01X344350Y659310D02*
Y676900D01*
G01X344300D02*
Y659350D01*
G01X344450Y659310D02*
Y676900D01*
G01X344400D02*
Y659350D01*
G01X344550Y659310D02*
Y676900D01*
G01X344500D02*
Y659350D01*
G01X342800Y676900D02*
Y659350D01*
G01X342850Y659310D02*
Y676900D01*
G01X342950Y659310D02*
Y676900D01*
G01X342900D02*
Y659350D01*
G01X343050Y659310D02*
Y676900D01*
G01X343000D02*
Y659350D01*
G01X343150Y659310D02*
Y676900D01*
G01X343100D02*
Y659350D01*
G01X343250Y659310D02*
Y676900D01*
G01X343200D02*
Y659350D01*
G01X343350Y659310D02*
Y676900D01*
G01X343300D02*
Y659350D01*
G01X343450Y659310D02*
Y676900D01*
G01X343400D02*
Y659350D01*
G01X343550Y659310D02*
Y676900D01*
G01X343500D02*
Y659350D01*
G01X343650Y659310D02*
Y676900D01*
G01X343600D02*
Y659350D01*
G01X341900Y676900D02*
Y659350D01*
G01X341950Y659310D02*
Y676900D01*
G01X342050Y659310D02*
Y676900D01*
G01X342000D02*
Y659350D01*
G01X342150Y659310D02*
Y676900D01*
G01X342100D02*
Y659350D01*
G01X342250Y659310D02*
Y676900D01*
G01X342200D02*
Y659350D01*
G01X342350Y659310D02*
Y676900D01*
G01X342300D02*
Y659350D01*
G01X342450Y659310D02*
Y676900D01*
G01X342400D02*
Y659350D01*
G01X342550Y659310D02*
Y676900D01*
G01X342500D02*
Y659350D01*
G01X342650Y659310D02*
Y676900D01*
G01X342600D02*
Y659350D01*
G01X342750Y659310D02*
Y676900D01*
G01X342700D02*
Y659350D01*
G01X341000Y676900D02*
Y659350D01*
G01X341050Y659310D02*
Y676900D01*
G01X341150Y659310D02*
Y676900D01*
G01X341100D02*
Y659350D01*
G01X341250Y659310D02*
Y676900D01*
G01X341200D02*
Y659350D01*
G01X341350Y659310D02*
Y676900D01*
G01X341300D02*
Y659350D01*
G01X341450Y659310D02*
Y676900D01*
G01X341400D02*
Y659350D01*
G01X341550Y659310D02*
Y676900D01*
G01X341500D02*
Y659350D01*
G01X341650Y659310D02*
Y676900D01*
G01X341600D02*
Y659350D01*
G01X341750Y659310D02*
Y676900D01*
G01X341700D02*
Y659350D01*
G01X341850Y659310D02*
Y676900D01*
G01X341800D02*
Y659350D01*
G01X340100Y676900D02*
Y659350D01*
G01X340150Y659310D02*
Y676900D01*
G01X340250Y659310D02*
Y676900D01*
G01X340200D02*
Y659350D01*
G01X340350Y659310D02*
Y676900D01*
G01X340300D02*
Y659350D01*
G01X340450Y659310D02*
Y676900D01*
G01X340400D02*
Y659350D01*
G01X340550Y659310D02*
Y676900D01*
G01X340500D02*
Y659350D01*
G01X340650Y659310D02*
Y676900D01*
G01X340600D02*
Y659350D01*
G01X340750Y659310D02*
Y676900D01*
G01X340700D02*
Y659350D01*
G01X340850Y659310D02*
Y676900D01*
G01X340800D02*
Y659350D01*
G01X340950Y659310D02*
Y676900D01*
G01X340900D02*
Y659350D01*
G01X340050Y659310D02*
Y676900D01*
G54D15*
G01X13215Y-125739D02*
X14089Y-124864D01*
X14744Y-123406D01*
X15181Y-121363D01*
X14744Y-119614D01*
X13871Y-118447D01*
X12342Y-117572D01*
X6447D01*
Y-135072D01*
X13652D01*
X15181Y-133906D01*
X16054Y-132155D01*
X16491Y-130114D01*
X16054Y-128072D01*
X14744Y-126322D01*
X13215Y-125739D01*
X6447D01*
G01X25912Y-135072D02*
Y-123406D01*
G01Y-125739D02*
X27004Y-124572D01*
X28096Y-123697D01*
X29624Y-123406D01*
X30715Y-123697D01*
X32026Y-124572D01*
G01X41884Y-140322D02*
X43194Y-140905D01*
X44941Y-140322D01*
X46032Y-139156D01*
X46906Y-137697D01*
X48215Y-133031D01*
X51054Y-123406D01*
G01X44067D02*
X48215Y-133031D01*
G01X67462Y-124864D02*
X65934Y-123697D01*
X64624Y-123406D01*
X62877Y-123989D01*
X61567Y-125155D01*
X60694Y-127197D01*
X60475Y-129239D01*
X60694Y-131281D01*
X61567Y-133031D01*
X62877Y-134489D01*
X64624Y-135072D01*
X66152Y-134489D01*
X67462Y-133322D01*
G01X78194Y-127197D02*
X85181D01*
X84526Y-125155D01*
X83434Y-123989D01*
X81906Y-123406D01*
X80377Y-123697D01*
X79067Y-124572D01*
X78194Y-126614D01*
X77757Y-128364D01*
Y-130114D01*
X78194Y-131864D01*
X79286Y-133614D01*
X80596Y-134780D01*
X82124Y-135072D01*
X83652Y-134489D01*
X85181Y-132739D01*
G01X121272Y-119031D02*
X119962Y-118155D01*
X118434Y-117572D01*
X116687D01*
X114722Y-118447D01*
X113194Y-119905D01*
X112102Y-121656D01*
X111229Y-124572D01*
X111010Y-127197D01*
X111447Y-129822D01*
X112102Y-131572D01*
X113412Y-133322D01*
X114941Y-134489D01*
X116469Y-135072D01*
X117997D01*
X119526Y-134489D01*
X120836Y-133614D01*
X121928Y-132448D01*
G01X137899Y-135072D02*
Y-123406D01*
G01Y-125447D02*
X137026Y-124281D01*
X135715Y-123697D01*
X134187Y-123406D01*
X132659Y-123989D01*
X131349Y-125155D01*
X130475Y-126905D01*
X130039Y-129239D01*
X130475Y-131572D01*
X131349Y-133322D01*
X132659Y-134489D01*
X134187Y-135072D01*
X135715Y-134780D01*
X137026Y-133906D01*
X137899Y-132739D01*
G01X147757Y-135072D02*
Y-123406D01*
G01Y-126322D02*
X148631Y-124864D01*
X149941Y-123697D01*
X151687Y-123406D01*
X153215Y-123697D01*
X154526Y-124864D01*
X155181Y-126905D01*
Y-135072D01*
G01X164384Y-140322D02*
X165694Y-140905D01*
X167441Y-140322D01*
X168532Y-139156D01*
X169406Y-137697D01*
X170715Y-133031D01*
X173554Y-123406D01*
G01X166567D02*
X170715Y-133031D01*
G01X186469Y-135072D02*
X185159Y-134780D01*
X183849Y-133614D01*
X182975Y-131572D01*
X182539Y-129239D01*
X182975Y-126905D01*
X183849Y-124864D01*
X185159Y-123697D01*
X186469Y-123406D01*
X187779Y-123697D01*
X189089Y-124864D01*
X189962Y-126905D01*
X190181Y-129239D01*
X189962Y-131572D01*
X189089Y-133614D01*
X187779Y-134780D01*
X186469Y-135072D01*
G01X200257D02*
Y-123406D01*
G01Y-126322D02*
X201131Y-124864D01*
X202441Y-123697D01*
X204187Y-123406D01*
X205715Y-123697D01*
X207026Y-124864D01*
X207681Y-126905D01*
Y-135072D01*
G01X236349Y-117572D02*
X241589D01*
G01X238969D02*
Y-135072D01*
G01X236349D02*
X241589D01*
G01X256469D02*
X254722Y-134780D01*
X253194Y-133614D01*
X251884Y-131864D01*
X251010Y-129822D01*
X250574Y-127489D01*
Y-125155D01*
X251010Y-122822D01*
X251884Y-120780D01*
X253194Y-119031D01*
X254722Y-117864D01*
X256469Y-117572D01*
X258215Y-117864D01*
X259744Y-119031D01*
X261054Y-120780D01*
X261928Y-122822D01*
X262364Y-125155D01*
Y-127489D01*
X261928Y-129822D01*
X261054Y-131864D01*
X259744Y-133614D01*
X258215Y-134780D01*
X256469Y-135072D01*
G01X268292D02*
Y-117572D01*
X273969Y-132155D01*
X279646Y-117572D01*
Y-135072D01*
G01X307877Y-140905D02*
X305694Y-137989D01*
X304602Y-135072D01*
Y-123406D01*
X305694Y-120489D01*
X307877Y-117572D01*
G01X321010Y-123406D02*
X323631Y-135072D01*
X326469Y-123406D01*
X329307Y-135072D01*
X331928Y-123406D01*
G01X340039Y-135655D02*
X347899Y-117572D01*
G01X376349D02*
X381589D01*
G01X378969D02*
Y-135072D01*
G01X376349D02*
X381589D01*
G01X396469D02*
X394722Y-134780D01*
X393194Y-133614D01*
X391884Y-131864D01*
X391010Y-129822D01*
X390574Y-127489D01*
Y-125155D01*
X391010Y-122822D01*
X391884Y-120780D01*
X393194Y-119031D01*
X394722Y-117864D01*
X396469Y-117572D01*
X398215Y-117864D01*
X399744Y-119031D01*
X401054Y-120780D01*
X401928Y-122822D01*
X402364Y-125155D01*
Y-127489D01*
X401928Y-129822D01*
X401054Y-131864D01*
X399744Y-133614D01*
X398215Y-134780D01*
X396469Y-135072D01*
G01X418772Y-119031D02*
X417462Y-118155D01*
X415934Y-117572D01*
X414187D01*
X412222Y-118447D01*
X410694Y-119905D01*
X409602Y-121656D01*
X408729Y-124572D01*
X408510Y-127197D01*
X408947Y-129822D01*
X409602Y-131572D01*
X410912Y-133322D01*
X412441Y-134489D01*
X413969Y-135072D01*
X415497D01*
X417026Y-134489D01*
X418336Y-133614D01*
X419428Y-132448D01*
G01X432561Y-140905D02*
X434744Y-137989D01*
X435836Y-135072D01*
Y-123406D01*
X434744Y-120489D01*
X432561Y-117572D01*
G01X180792Y-90072D02*
Y-72572D01*
X186469Y-87155D01*
X192146Y-72572D01*
Y-90072D01*
G01X203969D02*
X202659Y-89780D01*
X201349Y-88614D01*
X200475Y-86572D01*
X200039Y-84239D01*
X200475Y-81905D01*
X201349Y-79864D01*
X202659Y-78697D01*
X203969Y-78406D01*
X205279Y-78697D01*
X206589Y-79864D01*
X207462Y-81905D01*
X207681Y-84239D01*
X207462Y-86572D01*
X206589Y-88614D01*
X205279Y-89780D01*
X203969Y-90072D01*
G01X225399Y-72572D02*
Y-90072D01*
G01Y-87448D02*
X224526Y-88906D01*
X223215Y-89780D01*
X221687Y-90072D01*
X219941Y-89489D01*
X218631Y-88031D01*
X217757Y-86281D01*
X217539Y-84239D01*
X217757Y-82197D01*
X218631Y-80447D01*
X219941Y-78989D01*
X221687Y-78406D01*
X223215Y-78697D01*
X224307Y-79281D01*
X225399Y-80447D01*
G01X235694Y-82197D02*
X242681D01*
X242026Y-80155D01*
X240934Y-78989D01*
X239406Y-78406D01*
X237877Y-78697D01*
X236567Y-79572D01*
X235694Y-81614D01*
X235257Y-83364D01*
Y-85114D01*
X235694Y-86864D01*
X236786Y-88614D01*
X238096Y-89780D01*
X239624Y-90072D01*
X241152Y-89489D01*
X242681Y-87739D01*
G01X256469Y-90072D02*
Y-72572D01*
G01X341400Y668100D02*
X333400D01*
G01X337400Y672100D02*
Y664100D01*
G01X490269Y-135072D02*
Y-117572D01*
X487649Y-121072D01*
G01Y-135072D02*
X492889D01*
G01X503621Y-127781D02*
X505149Y-125739D01*
X506459Y-124572D01*
X508206Y-123989D01*
X509734Y-124572D01*
X510826Y-125739D01*
X511699Y-127489D01*
X511917Y-129530D01*
X511699Y-131281D01*
X510826Y-133031D01*
X509515Y-134489D01*
X507987Y-135072D01*
X506241Y-134489D01*
X504712Y-132739D01*
X503839Y-130114D01*
X503621Y-127197D01*
X504057Y-123406D01*
X504712Y-121363D01*
X505804Y-119322D01*
X507332Y-117864D01*
X508861Y-117572D01*
X510389Y-118155D01*
X511481Y-119614D01*
G01X520466Y-131572D02*
X521775Y-133614D01*
X523522Y-134780D01*
X525487Y-135072D01*
X527234Y-134780D01*
X528981Y-133322D01*
X530072Y-131572D01*
X530291Y-129822D01*
X529854Y-127781D01*
X528326Y-126322D01*
X526797Y-125739D01*
X524832D01*
G01X526797D02*
X528107Y-124864D01*
X529199Y-123406D01*
X529636Y-121656D01*
X529199Y-119905D01*
X528107Y-118447D01*
X526142Y-117572D01*
X524177Y-117864D01*
X522212Y-119031D01*
G01X542769Y-135072D02*
Y-117572D01*
X540149Y-121072D01*
G01Y-135072D02*
X545389D01*
G01X560269D02*
X561797Y-134780D01*
X563544Y-133906D01*
X564636Y-132448D01*
X565072Y-130405D01*
X564636Y-128364D01*
X563326Y-126614D01*
X561361Y-125739D01*
X559177D01*
X557867Y-125155D01*
X556775Y-123697D01*
X556339Y-121656D01*
X556994Y-119614D01*
X558522Y-118155D01*
X560269Y-117572D01*
X562015Y-118155D01*
X563544Y-119614D01*
X564199Y-121656D01*
X563762Y-123697D01*
X562671Y-125155D01*
X561361Y-125739D01*
X559177D01*
X557212Y-126614D01*
X555902Y-128364D01*
X555466Y-130405D01*
X555902Y-132448D01*
X556994Y-133906D01*
X558741Y-134780D01*
X560269Y-135072D01*
G01X477152Y-90072D02*
Y-72572D01*
X482392D01*
X484139Y-73447D01*
X485449Y-75489D01*
X485886Y-77822D01*
X485449Y-80155D01*
X484357Y-81905D01*
X482392Y-82781D01*
X477152D01*
G01X503822Y-74031D02*
X502512Y-73155D01*
X500984Y-72572D01*
X499237D01*
X497272Y-73447D01*
X495744Y-74905D01*
X494652Y-76656D01*
X493779Y-79572D01*
X493560Y-82197D01*
X493997Y-84822D01*
X494652Y-86572D01*
X495962Y-88322D01*
X497491Y-89489D01*
X499019Y-90072D01*
X500547D01*
X502076Y-89489D01*
X503386Y-88614D01*
X504478Y-87448D01*
G01X518265Y-80739D02*
X519139Y-79864D01*
X519794Y-78406D01*
X520231Y-76363D01*
X519794Y-74614D01*
X518921Y-73447D01*
X517392Y-72572D01*
X511497D01*
Y-90072D01*
X518702D01*
X520231Y-88906D01*
X521104Y-87155D01*
X521541Y-85114D01*
X521104Y-83072D01*
X519794Y-81322D01*
X518265Y-80739D01*
X511497D01*
G01X527469Y-95905D02*
X540569D01*
G01X546497Y-90072D02*
Y-72572D01*
X556541Y-90072D01*
Y-72572D01*
G01X569019Y-90072D02*
X567272Y-89780D01*
X565744Y-88614D01*
X564434Y-86864D01*
X563560Y-84822D01*
X563124Y-82489D01*
Y-80155D01*
X563560Y-77822D01*
X564434Y-75780D01*
X565744Y-74031D01*
X567272Y-72864D01*
X569019Y-72572D01*
X570765Y-72864D01*
X572294Y-74031D01*
X573604Y-75780D01*
X574478Y-77822D01*
X574914Y-80155D01*
Y-82489D01*
X574478Y-84822D01*
X573604Y-86864D01*
X572294Y-88614D01*
X570765Y-89780D01*
X569019Y-90072D01*
G01X647421Y-120489D02*
X648731Y-118739D01*
X650259Y-117864D01*
X652006Y-117572D01*
X654189Y-118155D01*
X655717Y-119614D01*
X656154Y-121363D01*
X655936Y-123114D01*
X655062Y-124572D01*
X650696Y-127489D01*
X648731Y-129530D01*
X647421Y-132448D01*
X646984Y-135072D01*
X656154D01*
G01X619860Y-72572D02*
X625319Y-90072D01*
X630778Y-72572D01*
G01X647186Y-90072D02*
X638452D01*
Y-72572D01*
X647186D01*
G01X643692Y-81030D02*
X638452D01*
G01X655952Y-90072D02*
Y-72572D01*
X661411D01*
X663157Y-73447D01*
X664249Y-74614D01*
X664686Y-76947D01*
X664249Y-79281D01*
X662939Y-80739D01*
X661411Y-81614D01*
X655952D01*
G01X661411D02*
X664686Y-90072D01*
G01X677819Y-90655D02*
X677382Y-90364D01*
Y-89780D01*
X677819Y-89489D01*
X678256Y-89780D01*
Y-90364D01*
X677819Y-90655D01*
G01X826023Y-125739D02*
X825149Y-124864D01*
X824494Y-123406D01*
X824057Y-121363D01*
X824494Y-119614D01*
X825367Y-118447D01*
X826896Y-117572D01*
X832791D01*
Y-135072D01*
X825586D01*
X824057Y-133906D01*
X823184Y-132155D01*
X822747Y-130114D01*
X823184Y-128072D01*
X824494Y-126322D01*
X826023Y-125739D01*
X832791D01*
G01X814854Y-132739D02*
X813107Y-134197D01*
X811142Y-135072D01*
X809396D01*
X807649Y-134197D01*
X806339Y-132739D01*
X805684Y-130697D01*
X806121Y-128656D01*
X807212Y-126905D01*
X809177Y-125739D01*
X811797Y-125155D01*
X813326Y-123989D01*
X813981Y-121947D01*
X813544Y-119905D01*
X812452Y-118447D01*
X810924Y-117572D01*
X809396D01*
X807867Y-118155D01*
X806557Y-119614D01*
G01X795389Y-117572D02*
X790149D01*
G01X792769D02*
Y-135072D01*
G01X795389D02*
X790149D01*
G01X779636Y-117572D02*
Y-135072D01*
X770902D01*
G01X762572D02*
Y-117572D01*
G01X754276D02*
X762572Y-128364D01*
G01X752966Y-135072D02*
X758861Y-123406D01*
G01X753402Y-72572D02*
Y-90072D01*
X762136D01*
G01X779199D02*
Y-78406D01*
G01Y-80447D02*
X778326Y-79281D01*
X777015Y-78697D01*
X775487Y-78406D01*
X773959Y-78989D01*
X772649Y-80155D01*
X771775Y-81905D01*
X771339Y-84239D01*
X771775Y-86572D01*
X772649Y-88322D01*
X773959Y-89489D01*
X775487Y-90072D01*
X777015Y-89780D01*
X778326Y-88906D01*
X779199Y-87739D01*
G01X788184Y-95322D02*
X789494Y-95905D01*
X791241Y-95322D01*
X792332Y-94156D01*
X793206Y-92697D01*
X794515Y-88031D01*
X797354Y-78406D01*
G01X790367D02*
X794515Y-88031D01*
G01X806994Y-82197D02*
X813981D01*
X813326Y-80155D01*
X812234Y-78989D01*
X810706Y-78406D01*
X809177Y-78697D01*
X807867Y-79572D01*
X806994Y-81614D01*
X806557Y-83364D01*
Y-85114D01*
X806994Y-86864D01*
X808086Y-88614D01*
X809396Y-89780D01*
X810924Y-90072D01*
X812452Y-89489D01*
X813981Y-87739D01*
G01X824712Y-90072D02*
Y-78406D01*
G01Y-80739D02*
X825804Y-79572D01*
X826896Y-78697D01*
X828424Y-78406D01*
X829515Y-78697D01*
X830826Y-79572D01*
G01X917819Y-135072D02*
X916072Y-134780D01*
X914544Y-133614D01*
X913234Y-131864D01*
X912360Y-129822D01*
X911924Y-127489D01*
Y-125155D01*
X912360Y-122822D01*
X913234Y-120780D01*
X914544Y-119031D01*
X916072Y-117864D01*
X917819Y-117572D01*
X919565Y-117864D01*
X921094Y-119031D01*
X922404Y-120780D01*
X923278Y-122822D01*
X923714Y-125155D01*
Y-127489D01*
X923278Y-129822D01*
X922404Y-131864D01*
X921094Y-133614D01*
X919565Y-134780D01*
X917819Y-135072D01*
G01X919565Y-130405D02*
X922186Y-135072D01*
G01X930516Y-117572D02*
Y-130114D01*
X931389Y-132739D01*
X933136Y-134489D01*
X935319Y-135072D01*
X937502Y-134489D01*
X939249Y-132739D01*
X940122Y-130114D01*
Y-117572D01*
G01X950199D02*
X955439D01*
G01X952819D02*
Y-135072D01*
G01X950199D02*
X955439D01*
G01X965297D02*
Y-117572D01*
X975341Y-135072D01*
Y-117572D01*
G01X992622Y-119031D02*
X991312Y-118155D01*
X989784Y-117572D01*
X988037D01*
X986072Y-118447D01*
X984544Y-119905D01*
X983452Y-121656D01*
X982579Y-124572D01*
X982360Y-127197D01*
X982797Y-129822D01*
X983452Y-131572D01*
X984762Y-133322D01*
X986291Y-134489D01*
X987819Y-135072D01*
X989347D01*
X990876Y-134489D01*
X992186Y-133614D01*
X993278Y-132448D01*
G01X1005319Y-135072D02*
Y-127197D01*
X1000952Y-117572D01*
G01X1009686D02*
X1005319Y-127197D01*
G01X895516Y-90072D02*
Y-72572D01*
X899882D01*
X901629Y-73447D01*
X902939Y-74614D01*
X904031Y-76363D01*
X904904Y-78406D01*
X905122Y-81322D01*
X904904Y-84239D01*
X904031Y-86281D01*
X902939Y-88031D01*
X901629Y-89197D01*
X899882Y-90072D01*
X895516D01*
G01X914544Y-82197D02*
X921531D01*
X920876Y-80155D01*
X919784Y-78989D01*
X918256Y-78406D01*
X916727Y-78697D01*
X915417Y-79572D01*
X914544Y-81614D01*
X914107Y-83364D01*
Y-85114D01*
X914544Y-86864D01*
X915636Y-88614D01*
X916946Y-89780D01*
X918474Y-90072D01*
X920002Y-89489D01*
X921531Y-87739D01*
G01X932044Y-88031D02*
X933136Y-89197D01*
X934664Y-90072D01*
X935974D01*
X937284Y-89489D01*
X938157Y-88614D01*
X938594Y-87448D01*
X938376Y-85697D01*
X937502Y-84822D01*
X933572Y-83072D01*
X932699Y-81030D01*
X933136Y-79572D01*
X934009Y-78697D01*
X935319Y-78406D01*
X936629Y-78697D01*
X937939Y-79572D01*
G01X952819Y-78406D02*
Y-90072D01*
G01Y-73739D02*
X952382Y-73447D01*
Y-72864D01*
X952819Y-72572D01*
X953256Y-72864D01*
Y-73447D01*
X952819Y-73739D01*
G01X967262Y-94447D02*
X968791Y-95614D01*
X970537Y-95905D01*
X972065Y-95614D01*
X973376Y-94156D01*
X974249Y-92114D01*
Y-78406D01*
G01Y-80739D02*
X973376Y-79572D01*
X972065Y-78697D01*
X970537Y-78406D01*
X968791Y-78989D01*
X967699Y-80155D01*
X966825Y-82197D01*
X966389Y-84239D01*
X966607Y-85989D01*
X967481Y-88031D01*
X968791Y-89489D01*
X970537Y-90072D01*
X971847Y-89780D01*
X973376Y-88614D01*
X974249Y-87448D01*
G01X984107Y-90072D02*
Y-78406D01*
G01Y-81322D02*
X984981Y-79864D01*
X986291Y-78697D01*
X988037Y-78406D01*
X989565Y-78697D01*
X990876Y-79864D01*
X991531Y-81905D01*
Y-90072D01*
G01X1002044Y-82197D02*
X1009031D01*
X1008376Y-80155D01*
X1007284Y-78989D01*
X1005756Y-78406D01*
X1004227Y-78697D01*
X1002917Y-79572D01*
X1002044Y-81614D01*
X1001607Y-83364D01*
Y-85114D01*
X1002044Y-86864D01*
X1003136Y-88614D01*
X1004446Y-89780D01*
X1005974Y-90072D01*
X1007502Y-89489D01*
X1009031Y-87739D01*
G01X1019762Y-90072D02*
Y-78406D01*
G01Y-80739D02*
X1020854Y-79572D01*
X1021946Y-78697D01*
X1023474Y-78406D01*
X1024565Y-78697D01*
X1025876Y-79572D01*
G01X1066519Y-117572D02*
X1064772Y-118155D01*
X1063462Y-119614D01*
X1062589Y-121363D01*
X1061934Y-123697D01*
X1061716Y-126322D01*
X1061934Y-128947D01*
X1062589Y-131281D01*
X1063462Y-133031D01*
X1064772Y-134489D01*
X1066519Y-135072D01*
X1068265Y-134489D01*
X1069576Y-133031D01*
X1070449Y-131281D01*
X1071104Y-128947D01*
X1071322Y-126322D01*
X1071104Y-123697D01*
X1070449Y-121363D01*
X1069576Y-119614D01*
X1068265Y-118155D01*
X1066519Y-117572D01*
G01X1084019Y-135072D02*
X1085547Y-134780D01*
X1087294Y-133906D01*
X1088386Y-132448D01*
X1088822Y-130405D01*
X1088386Y-128364D01*
X1087076Y-126614D01*
X1085111Y-125739D01*
X1082927D01*
X1081617Y-125155D01*
X1080525Y-123697D01*
X1080089Y-121656D01*
X1080744Y-119614D01*
X1082272Y-118155D01*
X1084019Y-117572D01*
X1085765Y-118155D01*
X1087294Y-119614D01*
X1087949Y-121656D01*
X1087512Y-123697D01*
X1086421Y-125155D01*
X1085111Y-125739D01*
X1082927D01*
X1080962Y-126614D01*
X1079652Y-128364D01*
X1079216Y-130405D01*
X1079652Y-132448D01*
X1080744Y-133906D01*
X1082491Y-134780D01*
X1084019Y-135072D01*
G01X1097589Y-135655D02*
X1105449Y-117572D01*
G01X1119019D02*
X1117272Y-118155D01*
X1115962Y-119614D01*
X1115089Y-121363D01*
X1114434Y-123697D01*
X1114216Y-126322D01*
X1114434Y-128947D01*
X1115089Y-131281D01*
X1115962Y-133031D01*
X1117272Y-134489D01*
X1119019Y-135072D01*
X1120765Y-134489D01*
X1122076Y-133031D01*
X1122949Y-131281D01*
X1123604Y-128947D01*
X1123822Y-126322D01*
X1123604Y-123697D01*
X1122949Y-121363D01*
X1122076Y-119614D01*
X1120765Y-118155D01*
X1119019Y-117572D01*
G01X1136082Y-135072D02*
X1136519Y-131281D01*
X1137174Y-128072D01*
X1138047Y-125155D01*
X1139139Y-121947D01*
X1140886Y-117572D01*
X1132152D01*
G01X1150089Y-135655D02*
X1157949Y-117572D01*
G01X1167371Y-120489D02*
X1168681Y-118739D01*
X1170209Y-117864D01*
X1171956Y-117572D01*
X1174139Y-118155D01*
X1175667Y-119614D01*
X1176104Y-121363D01*
X1175886Y-123114D01*
X1175012Y-124572D01*
X1170646Y-127489D01*
X1168681Y-129530D01*
X1167371Y-132448D01*
X1166934Y-135072D01*
X1176104D01*
G01X1189019Y-117572D02*
X1187272Y-118155D01*
X1185962Y-119614D01*
X1185089Y-121363D01*
X1184434Y-123697D01*
X1184216Y-126322D01*
X1184434Y-128947D01*
X1185089Y-131281D01*
X1185962Y-133031D01*
X1187272Y-134489D01*
X1189019Y-135072D01*
X1190765Y-134489D01*
X1192076Y-133031D01*
X1192949Y-131281D01*
X1193604Y-128947D01*
X1193822Y-126322D01*
X1193604Y-123697D01*
X1192949Y-121363D01*
X1192076Y-119614D01*
X1190765Y-118155D01*
X1189019Y-117572D01*
G01X1206519Y-135072D02*
Y-117572D01*
X1203899Y-121072D01*
G01Y-135072D02*
X1209139D01*
G01X1223582D02*
X1224019Y-131281D01*
X1224674Y-128072D01*
X1225547Y-125155D01*
X1226639Y-121947D01*
X1228386Y-117572D01*
X1219652D01*
G01X1114216Y-90072D02*
Y-72572D01*
X1118582D01*
X1120329Y-73447D01*
X1121639Y-74614D01*
X1122731Y-76363D01*
X1123604Y-78406D01*
X1123822Y-81322D01*
X1123604Y-84239D01*
X1122731Y-86281D01*
X1121639Y-88031D01*
X1120329Y-89197D01*
X1118582Y-90072D01*
X1114216D01*
G01X1140449D02*
Y-78406D01*
G01Y-80447D02*
X1139576Y-79281D01*
X1138265Y-78697D01*
X1136737Y-78406D01*
X1135209Y-78989D01*
X1133899Y-80155D01*
X1133025Y-81905D01*
X1132589Y-84239D01*
X1133025Y-86572D01*
X1133899Y-88322D01*
X1135209Y-89489D01*
X1136737Y-90072D01*
X1138265Y-89780D01*
X1139576Y-88906D01*
X1140449Y-87739D01*
G01X1154019Y-72572D02*
Y-90072D01*
G01X1150962Y-78406D02*
X1157076D01*
G01X1168244Y-82197D02*
X1175231D01*
X1174576Y-80155D01*
X1173484Y-78989D01*
X1171956Y-78406D01*
X1170427Y-78697D01*
X1169117Y-79572D01*
X1168244Y-81614D01*
X1167807Y-83364D01*
Y-85114D01*
X1168244Y-86864D01*
X1169336Y-88614D01*
X1170646Y-89780D01*
X1172174Y-90072D01*
X1173702Y-89489D01*
X1175231Y-87739D01*
G01X21458Y526295D02*
Y528795D01*
X20417D01*
X20083Y528670D01*
X19875Y528503D01*
X19792Y528170D01*
X19875Y527837D01*
X20125Y527628D01*
X20417Y527503D01*
X21458D01*
G01X20417D02*
X19792Y526295D01*
G01X18317Y528378D02*
X18067Y528628D01*
X17775Y528753D01*
X17442Y528795D01*
X17025Y528712D01*
X16733Y528503D01*
X16650Y528253D01*
X16692Y528003D01*
X16858Y527795D01*
X17692Y527378D01*
X18067Y527087D01*
X18317Y526670D01*
X18400Y526295D01*
X16650D01*
G01X13925D02*
Y528795D01*
X15467Y527003D01*
X13383D01*
G01X12117Y528378D02*
X11867Y528628D01*
X11575Y528753D01*
X11242Y528795D01*
X10825Y528712D01*
X10533Y528503D01*
X10450Y528253D01*
X10492Y528003D01*
X10658Y527795D01*
X11492Y527378D01*
X11867Y527087D01*
X12117Y526670D01*
X12200Y526295D01*
X10450D01*
G01X21415Y520571D02*
Y523071D01*
X20374D01*
X20040Y522946D01*
X19832Y522779D01*
X19749Y522446D01*
X19832Y522113D01*
X20082Y521904D01*
X20374Y521779D01*
X21415D01*
G01X20374D02*
X19749Y520571D01*
G01X18274Y522654D02*
X18024Y522904D01*
X17732Y523029D01*
X17399Y523071D01*
X16982Y522988D01*
X16690Y522779D01*
X16607Y522529D01*
X16649Y522279D01*
X16815Y522071D01*
X17649Y521654D01*
X18024Y521363D01*
X18274Y520946D01*
X18357Y520571D01*
X16607D01*
G01X15299Y521071D02*
X15049Y520779D01*
X14715Y520613D01*
X14340Y520571D01*
X14007Y520613D01*
X13674Y520821D01*
X13465Y521071D01*
X13424Y521321D01*
X13507Y521613D01*
X13799Y521821D01*
X14090Y521904D01*
X14465D01*
G01X14090D02*
X13840Y522029D01*
X13632Y522238D01*
X13549Y522488D01*
X13632Y522738D01*
X13840Y522946D01*
X14215Y523071D01*
X14590Y523029D01*
X14965Y522863D01*
G01X11365Y520571D02*
X11282Y521113D01*
X11157Y521571D01*
X10990Y521988D01*
X10782Y522446D01*
X10449Y523071D01*
X12115D01*
G01X21448Y531938D02*
Y534438D01*
X20407D01*
X20073Y534313D01*
X19865Y534146D01*
X19782Y533813D01*
X19865Y533480D01*
X20115Y533271D01*
X20407Y533146D01*
X21448D01*
G01X20407D02*
X19782Y531938D01*
G01X18307Y534021D02*
X18057Y534271D01*
X17765Y534396D01*
X17432Y534438D01*
X17015Y534355D01*
X16723Y534146D01*
X16640Y533896D01*
X16682Y533646D01*
X16848Y533438D01*
X17682Y533021D01*
X18057Y532730D01*
X18307Y532313D01*
X18390Y531938D01*
X16640D01*
G01X15332Y532313D02*
X15082Y532105D01*
X14790Y531980D01*
X14415Y531938D01*
X14040Y532021D01*
X13748Y532188D01*
X13540Y532480D01*
X13498Y532813D01*
X13582Y533146D01*
X13790Y533355D01*
X14082Y533521D01*
X14373Y533563D01*
X14665Y533521D01*
X15040Y533355D01*
X14915Y534438D01*
X13790D01*
G01X12107Y532980D02*
X11815Y533271D01*
X11565Y533438D01*
X11232Y533521D01*
X10940Y533438D01*
X10732Y533271D01*
X10565Y533021D01*
X10523Y532730D01*
X10565Y532480D01*
X10732Y532230D01*
X10982Y532021D01*
X11273Y531938D01*
X11607Y532021D01*
X11898Y532271D01*
X12065Y532646D01*
X12107Y533063D01*
X12023Y533605D01*
X11898Y533896D01*
X11690Y534188D01*
X11398Y534396D01*
X11107Y534438D01*
X10815Y534355D01*
X10607Y534146D01*
G01X21468Y554453D02*
Y556953D01*
X20427D01*
X20093Y556828D01*
X19885Y556661D01*
X19802Y556328D01*
X19885Y555995D01*
X20135Y555786D01*
X20427Y555661D01*
X21468D01*
G01X20427D02*
X19802Y554453D01*
G01X18327Y556536D02*
X18077Y556786D01*
X17785Y556911D01*
X17452Y556953D01*
X17035Y556870D01*
X16743Y556661D01*
X16660Y556411D01*
X16702Y556161D01*
X16868Y555953D01*
X17702Y555536D01*
X18077Y555245D01*
X18327Y554828D01*
X18410Y554453D01*
X16660D01*
G01X15352Y554828D02*
X15102Y554620D01*
X14810Y554495D01*
X14435Y554453D01*
X14060Y554536D01*
X13768Y554703D01*
X13560Y554995D01*
X13518Y555328D01*
X13602Y555661D01*
X13810Y555870D01*
X14102Y556036D01*
X14393Y556078D01*
X14685Y556036D01*
X15060Y555870D01*
X14935Y556953D01*
X13810D01*
G01X10835Y554453D02*
Y556953D01*
X12377Y555161D01*
X10293D01*
G01X21341Y537554D02*
Y540054D01*
X20300D01*
X19966Y539929D01*
X19758Y539762D01*
X19675Y539429D01*
X19758Y539096D01*
X20008Y538887D01*
X20300Y538762D01*
X21341D01*
G01X20300D02*
X19675Y537554D01*
G01X18200Y539637D02*
X17950Y539887D01*
X17658Y540012D01*
X17325Y540054D01*
X16908Y539971D01*
X16616Y539762D01*
X16533Y539512D01*
X16575Y539262D01*
X16741Y539054D01*
X17575Y538637D01*
X17950Y538346D01*
X18200Y537929D01*
X18283Y537554D01*
X16533D01*
G01X15225Y537929D02*
X14975Y537721D01*
X14683Y537596D01*
X14308Y537554D01*
X13933Y537637D01*
X13641Y537804D01*
X13433Y538096D01*
X13391Y538429D01*
X13475Y538762D01*
X13683Y538971D01*
X13975Y539137D01*
X14266Y539179D01*
X14558Y539137D01*
X14933Y538971D01*
X14808Y540054D01*
X13683D01*
G01X11208D02*
X11541Y539971D01*
X11791Y539762D01*
X11958Y539512D01*
X12083Y539179D01*
X12125Y538804D01*
X12083Y538429D01*
X11958Y538096D01*
X11791Y537846D01*
X11541Y537637D01*
X11208Y537554D01*
X10875Y537637D01*
X10625Y537846D01*
X10458Y538096D01*
X10333Y538429D01*
X10291Y538804D01*
X10333Y539179D01*
X10458Y539512D01*
X10625Y539762D01*
X10875Y539971D01*
X11208Y540054D01*
G01X21441Y543181D02*
Y545681D01*
X20400D01*
X20066Y545556D01*
X19858Y545389D01*
X19775Y545056D01*
X19858Y544723D01*
X20108Y544514D01*
X20400Y544389D01*
X21441D01*
G01X20400D02*
X19775Y543181D01*
G01X18300Y545264D02*
X18050Y545514D01*
X17758Y545639D01*
X17425Y545681D01*
X17008Y545598D01*
X16716Y545389D01*
X16633Y545139D01*
X16675Y544889D01*
X16841Y544681D01*
X17675Y544264D01*
X18050Y543973D01*
X18300Y543556D01*
X18383Y543181D01*
X16633D01*
G01X13908D02*
Y545681D01*
X15450Y543889D01*
X13366D01*
G01X12100Y544223D02*
X11808Y544514D01*
X11558Y544681D01*
X11225Y544764D01*
X10933Y544681D01*
X10725Y544514D01*
X10558Y544264D01*
X10516Y543973D01*
X10558Y543723D01*
X10725Y543473D01*
X10975Y543264D01*
X11266Y543181D01*
X11600Y543264D01*
X11891Y543514D01*
X12058Y543889D01*
X12100Y544306D01*
X12016Y544848D01*
X11891Y545139D01*
X11683Y545431D01*
X11391Y545639D01*
X11100Y545681D01*
X10808Y545598D01*
X10600Y545389D01*
G01X21486Y548808D02*
Y551308D01*
X20445D01*
X20111Y551183D01*
X19903Y551016D01*
X19820Y550683D01*
X19903Y550350D01*
X20153Y550141D01*
X20445Y550016D01*
X21486D01*
G01X20445D02*
X19820Y548808D01*
G01X18345Y550891D02*
X18095Y551141D01*
X17803Y551266D01*
X17470Y551308D01*
X17053Y551225D01*
X16761Y551016D01*
X16678Y550766D01*
X16720Y550516D01*
X16886Y550308D01*
X17720Y549891D01*
X18095Y549600D01*
X18345Y549183D01*
X18428Y548808D01*
X16678D01*
G01X15370Y549308D02*
X15120Y549016D01*
X14786Y548850D01*
X14411Y548808D01*
X14078Y548850D01*
X13745Y549058D01*
X13536Y549308D01*
X13495Y549558D01*
X13578Y549850D01*
X13870Y550058D01*
X14161Y550141D01*
X14536D01*
G01X14161D02*
X13911Y550266D01*
X13703Y550475D01*
X13620Y550725D01*
X13703Y550975D01*
X13911Y551183D01*
X14286Y551308D01*
X14661Y551266D01*
X15036Y551100D01*
G01X12270Y549308D02*
X12020Y549016D01*
X11686Y548850D01*
X11311Y548808D01*
X10978Y548850D01*
X10645Y549058D01*
X10436Y549308D01*
X10395Y549558D01*
X10478Y549850D01*
X10770Y550058D01*
X11061Y550141D01*
X11436D01*
G01X11061D02*
X10811Y550266D01*
X10603Y550475D01*
X10520Y550725D01*
X10603Y550975D01*
X10811Y551183D01*
X11186Y551308D01*
X11561Y551266D01*
X11936Y551100D01*
G01X21383Y560200D02*
Y562700D01*
X20342D01*
X20008Y562575D01*
X19800Y562408D01*
X19717Y562075D01*
X19800Y561742D01*
X20050Y561533D01*
X20342Y561408D01*
X21383D01*
G01X20342D02*
X19717Y560200D01*
G01X18242Y562283D02*
X17992Y562533D01*
X17700Y562658D01*
X17367Y562700D01*
X16950Y562617D01*
X16658Y562408D01*
X16575Y562158D01*
X16617Y561908D01*
X16783Y561700D01*
X17617Y561283D01*
X17992Y560992D01*
X18242Y560575D01*
X18325Y560200D01*
X16575D01*
G01X14350D02*
Y562700D01*
X14850Y562200D01*
G01Y560200D02*
X13850D01*
G01X11250D02*
Y562700D01*
X11750Y562200D01*
G01Y560200D02*
X10750D01*
G01X57517Y494467D02*
X60017D01*
Y495508D01*
X59892Y495842D01*
X59725Y496050D01*
X59392Y496133D01*
X59059Y496050D01*
X58850Y495800D01*
X58725Y495508D01*
Y494467D01*
G01Y495508D02*
X57517Y496133D01*
G01X59600Y497608D02*
X59850Y497858D01*
X59975Y498150D01*
X60017Y498483D01*
X59934Y498900D01*
X59725Y499192D01*
X59475Y499275D01*
X59225Y499233D01*
X59017Y499067D01*
X58600Y498233D01*
X58309Y497858D01*
X57892Y497608D01*
X57517Y497525D01*
Y499275D01*
G01Y502000D02*
X60017D01*
X58225Y500458D01*
Y502542D01*
G01X57517Y505100D02*
X60017D01*
X58225Y503558D01*
Y505642D01*
G01X53666Y507517D02*
X56166D01*
Y508558D01*
X56041Y508892D01*
X55874Y509100D01*
X55541Y509183D01*
X55208Y509100D01*
X54999Y508850D01*
X54874Y508558D01*
Y507517D01*
G01Y508558D02*
X53666Y509183D01*
G01X55749Y510658D02*
X55999Y510908D01*
X56124Y511200D01*
X56166Y511533D01*
X56083Y511950D01*
X55874Y512242D01*
X55624Y512325D01*
X55374Y512283D01*
X55166Y512117D01*
X54749Y511283D01*
X54458Y510908D01*
X54041Y510658D01*
X53666Y510575D01*
Y512325D01*
G01Y515050D02*
X56166D01*
X54374Y513508D01*
Y515592D01*
G01X53958Y516942D02*
X53749Y517233D01*
X53666Y517567D01*
X53749Y517900D01*
X53999Y518192D01*
X54374Y518400D01*
X54749Y518483D01*
X55208D01*
X55583Y518400D01*
X55916Y518192D01*
X56083Y517942D01*
X56166Y517650D01*
X56083Y517317D01*
X55916Y517067D01*
X55666Y516900D01*
X55333Y516817D01*
X55041Y516900D01*
X54749Y517108D01*
X54583Y517358D01*
X54541Y517650D01*
X54624Y517983D01*
X54833Y518233D01*
X55208Y518483D01*
G01X44666Y507017D02*
X47166D01*
Y508058D01*
X47041Y508392D01*
X46874Y508600D01*
X46541Y508683D01*
X46208Y508600D01*
X45999Y508350D01*
X45874Y508058D01*
Y507017D01*
G01Y508058D02*
X44666Y508683D01*
G01X46749Y510158D02*
X46999Y510408D01*
X47124Y510700D01*
X47166Y511033D01*
X47083Y511450D01*
X46874Y511742D01*
X46624Y511825D01*
X46374Y511783D01*
X46166Y511617D01*
X45749Y510783D01*
X45458Y510408D01*
X45041Y510158D01*
X44666Y510075D01*
Y511825D01*
G01X45041Y513133D02*
X44833Y513383D01*
X44708Y513675D01*
X44666Y514050D01*
X44749Y514425D01*
X44916Y514717D01*
X45208Y514925D01*
X45541Y514967D01*
X45874Y514883D01*
X46083Y514675D01*
X46249Y514383D01*
X46291Y514092D01*
X46249Y513800D01*
X46083Y513425D01*
X47166Y513550D01*
Y514675D01*
G01X45166Y516233D02*
X44874Y516483D01*
X44708Y516817D01*
X44666Y517192D01*
X44708Y517525D01*
X44916Y517858D01*
X45166Y518067D01*
X45416Y518108D01*
X45708Y518025D01*
X45916Y517733D01*
X45999Y517442D01*
Y517067D01*
G01Y517442D02*
X46124Y517692D01*
X46333Y517900D01*
X46583Y517983D01*
X46833Y517900D01*
X47041Y517692D01*
X47166Y517317D01*
X47124Y516942D01*
X46958Y516567D01*
G01X40517Y493967D02*
X43017D01*
Y495008D01*
X42892Y495342D01*
X42725Y495550D01*
X42392Y495633D01*
X42059Y495550D01*
X41850Y495300D01*
X41725Y495008D01*
Y493967D01*
G01Y495008D02*
X40517Y495633D01*
G01X42600Y497108D02*
X42850Y497358D01*
X42975Y497650D01*
X43017Y497983D01*
X42934Y498400D01*
X42725Y498692D01*
X42475Y498775D01*
X42225Y498733D01*
X42017Y498567D01*
X41600Y497733D01*
X41309Y497358D01*
X40892Y497108D01*
X40517Y497025D01*
Y498775D01*
G01X41017Y500083D02*
X40725Y500333D01*
X40559Y500667D01*
X40517Y501042D01*
X40559Y501375D01*
X40767Y501708D01*
X41017Y501917D01*
X41267Y501958D01*
X41559Y501875D01*
X41767Y501583D01*
X41850Y501292D01*
Y500917D01*
G01Y501292D02*
X41975Y501542D01*
X42184Y501750D01*
X42434Y501833D01*
X42684Y501750D01*
X42892Y501542D01*
X43017Y501167D01*
X42975Y500792D01*
X42809Y500417D01*
G01X40892Y503183D02*
X40684Y503433D01*
X40559Y503725D01*
X40517Y504100D01*
X40600Y504475D01*
X40767Y504767D01*
X41059Y504975D01*
X41392Y505017D01*
X41725Y504933D01*
X41934Y504725D01*
X42100Y504433D01*
X42142Y504142D01*
X42100Y503850D01*
X41934Y503475D01*
X43017Y503600D01*
Y504725D01*
G01X77373Y504479D02*
X73373D01*
Y511879D01*
G01X39666Y507017D02*
X42166D01*
Y508058D01*
X42041Y508392D01*
X41874Y508600D01*
X41541Y508683D01*
X41208Y508600D01*
X40999Y508350D01*
X40874Y508058D01*
Y507017D01*
G01Y508058D02*
X39666Y508683D01*
G01X41749Y510158D02*
X41999Y510408D01*
X42124Y510700D01*
X42166Y511033D01*
X42083Y511450D01*
X41874Y511742D01*
X41624Y511825D01*
X41374Y511783D01*
X41166Y511617D01*
X40749Y510783D01*
X40458Y510408D01*
X40041Y510158D01*
X39666Y510075D01*
Y511825D01*
G01X40166Y513133D02*
X39874Y513383D01*
X39708Y513717D01*
X39666Y514092D01*
X39708Y514425D01*
X39916Y514758D01*
X40166Y514967D01*
X40416Y515008D01*
X40708Y514925D01*
X40916Y514633D01*
X40999Y514342D01*
Y513967D01*
G01Y514342D02*
X41124Y514592D01*
X41333Y514800D01*
X41583Y514883D01*
X41833Y514800D01*
X42041Y514592D01*
X42166Y514217D01*
X42124Y513842D01*
X41958Y513467D01*
G01X40708Y516358D02*
X40999Y516650D01*
X41166Y516900D01*
X41249Y517233D01*
X41166Y517525D01*
X40999Y517733D01*
X40749Y517900D01*
X40458Y517942D01*
X40208Y517900D01*
X39958Y517733D01*
X39749Y517483D01*
X39666Y517192D01*
X39749Y516858D01*
X39999Y516567D01*
X40374Y516400D01*
X40791Y516358D01*
X41333Y516442D01*
X41624Y516567D01*
X41916Y516775D01*
X42124Y517067D01*
X42166Y517358D01*
X42083Y517650D01*
X41874Y517858D01*
G01X77405Y512077D02*
X73405D01*
Y519477D01*
G01X36017Y493967D02*
X38517D01*
Y495008D01*
X38392Y495342D01*
X38225Y495550D01*
X37892Y495633D01*
X37559Y495550D01*
X37350Y495300D01*
X37225Y495008D01*
Y493967D01*
G01Y495008D02*
X36017Y495633D01*
G01X38100Y497108D02*
X38350Y497358D01*
X38475Y497650D01*
X38517Y497983D01*
X38434Y498400D01*
X38225Y498692D01*
X37975Y498775D01*
X37725Y498733D01*
X37517Y498567D01*
X37100Y497733D01*
X36809Y497358D01*
X36392Y497108D01*
X36017Y497025D01*
Y498775D01*
G01Y501500D02*
X38517D01*
X36725Y499958D01*
Y502042D01*
G01X38517Y504100D02*
X38434Y503767D01*
X38225Y503517D01*
X37975Y503350D01*
X37642Y503225D01*
X37267Y503183D01*
X36892Y503225D01*
X36559Y503350D01*
X36309Y503517D01*
X36100Y503767D01*
X36017Y504100D01*
X36100Y504433D01*
X36309Y504683D01*
X36559Y504850D01*
X36892Y504975D01*
X37267Y505017D01*
X37642Y504975D01*
X37975Y504850D01*
X38225Y504683D01*
X38434Y504433D01*
X38517Y504100D01*
G01X71878Y504377D02*
X67878D01*
Y511777D01*
G01X35667Y507017D02*
X38167D01*
Y508058D01*
X38042Y508392D01*
X37875Y508600D01*
X37542Y508683D01*
X37209Y508600D01*
X37000Y508350D01*
X36875Y508058D01*
Y507017D01*
G01Y508058D02*
X35667Y508683D01*
G01X37750Y510158D02*
X38000Y510408D01*
X38125Y510700D01*
X38167Y511033D01*
X38084Y511450D01*
X37875Y511742D01*
X37625Y511825D01*
X37375Y511783D01*
X37167Y511617D01*
X36750Y510783D01*
X36459Y510408D01*
X36042Y510158D01*
X35667Y510075D01*
Y511825D01*
G01Y514550D02*
X38167D01*
X36375Y513008D01*
Y515092D01*
G01X35667Y517150D02*
X38167D01*
X37667Y516650D01*
G01X35667D02*
Y517650D01*
G01X71778Y512077D02*
X67778D01*
Y519477D01*
G01X57666Y507517D02*
X60166D01*
Y508558D01*
X60041Y508892D01*
X59874Y509100D01*
X59541Y509183D01*
X59208Y509100D01*
X58999Y508850D01*
X58874Y508558D01*
Y507517D01*
G01Y508558D02*
X57666Y509183D01*
G01X59749Y510658D02*
X59999Y510908D01*
X60124Y511200D01*
X60166Y511533D01*
X60083Y511950D01*
X59874Y512242D01*
X59624Y512325D01*
X59374Y512283D01*
X59166Y512117D01*
X58749Y511283D01*
X58458Y510908D01*
X58041Y510658D01*
X57666Y510575D01*
Y512325D01*
G01Y515050D02*
X60166D01*
X58374Y513508D01*
Y515592D01*
G01X58041Y516733D02*
X57833Y516983D01*
X57708Y517275D01*
X57666Y517650D01*
X57749Y518025D01*
X57916Y518317D01*
X58208Y518525D01*
X58541Y518567D01*
X58874Y518483D01*
X59083Y518275D01*
X59249Y517983D01*
X59291Y517692D01*
X59249Y517400D01*
X59083Y517025D01*
X60166Y517150D01*
Y518275D01*
G01X53017Y493967D02*
X55517D01*
Y495008D01*
X55392Y495342D01*
X55225Y495550D01*
X54892Y495633D01*
X54559Y495550D01*
X54350Y495300D01*
X54225Y495008D01*
Y493967D01*
G01Y495008D02*
X53017Y495633D01*
G01X55100Y497108D02*
X55350Y497358D01*
X55475Y497650D01*
X55517Y497983D01*
X55434Y498400D01*
X55225Y498692D01*
X54975Y498775D01*
X54725Y498733D01*
X54517Y498567D01*
X54100Y497733D01*
X53809Y497358D01*
X53392Y497108D01*
X53017Y497025D01*
Y498775D01*
G01Y501500D02*
X55517D01*
X53725Y499958D01*
Y502042D01*
G01X53017Y504100D02*
X53059Y504392D01*
X53184Y504725D01*
X53392Y504933D01*
X53684Y505017D01*
X53975Y504933D01*
X54225Y504683D01*
X54350Y504308D01*
Y503892D01*
X54434Y503642D01*
X54642Y503433D01*
X54934Y503350D01*
X55225Y503475D01*
X55434Y503767D01*
X55517Y504100D01*
X55434Y504433D01*
X55225Y504725D01*
X54934Y504850D01*
X54642Y504767D01*
X54434Y504558D01*
X54350Y504308D01*
Y503892D01*
X54225Y503517D01*
X53975Y503267D01*
X53684Y503183D01*
X53392Y503267D01*
X53184Y503475D01*
X53059Y503808D01*
X53017Y504100D01*
G01X45017Y493967D02*
X47517D01*
Y495008D01*
X47392Y495342D01*
X47225Y495550D01*
X46892Y495633D01*
X46559Y495550D01*
X46350Y495300D01*
X46225Y495008D01*
Y493967D01*
G01Y495008D02*
X45017Y495633D01*
G01X47100Y497108D02*
X47350Y497358D01*
X47475Y497650D01*
X47517Y497983D01*
X47434Y498400D01*
X47225Y498692D01*
X46975Y498775D01*
X46725Y498733D01*
X46517Y498567D01*
X46100Y497733D01*
X45809Y497358D01*
X45392Y497108D01*
X45017Y497025D01*
Y498775D01*
G01X45392Y500083D02*
X45184Y500333D01*
X45059Y500625D01*
X45017Y501000D01*
X45100Y501375D01*
X45267Y501667D01*
X45559Y501875D01*
X45892Y501917D01*
X46225Y501833D01*
X46434Y501625D01*
X46600Y501333D01*
X46642Y501042D01*
X46600Y500750D01*
X46434Y500375D01*
X47517Y500500D01*
Y501625D01*
G01X47100Y503308D02*
X47350Y503558D01*
X47475Y503850D01*
X47517Y504183D01*
X47434Y504600D01*
X47225Y504892D01*
X46975Y504975D01*
X46725Y504933D01*
X46517Y504767D01*
X46100Y503933D01*
X45809Y503558D01*
X45392Y503308D01*
X45017Y503225D01*
Y504975D01*
G01X31517Y493967D02*
X34017D01*
Y495008D01*
X33892Y495342D01*
X33725Y495550D01*
X33392Y495633D01*
X33059Y495550D01*
X32850Y495300D01*
X32725Y495008D01*
Y493967D01*
G01Y495008D02*
X31517Y495633D01*
G01X33600Y497108D02*
X33850Y497358D01*
X33975Y497650D01*
X34017Y497983D01*
X33934Y498400D01*
X33725Y498692D01*
X33475Y498775D01*
X33225Y498733D01*
X33017Y498567D01*
X32600Y497733D01*
X32309Y497358D01*
X31892Y497108D01*
X31517Y497025D01*
Y498775D01*
G01X31892Y500083D02*
X31684Y500333D01*
X31559Y500625D01*
X31517Y501000D01*
X31600Y501375D01*
X31767Y501667D01*
X32059Y501875D01*
X32392Y501917D01*
X32725Y501833D01*
X32934Y501625D01*
X33100Y501333D01*
X33142Y501042D01*
X33100Y500750D01*
X32934Y500375D01*
X34017Y500500D01*
Y501625D01*
G01X31517Y504100D02*
X31559Y504392D01*
X31684Y504725D01*
X31892Y504933D01*
X32184Y505017D01*
X32475Y504933D01*
X32725Y504683D01*
X32850Y504308D01*
Y503892D01*
X32934Y503642D01*
X33142Y503433D01*
X33434Y503350D01*
X33725Y503475D01*
X33934Y503767D01*
X34017Y504100D01*
X33934Y504433D01*
X33725Y504725D01*
X33434Y504850D01*
X33142Y504767D01*
X32934Y504558D01*
X32850Y504308D01*
Y503892D01*
X32725Y503517D01*
X32475Y503267D01*
X32184Y503183D01*
X31892Y503267D01*
X31684Y503475D01*
X31559Y503808D01*
X31517Y504100D01*
G01X66251Y504477D02*
X62251D01*
Y511877D01*
G01X31167Y507017D02*
X33667D01*
Y508058D01*
X33542Y508392D01*
X33375Y508600D01*
X33042Y508683D01*
X32709Y508600D01*
X32500Y508350D01*
X32375Y508058D01*
Y507017D01*
G01Y508058D02*
X31167Y508683D01*
G01X33250Y510158D02*
X33500Y510408D01*
X33625Y510700D01*
X33667Y511033D01*
X33584Y511450D01*
X33375Y511742D01*
X33125Y511825D01*
X32875Y511783D01*
X32667Y511617D01*
X32250Y510783D01*
X31959Y510408D01*
X31542Y510158D01*
X31167Y510075D01*
Y511825D01*
G01X31542Y513133D02*
X31334Y513383D01*
X31209Y513675D01*
X31167Y514050D01*
X31250Y514425D01*
X31417Y514717D01*
X31709Y514925D01*
X32042Y514967D01*
X32375Y514883D01*
X32584Y514675D01*
X32750Y514383D01*
X32792Y514092D01*
X32750Y513800D01*
X32584Y513425D01*
X33667Y513550D01*
Y514675D01*
G01X31459Y516442D02*
X31250Y516733D01*
X31167Y517067D01*
X31250Y517400D01*
X31500Y517692D01*
X31875Y517900D01*
X32250Y517983D01*
X32709D01*
X33084Y517900D01*
X33417Y517692D01*
X33584Y517442D01*
X33667Y517150D01*
X33584Y516817D01*
X33417Y516567D01*
X33167Y516400D01*
X32834Y516317D01*
X32542Y516400D01*
X32250Y516608D01*
X32084Y516858D01*
X32042Y517150D01*
X32125Y517483D01*
X32334Y517733D01*
X32709Y517983D01*
G01X66151Y512077D02*
X62151D01*
Y519477D01*
G01X49017Y493967D02*
X51517D01*
Y495008D01*
X51392Y495342D01*
X51225Y495550D01*
X50892Y495633D01*
X50559Y495550D01*
X50350Y495300D01*
X50225Y495008D01*
Y493967D01*
G01Y495008D02*
X49017Y495633D01*
G01X51100Y497108D02*
X51350Y497358D01*
X51475Y497650D01*
X51517Y497983D01*
X51434Y498400D01*
X51225Y498692D01*
X50975Y498775D01*
X50725Y498733D01*
X50517Y498567D01*
X50100Y497733D01*
X49809Y497358D01*
X49392Y497108D01*
X49017Y497025D01*
Y498775D01*
G01X50059Y500208D02*
X50350Y500500D01*
X50517Y500750D01*
X50600Y501083D01*
X50517Y501375D01*
X50350Y501583D01*
X50100Y501750D01*
X49809Y501792D01*
X49559Y501750D01*
X49309Y501583D01*
X49100Y501333D01*
X49017Y501042D01*
X49100Y500708D01*
X49350Y500417D01*
X49725Y500250D01*
X50142Y500208D01*
X50684Y500292D01*
X50975Y500417D01*
X51267Y500625D01*
X51475Y500917D01*
X51517Y501208D01*
X51434Y501500D01*
X51225Y501708D01*
G01X51517Y504100D02*
X51434Y503767D01*
X51225Y503517D01*
X50975Y503350D01*
X50642Y503225D01*
X50267Y503183D01*
X49892Y503225D01*
X49559Y503350D01*
X49309Y503517D01*
X49100Y503767D01*
X49017Y504100D01*
X49100Y504433D01*
X49309Y504683D01*
X49559Y504850D01*
X49892Y504975D01*
X50267Y505017D01*
X50642Y504975D01*
X50975Y504850D01*
X51225Y504683D01*
X51434Y504433D01*
X51517Y504100D01*
G01X49166Y507517D02*
X51666D01*
Y508558D01*
X51541Y508892D01*
X51374Y509100D01*
X51041Y509183D01*
X50708Y509100D01*
X50499Y508850D01*
X50374Y508558D01*
Y507517D01*
G01Y508558D02*
X49166Y509183D01*
G01X51249Y510658D02*
X51499Y510908D01*
X51624Y511200D01*
X51666Y511533D01*
X51583Y511950D01*
X51374Y512242D01*
X51124Y512325D01*
X50874Y512283D01*
X50666Y512117D01*
X50249Y511283D01*
X49958Y510908D01*
X49541Y510658D01*
X49166Y510575D01*
Y512325D01*
G01X50208Y513758D02*
X50499Y514050D01*
X50666Y514300D01*
X50749Y514633D01*
X50666Y514925D01*
X50499Y515133D01*
X50249Y515300D01*
X49958Y515342D01*
X49708Y515300D01*
X49458Y515133D01*
X49249Y514883D01*
X49166Y514592D01*
X49249Y514258D01*
X49499Y513967D01*
X49874Y513800D01*
X50291Y513758D01*
X50833Y513842D01*
X51124Y513967D01*
X51416Y514175D01*
X51624Y514467D01*
X51666Y514758D01*
X51583Y515050D01*
X51374Y515258D01*
G01X49166Y517650D02*
X51666D01*
X51166Y517150D01*
G01X49166D02*
Y518150D01*
G01X34989Y526045D02*
Y528545D01*
X33948D01*
X33614Y528420D01*
X33406Y528253D01*
X33323Y527920D01*
X33406Y527587D01*
X33656Y527378D01*
X33948Y527253D01*
X34989D01*
G01X33948D02*
X33323Y526045D01*
G01X31848Y528128D02*
X31598Y528378D01*
X31306Y528503D01*
X30973Y528545D01*
X30556Y528462D01*
X30264Y528253D01*
X30181Y528003D01*
X30223Y527753D01*
X30389Y527545D01*
X31223Y527128D01*
X31598Y526837D01*
X31848Y526420D01*
X31931Y526045D01*
X30181D01*
G01X27456D02*
Y528545D01*
X28998Y526753D01*
X26914D01*
G01X25773Y526545D02*
X25523Y526253D01*
X25189Y526087D01*
X24814Y526045D01*
X24481Y526087D01*
X24148Y526295D01*
X23939Y526545D01*
X23898Y526795D01*
X23981Y527087D01*
X24273Y527295D01*
X24564Y527378D01*
X24939D01*
G01X24564D02*
X24314Y527503D01*
X24106Y527712D01*
X24023Y527962D01*
X24106Y528212D01*
X24314Y528420D01*
X24689Y528545D01*
X25064Y528503D01*
X25439Y528337D01*
G01X43906Y524995D02*
Y528995D01*
X51306D01*
G01X36475Y524995D02*
Y528995D01*
X43875D01*
G01X34989Y520319D02*
Y522819D01*
X33948D01*
X33614Y522694D01*
X33406Y522527D01*
X33323Y522194D01*
X33406Y521861D01*
X33656Y521652D01*
X33948Y521527D01*
X34989D01*
G01X33948D02*
X33323Y520319D01*
G01X31848Y522402D02*
X31598Y522652D01*
X31306Y522777D01*
X30973Y522819D01*
X30556Y522736D01*
X30264Y522527D01*
X30181Y522277D01*
X30223Y522027D01*
X30389Y521819D01*
X31223Y521402D01*
X31598Y521111D01*
X31848Y520694D01*
X31931Y520319D01*
X30181D01*
G01X28873Y520819D02*
X28623Y520527D01*
X28289Y520361D01*
X27914Y520319D01*
X27581Y520361D01*
X27248Y520569D01*
X27039Y520819D01*
X26998Y521069D01*
X27081Y521361D01*
X27373Y521569D01*
X27664Y521652D01*
X28039D01*
G01X27664D02*
X27414Y521777D01*
X27206Y521986D01*
X27123Y522236D01*
X27206Y522486D01*
X27414Y522694D01*
X27789Y522819D01*
X28164Y522777D01*
X28539Y522611D01*
G01X24856Y520319D02*
X24564Y520361D01*
X24231Y520486D01*
X24023Y520694D01*
X23939Y520986D01*
X24023Y521277D01*
X24273Y521527D01*
X24648Y521652D01*
X25064D01*
X25314Y521736D01*
X25523Y521944D01*
X25606Y522236D01*
X25481Y522527D01*
X25189Y522736D01*
X24856Y522819D01*
X24523Y522736D01*
X24231Y522527D01*
X24106Y522236D01*
X24189Y521944D01*
X24398Y521736D01*
X24648Y521652D01*
X25064D01*
X25439Y521527D01*
X25689Y521277D01*
X25773Y520986D01*
X25689Y520694D01*
X25481Y520486D01*
X25148Y520361D01*
X24856Y520319D01*
G01X43906Y519269D02*
Y523269D01*
X51306D01*
G01X36432Y519271D02*
Y523271D01*
X43832D01*
G01X59692Y545617D02*
X59817Y545367D01*
X59900Y545075D01*
Y544742D01*
X59775Y544367D01*
X59567Y544075D01*
X59317Y543867D01*
X58900Y543700D01*
X58525Y543658D01*
X58150Y543742D01*
X57900Y543867D01*
X57650Y544117D01*
X57483Y544408D01*
X57400Y544700D01*
Y544992D01*
X57483Y545283D01*
X57608Y545533D01*
X57775Y545742D01*
G01X58442Y547008D02*
X58733Y547300D01*
X58900Y547550D01*
X58983Y547883D01*
X58900Y548175D01*
X58733Y548383D01*
X58483Y548550D01*
X58192Y548592D01*
X57942Y548550D01*
X57692Y548383D01*
X57483Y548133D01*
X57400Y547842D01*
X57483Y547508D01*
X57733Y547217D01*
X58108Y547050D01*
X58525Y547008D01*
X59067Y547092D01*
X59358Y547217D01*
X59650Y547425D01*
X59858Y547717D01*
X59900Y548008D01*
X59817Y548300D01*
X59608Y548508D01*
G01X57400Y550900D02*
X57442Y551192D01*
X57567Y551525D01*
X57775Y551733D01*
X58067Y551817D01*
X58358Y551733D01*
X58608Y551483D01*
X58733Y551108D01*
Y550692D01*
X58817Y550442D01*
X59025Y550233D01*
X59317Y550150D01*
X59608Y550275D01*
X59817Y550567D01*
X59900Y550900D01*
X59817Y551233D01*
X59608Y551525D01*
X59317Y551650D01*
X59025Y551567D01*
X58817Y551358D01*
X58733Y551108D01*
Y550692D01*
X58608Y550317D01*
X58358Y550067D01*
X58067Y549983D01*
X57775Y550067D01*
X57567Y550275D01*
X57442Y550608D01*
X57400Y550900D01*
G01X79309Y571067D02*
X79434Y570817D01*
X79517Y570525D01*
Y570192D01*
X79392Y569817D01*
X79184Y569525D01*
X78934Y569317D01*
X78517Y569150D01*
X78142Y569108D01*
X77767Y569192D01*
X77517Y569317D01*
X77267Y569567D01*
X77100Y569858D01*
X77017Y570150D01*
Y570442D01*
X77100Y570733D01*
X77225Y570983D01*
X77392Y571192D01*
G01X78059Y572458D02*
X78350Y572750D01*
X78517Y573000D01*
X78600Y573333D01*
X78517Y573625D01*
X78350Y573833D01*
X78100Y574000D01*
X77809Y574042D01*
X77559Y574000D01*
X77309Y573833D01*
X77100Y573583D01*
X77017Y573292D01*
X77100Y572958D01*
X77350Y572667D01*
X77725Y572500D01*
X78142Y572458D01*
X78684Y572542D01*
X78975Y572667D01*
X79267Y572875D01*
X79475Y573167D01*
X79517Y573458D01*
X79434Y573750D01*
X79225Y573958D01*
G01X78059Y575558D02*
X78350Y575850D01*
X78517Y576100D01*
X78600Y576433D01*
X78517Y576725D01*
X78350Y576933D01*
X78100Y577100D01*
X77809Y577142D01*
X77559Y577100D01*
X77309Y576933D01*
X77100Y576683D01*
X77017Y576392D01*
X77100Y576058D01*
X77350Y575767D01*
X77725Y575600D01*
X78142Y575558D01*
X78684Y575642D01*
X78975Y575767D01*
X79267Y575975D01*
X79475Y576267D01*
X79517Y576558D01*
X79434Y576850D01*
X79225Y577058D01*
G01X40033Y587109D02*
X40283Y587234D01*
X40575Y587317D01*
X40908D01*
X41283Y587192D01*
X41575Y586984D01*
X41783Y586734D01*
X41950Y586317D01*
X41992Y585942D01*
X41908Y585567D01*
X41783Y585317D01*
X41533Y585067D01*
X41242Y584900D01*
X40950Y584817D01*
X40658D01*
X40367Y584900D01*
X40117Y585025D01*
X39908Y585192D01*
G01X38642Y585859D02*
X38350Y586150D01*
X38100Y586317D01*
X37767Y586400D01*
X37475Y586317D01*
X37267Y586150D01*
X37100Y585900D01*
X37058Y585609D01*
X37100Y585359D01*
X37267Y585109D01*
X37517Y584900D01*
X37808Y584817D01*
X38142Y584900D01*
X38433Y585150D01*
X38600Y585525D01*
X38642Y585942D01*
X38558Y586484D01*
X38433Y586775D01*
X38225Y587067D01*
X37933Y587275D01*
X37642Y587317D01*
X37350Y587234D01*
X37142Y587025D01*
G01X35667Y585317D02*
X35417Y585025D01*
X35083Y584859D01*
X34708Y584817D01*
X34375Y584859D01*
X34042Y585067D01*
X33833Y585317D01*
X33792Y585567D01*
X33875Y585859D01*
X34167Y586067D01*
X34458Y586150D01*
X34833D01*
G01X34458D02*
X34208Y586275D01*
X34000Y586484D01*
X33917Y586734D01*
X34000Y586984D01*
X34208Y587192D01*
X34583Y587317D01*
X34958Y587275D01*
X35333Y587109D01*
G01X86207Y548398D02*
Y550898D01*
X85166D01*
X84832Y550773D01*
X84624Y550606D01*
X84541Y550273D01*
X84624Y549940D01*
X84874Y549731D01*
X85166Y549606D01*
X86207D01*
G01X85166D02*
X84541Y548398D01*
G01X83066Y550481D02*
X82816Y550731D01*
X82524Y550856D01*
X82191Y550898D01*
X81774Y550815D01*
X81482Y550606D01*
X81399Y550356D01*
X81441Y550106D01*
X81607Y549898D01*
X82441Y549481D01*
X82816Y549190D01*
X83066Y548773D01*
X83149Y548398D01*
X81399D01*
G01X79174Y550898D02*
X79507Y550815D01*
X79757Y550606D01*
X79924Y550356D01*
X80049Y550023D01*
X80091Y549648D01*
X80049Y549273D01*
X79924Y548940D01*
X79757Y548690D01*
X79507Y548481D01*
X79174Y548398D01*
X78841Y548481D01*
X78591Y548690D01*
X78424Y548940D01*
X78299Y549273D01*
X78257Y549648D01*
X78299Y550023D01*
X78424Y550356D01*
X78591Y550606D01*
X78841Y550815D01*
X79174Y550898D01*
G01X76991Y548773D02*
X76741Y548565D01*
X76449Y548440D01*
X76074Y548398D01*
X75699Y548481D01*
X75407Y548648D01*
X75199Y548940D01*
X75157Y549273D01*
X75241Y549606D01*
X75449Y549815D01*
X75741Y549981D01*
X76032Y550023D01*
X76324Y549981D01*
X76699Y549815D01*
X76574Y550898D01*
X75449D01*
G01X83924Y560398D02*
Y556398D01*
X76524D01*
G01X47233Y574967D02*
Y577467D01*
X46192D01*
X45858Y577342D01*
X45650Y577175D01*
X45567Y576842D01*
X45650Y576509D01*
X45900Y576300D01*
X46192Y576175D01*
X47233D01*
G01X46192D02*
X45567Y574967D01*
G01X44092Y577050D02*
X43842Y577300D01*
X43550Y577425D01*
X43217Y577467D01*
X42800Y577384D01*
X42508Y577175D01*
X42425Y576925D01*
X42467Y576675D01*
X42633Y576467D01*
X43467Y576050D01*
X43842Y575759D01*
X44092Y575342D01*
X44175Y574967D01*
X42425D01*
G01X40200D02*
Y577467D01*
X40700Y576967D01*
G01Y574967D02*
X39700D01*
G01X37100Y577467D02*
X37433Y577384D01*
X37683Y577175D01*
X37850Y576925D01*
X37975Y576592D01*
X38017Y576217D01*
X37975Y575842D01*
X37850Y575509D01*
X37683Y575259D01*
X37433Y575050D01*
X37100Y574967D01*
X36767Y575050D01*
X36517Y575259D01*
X36350Y575509D01*
X36225Y575842D01*
X36183Y576217D01*
X36225Y576592D01*
X36350Y576925D01*
X36517Y577175D01*
X36767Y577384D01*
X37100Y577467D01*
G01X53100Y573850D02*
Y577850D01*
X60500D01*
G01X86008Y544263D02*
Y546763D01*
X84967D01*
X84633Y546638D01*
X84425Y546471D01*
X84342Y546138D01*
X84425Y545805D01*
X84675Y545596D01*
X84967Y545471D01*
X86008D01*
G01X84967D02*
X84342Y544263D01*
G01X82867Y546346D02*
X82617Y546596D01*
X82325Y546721D01*
X81992Y546763D01*
X81575Y546680D01*
X81283Y546471D01*
X81200Y546221D01*
X81242Y545971D01*
X81408Y545763D01*
X82242Y545346D01*
X82617Y545055D01*
X82867Y544638D01*
X82950Y544263D01*
X81200D01*
G01X78975Y546763D02*
X79308Y546680D01*
X79558Y546471D01*
X79725Y546221D01*
X79850Y545888D01*
X79892Y545513D01*
X79850Y545138D01*
X79725Y544805D01*
X79558Y544555D01*
X79308Y544346D01*
X78975Y544263D01*
X78642Y544346D01*
X78392Y544555D01*
X78225Y544805D01*
X78100Y545138D01*
X78058Y545513D01*
X78100Y545888D01*
X78225Y546221D01*
X78392Y546471D01*
X78642Y546680D01*
X78975Y546763D01*
G01X76667Y545305D02*
X76375Y545596D01*
X76125Y545763D01*
X75792Y545846D01*
X75500Y545763D01*
X75292Y545596D01*
X75125Y545346D01*
X75083Y545055D01*
X75125Y544805D01*
X75292Y544555D01*
X75542Y544346D01*
X75833Y544263D01*
X76167Y544346D01*
X76458Y544596D01*
X76625Y544971D01*
X76667Y545388D01*
X76583Y545930D01*
X76458Y546221D01*
X76250Y546513D01*
X75958Y546721D01*
X75667Y546763D01*
X75375Y546680D01*
X75167Y546471D01*
G01X83925Y556363D02*
Y552363D01*
X76525D01*
G01X46439Y570461D02*
Y572961D01*
X45398D01*
X45064Y572836D01*
X44856Y572669D01*
X44773Y572336D01*
X44856Y572003D01*
X45106Y571794D01*
X45398Y571669D01*
X46439D01*
G01X45398D02*
X44773Y570461D01*
G01X43298Y572544D02*
X43048Y572794D01*
X42756Y572919D01*
X42423Y572961D01*
X42006Y572878D01*
X41714Y572669D01*
X41631Y572419D01*
X41673Y572169D01*
X41839Y571961D01*
X42673Y571544D01*
X43048Y571253D01*
X43298Y570836D01*
X43381Y570461D01*
X41631D01*
G01X39406Y572961D02*
X39739Y572878D01*
X39989Y572669D01*
X40156Y572419D01*
X40281Y572086D01*
X40323Y571711D01*
X40281Y571336D01*
X40156Y571003D01*
X39989Y570753D01*
X39739Y570544D01*
X39406Y570461D01*
X39073Y570544D01*
X38823Y570753D01*
X38656Y571003D01*
X38531Y571336D01*
X38489Y571711D01*
X38531Y572086D01*
X38656Y572419D01*
X38823Y572669D01*
X39073Y572878D01*
X39406Y572961D01*
G01X37014Y570753D02*
X36723Y570544D01*
X36389Y570461D01*
X36056Y570544D01*
X35764Y570794D01*
X35556Y571169D01*
X35473Y571544D01*
Y572003D01*
X35556Y572378D01*
X35764Y572711D01*
X36014Y572878D01*
X36306Y572961D01*
X36639Y572878D01*
X36889Y572711D01*
X37056Y572461D01*
X37139Y572128D01*
X37056Y571836D01*
X36848Y571544D01*
X36598Y571378D01*
X36306Y571336D01*
X35973Y571419D01*
X35723Y571628D01*
X35473Y572003D01*
G01X48756Y569795D02*
Y573795D01*
X56156D01*
G01X34989Y531672D02*
Y534172D01*
X33948D01*
X33614Y534047D01*
X33406Y533880D01*
X33323Y533547D01*
X33406Y533214D01*
X33656Y533005D01*
X33948Y532880D01*
X34989D01*
G01X33948D02*
X33323Y531672D01*
G01X31848Y533755D02*
X31598Y534005D01*
X31306Y534130D01*
X30973Y534172D01*
X30556Y534089D01*
X30264Y533880D01*
X30181Y533630D01*
X30223Y533380D01*
X30389Y533172D01*
X31223Y532755D01*
X31598Y532464D01*
X31848Y532047D01*
X31931Y531672D01*
X30181D01*
G01X28873Y532047D02*
X28623Y531839D01*
X28331Y531714D01*
X27956Y531672D01*
X27581Y531755D01*
X27289Y531922D01*
X27081Y532214D01*
X27039Y532547D01*
X27123Y532880D01*
X27331Y533089D01*
X27623Y533255D01*
X27914Y533297D01*
X28206Y533255D01*
X28581Y533089D01*
X28456Y534172D01*
X27331D01*
G01X24939Y531672D02*
X24856Y532214D01*
X24731Y532672D01*
X24564Y533089D01*
X24356Y533547D01*
X24023Y534172D01*
X25689D01*
G01X43906Y530622D02*
Y534622D01*
X51306D01*
G01X36465Y530638D02*
Y534638D01*
X43865D01*
G01X35068Y554203D02*
Y556703D01*
X34027D01*
X33693Y556578D01*
X33485Y556411D01*
X33402Y556078D01*
X33485Y555745D01*
X33735Y555536D01*
X34027Y555411D01*
X35068D01*
G01X34027D02*
X33402Y554203D01*
G01X31927Y556286D02*
X31677Y556536D01*
X31385Y556661D01*
X31052Y556703D01*
X30635Y556620D01*
X30343Y556411D01*
X30260Y556161D01*
X30302Y555911D01*
X30468Y555703D01*
X31302Y555286D01*
X31677Y554995D01*
X31927Y554578D01*
X32010Y554203D01*
X30260D01*
G01X28952Y554578D02*
X28702Y554370D01*
X28410Y554245D01*
X28035Y554203D01*
X27660Y554286D01*
X27368Y554453D01*
X27160Y554745D01*
X27118Y555078D01*
X27202Y555411D01*
X27410Y555620D01*
X27702Y555786D01*
X27993Y555828D01*
X28285Y555786D01*
X28660Y555620D01*
X28535Y556703D01*
X27410D01*
G01X25852Y554578D02*
X25602Y554370D01*
X25310Y554245D01*
X24935Y554203D01*
X24560Y554286D01*
X24268Y554453D01*
X24060Y554745D01*
X24018Y555078D01*
X24102Y555411D01*
X24310Y555620D01*
X24602Y555786D01*
X24893Y555828D01*
X25185Y555786D01*
X25560Y555620D01*
X25435Y556703D01*
X24310D01*
G01X43985Y553153D02*
Y557153D01*
X51385D01*
G01X36485Y553153D02*
Y557153D01*
X43885D01*
G01X34989Y537299D02*
Y539799D01*
X33948D01*
X33614Y539674D01*
X33406Y539507D01*
X33323Y539174D01*
X33406Y538841D01*
X33656Y538632D01*
X33948Y538507D01*
X34989D01*
G01X33948D02*
X33323Y537299D01*
G01X31848Y539382D02*
X31598Y539632D01*
X31306Y539757D01*
X30973Y539799D01*
X30556Y539716D01*
X30264Y539507D01*
X30181Y539257D01*
X30223Y539007D01*
X30389Y538799D01*
X31223Y538382D01*
X31598Y538091D01*
X31848Y537674D01*
X31931Y537299D01*
X30181D01*
G01X28873Y537674D02*
X28623Y537466D01*
X28331Y537341D01*
X27956Y537299D01*
X27581Y537382D01*
X27289Y537549D01*
X27081Y537841D01*
X27039Y538174D01*
X27123Y538507D01*
X27331Y538716D01*
X27623Y538882D01*
X27914Y538924D01*
X28206Y538882D01*
X28581Y538716D01*
X28456Y539799D01*
X27331D01*
G01X24856Y537299D02*
Y539799D01*
X25356Y539299D01*
G01Y537299D02*
X24356D01*
G01X43906Y536249D02*
Y540249D01*
X51306D01*
G01X36358Y536254D02*
Y540254D01*
X43758D01*
G01X34989Y542926D02*
Y545426D01*
X33948D01*
X33614Y545301D01*
X33406Y545134D01*
X33323Y544801D01*
X33406Y544468D01*
X33656Y544259D01*
X33948Y544134D01*
X34989D01*
G01X33948D02*
X33323Y542926D01*
G01X31848Y545009D02*
X31598Y545259D01*
X31306Y545384D01*
X30973Y545426D01*
X30556Y545343D01*
X30264Y545134D01*
X30181Y544884D01*
X30223Y544634D01*
X30389Y544426D01*
X31223Y544009D01*
X31598Y543718D01*
X31848Y543301D01*
X31931Y542926D01*
X30181D01*
G01X27456D02*
Y545426D01*
X28998Y543634D01*
X26914D01*
G01X24939Y542926D02*
X24856Y543468D01*
X24731Y543926D01*
X24564Y544343D01*
X24356Y544801D01*
X24023Y545426D01*
X25689D01*
G01X43906Y541876D02*
Y545876D01*
X51306D01*
G01X36458Y541881D02*
Y545881D01*
X43858D01*
G01X35068Y548576D02*
Y551076D01*
X34027D01*
X33693Y550951D01*
X33485Y550784D01*
X33402Y550451D01*
X33485Y550118D01*
X33735Y549909D01*
X34027Y549784D01*
X35068D01*
G01X34027D02*
X33402Y548576D01*
G01X31927Y550659D02*
X31677Y550909D01*
X31385Y551034D01*
X31052Y551076D01*
X30635Y550993D01*
X30343Y550784D01*
X30260Y550534D01*
X30302Y550284D01*
X30468Y550076D01*
X31302Y549659D01*
X31677Y549368D01*
X31927Y548951D01*
X32010Y548576D01*
X30260D01*
G01X28952Y549076D02*
X28702Y548784D01*
X28368Y548618D01*
X27993Y548576D01*
X27660Y548618D01*
X27327Y548826D01*
X27118Y549076D01*
X27077Y549326D01*
X27160Y549618D01*
X27452Y549826D01*
X27743Y549909D01*
X28118D01*
G01X27743D02*
X27493Y550034D01*
X27285Y550243D01*
X27202Y550493D01*
X27285Y550743D01*
X27493Y550951D01*
X27868Y551076D01*
X28243Y551034D01*
X28618Y550868D01*
G01X24435Y548576D02*
Y551076D01*
X25977Y549284D01*
X23893D01*
G01X43985Y547526D02*
Y551526D01*
X51385D01*
G01X36503Y547508D02*
Y551508D01*
X43903D01*
G01X35068Y559929D02*
Y562429D01*
X34027D01*
X33693Y562304D01*
X33485Y562137D01*
X33402Y561804D01*
X33485Y561471D01*
X33735Y561262D01*
X34027Y561137D01*
X35068D01*
G01X34027D02*
X33402Y559929D01*
G01X31927Y562012D02*
X31677Y562262D01*
X31385Y562387D01*
X31052Y562429D01*
X30635Y562346D01*
X30343Y562137D01*
X30260Y561887D01*
X30302Y561637D01*
X30468Y561429D01*
X31302Y561012D01*
X31677Y560721D01*
X31927Y560304D01*
X32010Y559929D01*
X30260D01*
G01X28035D02*
Y562429D01*
X28535Y561929D01*
G01Y559929D02*
X27535D01*
G01X25727Y562012D02*
X25477Y562262D01*
X25185Y562387D01*
X24852Y562429D01*
X24435Y562346D01*
X24143Y562137D01*
X24060Y561887D01*
X24102Y561637D01*
X24268Y561429D01*
X25102Y561012D01*
X25477Y560721D01*
X25727Y560304D01*
X25810Y559929D01*
X24060D01*
G01X43985Y558879D02*
Y562879D01*
X51385D01*
G01X36400Y558900D02*
Y562900D01*
X43800D01*
G01X62558Y587667D02*
X62683Y587417D01*
X62766Y587125D01*
Y586792D01*
X62641Y586417D01*
X62433Y586125D01*
X62183Y585917D01*
X61766Y585750D01*
X61391Y585708D01*
X61016Y585792D01*
X60766Y585917D01*
X60516Y586167D01*
X60349Y586458D01*
X60266Y586750D01*
Y587042D01*
X60349Y587333D01*
X60474Y587583D01*
X60641Y587792D01*
G01X61308Y589058D02*
X61599Y589350D01*
X61766Y589600D01*
X61849Y589933D01*
X61766Y590225D01*
X61599Y590433D01*
X61349Y590600D01*
X61058Y590642D01*
X60808Y590600D01*
X60558Y590433D01*
X60349Y590183D01*
X60266Y589892D01*
X60349Y589558D01*
X60599Y589267D01*
X60974Y589100D01*
X61391Y589058D01*
X61933Y589142D01*
X62224Y589267D01*
X62516Y589475D01*
X62724Y589767D01*
X62766Y590058D01*
X62683Y590350D01*
X62474Y590558D01*
G01X62349Y592158D02*
X62599Y592408D01*
X62724Y592700D01*
X62766Y593033D01*
X62683Y593450D01*
X62474Y593742D01*
X62224Y593825D01*
X61974Y593783D01*
X61766Y593617D01*
X61349Y592783D01*
X61058Y592408D01*
X60641Y592158D01*
X60266Y592075D01*
Y593825D01*
G01X42133Y581459D02*
X42383Y581584D01*
X42675Y581667D01*
X43008D01*
X43383Y581542D01*
X43675Y581334D01*
X43883Y581084D01*
X44050Y580667D01*
X44092Y580292D01*
X44008Y579917D01*
X43883Y579667D01*
X43633Y579417D01*
X43342Y579250D01*
X43050Y579167D01*
X42758D01*
X42467Y579250D01*
X42217Y579375D01*
X42008Y579542D01*
G01X40742Y580209D02*
X40450Y580500D01*
X40200Y580667D01*
X39867Y580750D01*
X39575Y580667D01*
X39367Y580500D01*
X39200Y580250D01*
X39158Y579959D01*
X39200Y579709D01*
X39367Y579459D01*
X39617Y579250D01*
X39908Y579167D01*
X40242Y579250D01*
X40533Y579500D01*
X40700Y579875D01*
X40742Y580292D01*
X40658Y580834D01*
X40533Y581125D01*
X40325Y581417D01*
X40033Y581625D01*
X39742Y581667D01*
X39450Y581584D01*
X39242Y581375D01*
G01X36850Y579167D02*
Y581667D01*
X37350Y581167D01*
G01Y579167D02*
X36350D01*
G01X34183Y568192D02*
X34433Y568317D01*
X34725Y568400D01*
X35058D01*
X35433Y568275D01*
X35725Y568067D01*
X35933Y567817D01*
X36100Y567400D01*
X36142Y567025D01*
X36058Y566650D01*
X35933Y566400D01*
X35683Y566150D01*
X35392Y565983D01*
X35100Y565900D01*
X34808D01*
X34517Y565983D01*
X34267Y566108D01*
X34058Y566275D01*
G01X32792Y566942D02*
X32500Y567233D01*
X32250Y567400D01*
X31917Y567483D01*
X31625Y567400D01*
X31417Y567233D01*
X31250Y566983D01*
X31208Y566692D01*
X31250Y566442D01*
X31417Y566192D01*
X31667Y565983D01*
X31958Y565900D01*
X32292Y565983D01*
X32583Y566233D01*
X32750Y566608D01*
X32792Y567025D01*
X32708Y567567D01*
X32583Y567858D01*
X32375Y568150D01*
X32083Y568358D01*
X31792Y568400D01*
X31500Y568317D01*
X31292Y568108D01*
G01X29817Y566275D02*
X29567Y566067D01*
X29275Y565942D01*
X28900Y565900D01*
X28525Y565983D01*
X28233Y566150D01*
X28025Y566442D01*
X27983Y566775D01*
X28067Y567108D01*
X28275Y567317D01*
X28567Y567483D01*
X28858Y567525D01*
X29150Y567483D01*
X29525Y567317D01*
X29400Y568400D01*
X28275D01*
G01X104583Y499559D02*
X104833Y499684D01*
X105125Y499767D01*
X105458D01*
X105833Y499642D01*
X106125Y499434D01*
X106333Y499184D01*
X106500Y498767D01*
X106542Y498392D01*
X106458Y498017D01*
X106333Y497767D01*
X106083Y497517D01*
X105792Y497350D01*
X105500Y497267D01*
X105208D01*
X104917Y497350D01*
X104667Y497475D01*
X104458Y497642D01*
G01X103317D02*
X103067Y497434D01*
X102775Y497309D01*
X102400Y497267D01*
X102025Y497350D01*
X101733Y497517D01*
X101525Y497809D01*
X101483Y498142D01*
X101567Y498475D01*
X101775Y498684D01*
X102067Y498850D01*
X102358Y498892D01*
X102650Y498850D01*
X103025Y498684D01*
X102900Y499767D01*
X101775D01*
G01X99300D02*
X99633Y499684D01*
X99883Y499475D01*
X100050Y499225D01*
X100175Y498892D01*
X100217Y498517D01*
X100175Y498142D01*
X100050Y497809D01*
X99883Y497559D01*
X99633Y497350D01*
X99300Y497267D01*
X98967Y497350D01*
X98717Y497559D01*
X98550Y497809D01*
X98425Y498142D01*
X98383Y498517D01*
X98425Y498892D01*
X98550Y499225D01*
X98717Y499475D01*
X98967Y499684D01*
X99300Y499767D01*
G01X96200Y497267D02*
X95908Y497309D01*
X95575Y497434D01*
X95367Y497642D01*
X95283Y497934D01*
X95367Y498225D01*
X95617Y498475D01*
X95992Y498600D01*
X96408D01*
X96658Y498684D01*
X96867Y498892D01*
X96950Y499184D01*
X96825Y499475D01*
X96533Y499684D01*
X96200Y499767D01*
X95867Y499684D01*
X95575Y499475D01*
X95450Y499184D01*
X95533Y498892D01*
X95742Y498684D01*
X95992Y498600D01*
X96408D01*
X96783Y498475D01*
X97033Y498225D01*
X97117Y497934D01*
X97033Y497642D01*
X96825Y497434D01*
X96492Y497309D01*
X96200Y497267D01*
G01X99900Y504600D02*
X95900D01*
Y512000D01*
G01X94286Y512077D02*
X90286D01*
Y519477D01*
G01X83032Y512077D02*
X79032D01*
Y519477D01*
G01X124267Y526617D02*
X126767D01*
Y527658D01*
X126642Y527992D01*
X126475Y528200D01*
X126142Y528283D01*
X125809Y528200D01*
X125600Y527950D01*
X125475Y527658D01*
Y526617D01*
G01Y527658D02*
X124267Y528283D01*
G01X126350Y529758D02*
X126600Y530008D01*
X126725Y530300D01*
X126767Y530633D01*
X126684Y531050D01*
X126475Y531342D01*
X126225Y531425D01*
X125975Y531383D01*
X125767Y531217D01*
X125350Y530383D01*
X125059Y530008D01*
X124642Y529758D01*
X124267Y529675D01*
Y531425D01*
G01Y533567D02*
X124809Y533650D01*
X125267Y533775D01*
X125684Y533942D01*
X126142Y534150D01*
X126767Y534483D01*
Y532817D01*
G01X124267Y536667D02*
X124809Y536750D01*
X125267Y536875D01*
X125684Y537042D01*
X126142Y537250D01*
X126767Y537583D01*
Y535917D01*
G01X136400Y509517D02*
X138900D01*
Y510558D01*
X138775Y510892D01*
X138608Y511100D01*
X138275Y511183D01*
X137942Y511100D01*
X137733Y510850D01*
X137608Y510558D01*
Y509517D01*
G01Y510558D02*
X136400Y511183D01*
G01X138483Y512658D02*
X138733Y512908D01*
X138858Y513200D01*
X138900Y513533D01*
X138817Y513950D01*
X138608Y514242D01*
X138358Y514325D01*
X138108Y514283D01*
X137900Y514117D01*
X137483Y513283D01*
X137192Y512908D01*
X136775Y512658D01*
X136400Y512575D01*
Y514325D01*
G01Y516550D02*
X136442Y516842D01*
X136567Y517175D01*
X136775Y517383D01*
X137067Y517467D01*
X137358Y517383D01*
X137608Y517133D01*
X137733Y516758D01*
Y516342D01*
X137817Y516092D01*
X138025Y515883D01*
X138317Y515800D01*
X138608Y515925D01*
X138817Y516217D01*
X138900Y516550D01*
X138817Y516883D01*
X138608Y517175D01*
X138317Y517300D01*
X138025Y517217D01*
X137817Y517008D01*
X137733Y516758D01*
Y516342D01*
X137608Y515967D01*
X137358Y515717D01*
X137067Y515633D01*
X136775Y515717D01*
X136567Y515925D01*
X136442Y516258D01*
X136400Y516550D01*
G01Y520150D02*
X138900D01*
X137108Y518608D01*
Y520692D01*
G01X140200Y496617D02*
X142700D01*
Y497658D01*
X142575Y497992D01*
X142408Y498200D01*
X142075Y498283D01*
X141742Y498200D01*
X141533Y497950D01*
X141408Y497658D01*
Y496617D01*
G01Y497658D02*
X140200Y498283D01*
G01X140700Y499633D02*
X140408Y499883D01*
X140242Y500217D01*
X140200Y500592D01*
X140242Y500925D01*
X140450Y501258D01*
X140700Y501467D01*
X140950Y501508D01*
X141242Y501425D01*
X141450Y501133D01*
X141533Y500842D01*
Y500467D01*
G01Y500842D02*
X141658Y501092D01*
X141867Y501300D01*
X142117Y501383D01*
X142367Y501300D01*
X142575Y501092D01*
X142700Y500717D01*
X142658Y500342D01*
X142492Y499967D01*
G01X140200Y503650D02*
X142700D01*
X142200Y503150D01*
G01X140200D02*
Y504150D01*
G01Y507250D02*
X142700D01*
X140908Y505708D01*
Y507792D01*
G01X99913Y512077D02*
X95913D01*
Y519477D01*
G01X94273Y504600D02*
X90273D01*
Y512000D01*
G01X83068Y504466D02*
X79068D01*
Y511866D01*
G01X88673Y504600D02*
X84673D01*
Y512000D01*
G01X88659Y512077D02*
X84659D01*
Y519477D01*
G01X132700Y509517D02*
X135200D01*
Y510558D01*
X135075Y510892D01*
X134908Y511100D01*
X134575Y511183D01*
X134242Y511100D01*
X134033Y510850D01*
X133908Y510558D01*
Y509517D01*
G01Y510558D02*
X132700Y511183D01*
G01X133200Y512533D02*
X132908Y512783D01*
X132742Y513117D01*
X132700Y513492D01*
X132742Y513825D01*
X132950Y514158D01*
X133200Y514367D01*
X133450Y514408D01*
X133742Y514325D01*
X133950Y514033D01*
X134033Y513742D01*
Y513367D01*
G01Y513742D02*
X134158Y513992D01*
X134367Y514200D01*
X134617Y514283D01*
X134867Y514200D01*
X135075Y513992D01*
X135200Y513617D01*
X135158Y513242D01*
X134992Y512867D01*
G01X132700Y516467D02*
X133242Y516550D01*
X133700Y516675D01*
X134117Y516842D01*
X134575Y517050D01*
X135200Y517383D01*
Y515717D01*
G01Y519650D02*
X135117Y519317D01*
X134908Y519067D01*
X134658Y518900D01*
X134325Y518775D01*
X133950Y518733D01*
X133575Y518775D01*
X133242Y518900D01*
X132992Y519067D01*
X132783Y519317D01*
X132700Y519650D01*
X132783Y519983D01*
X132992Y520233D01*
X133242Y520400D01*
X133575Y520525D01*
X133950Y520567D01*
X134325Y520525D01*
X134658Y520400D01*
X134908Y520233D01*
X135117Y519983D01*
X135200Y519650D01*
G01X136983Y522167D02*
Y524667D01*
X135942D01*
X135608Y524542D01*
X135400Y524375D01*
X135317Y524042D01*
X135400Y523709D01*
X135650Y523500D01*
X135942Y523375D01*
X136983D01*
G01X135942D02*
X135317Y522167D01*
G01X133967Y522667D02*
X133717Y522375D01*
X133383Y522209D01*
X133008Y522167D01*
X132675Y522209D01*
X132342Y522417D01*
X132133Y522667D01*
X132092Y522917D01*
X132175Y523209D01*
X132467Y523417D01*
X132758Y523500D01*
X133133D01*
G01X132758D02*
X132508Y523625D01*
X132300Y523834D01*
X132217Y524084D01*
X132300Y524334D01*
X132508Y524542D01*
X132883Y524667D01*
X133258Y524625D01*
X133633Y524459D01*
G01X130033Y522167D02*
X129950Y522709D01*
X129825Y523167D01*
X129658Y523584D01*
X129450Y524042D01*
X129117Y524667D01*
X130783D01*
G01X127767Y522667D02*
X127517Y522375D01*
X127183Y522209D01*
X126808Y522167D01*
X126475Y522209D01*
X126142Y522417D01*
X125933Y522667D01*
X125892Y522917D01*
X125975Y523209D01*
X126267Y523417D01*
X126558Y523500D01*
X126933D01*
G01X126558D02*
X126308Y523625D01*
X126100Y523834D01*
X126017Y524084D01*
X126100Y524334D01*
X126308Y524542D01*
X126683Y524667D01*
X127058Y524625D01*
X127433Y524459D01*
G01X140100Y509517D02*
X142600D01*
Y510558D01*
X142475Y510892D01*
X142308Y511100D01*
X141975Y511183D01*
X141642Y511100D01*
X141433Y510850D01*
X141308Y510558D01*
Y509517D01*
G01Y510558D02*
X140100Y511183D01*
G01X140600Y512533D02*
X140308Y512783D01*
X140142Y513117D01*
X140100Y513492D01*
X140142Y513825D01*
X140350Y514158D01*
X140600Y514367D01*
X140850Y514408D01*
X141142Y514325D01*
X141350Y514033D01*
X141433Y513742D01*
Y513367D01*
G01Y513742D02*
X141558Y513992D01*
X141767Y514200D01*
X142017Y514283D01*
X142267Y514200D01*
X142475Y513992D01*
X142600Y513617D01*
X142558Y513242D01*
X142392Y512867D01*
G01X140100Y516467D02*
X140642Y516550D01*
X141100Y516675D01*
X141517Y516842D01*
X141975Y517050D01*
X142600Y517383D01*
Y515717D01*
G01X140100Y520150D02*
X142600D01*
X140808Y518608D01*
Y520692D01*
G01X123983Y522167D02*
Y524667D01*
X122942D01*
X122608Y524542D01*
X122400Y524375D01*
X122317Y524042D01*
X122400Y523709D01*
X122650Y523500D01*
X122942Y523375D01*
X123983D01*
G01X122942D02*
X122317Y522167D01*
G01X120967Y522667D02*
X120717Y522375D01*
X120383Y522209D01*
X120008Y522167D01*
X119675Y522209D01*
X119342Y522417D01*
X119133Y522667D01*
X119092Y522917D01*
X119175Y523209D01*
X119467Y523417D01*
X119758Y523500D01*
X120133D01*
G01X119758D02*
X119508Y523625D01*
X119300Y523834D01*
X119217Y524084D01*
X119300Y524334D01*
X119508Y524542D01*
X119883Y524667D01*
X120258Y524625D01*
X120633Y524459D01*
G01X117033Y522167D02*
X116950Y522709D01*
X116825Y523167D01*
X116658Y523584D01*
X116450Y524042D01*
X116117Y524667D01*
X117783D01*
G01X114767Y522542D02*
X114517Y522334D01*
X114225Y522209D01*
X113850Y522167D01*
X113475Y522250D01*
X113183Y522417D01*
X112975Y522709D01*
X112933Y523042D01*
X113017Y523375D01*
X113225Y523584D01*
X113517Y523750D01*
X113808Y523792D01*
X114100Y523750D01*
X114475Y523584D01*
X114350Y524667D01*
X113225D01*
G01X133800Y471117D02*
X136300D01*
Y472158D01*
X136175Y472492D01*
X136008Y472700D01*
X135675Y472783D01*
X135342Y472700D01*
X135133Y472450D01*
X135008Y472158D01*
Y471117D01*
G01Y472158D02*
X133800Y472783D01*
G01Y474967D02*
X134342Y475050D01*
X134800Y475175D01*
X135217Y475342D01*
X135675Y475550D01*
X136300Y475883D01*
Y474217D01*
G01X133800Y478150D02*
X136300D01*
X135800Y477650D01*
G01X133800D02*
Y478650D01*
G01X134842Y480458D02*
X135133Y480750D01*
X135300Y481000D01*
X135383Y481333D01*
X135300Y481625D01*
X135133Y481833D01*
X134883Y482000D01*
X134592Y482042D01*
X134342Y482000D01*
X134092Y481833D01*
X133883Y481583D01*
X133800Y481292D01*
X133883Y480958D01*
X134133Y480667D01*
X134508Y480500D01*
X134925Y480458D01*
X135467Y480542D01*
X135758Y480667D01*
X136050Y480875D01*
X136258Y481167D01*
X136300Y481458D01*
X136217Y481750D01*
X136008Y481958D01*
G01X138702Y487161D02*
X134702D01*
Y494561D01*
G01X132800Y496617D02*
X135300D01*
Y497658D01*
X135175Y497992D01*
X135008Y498200D01*
X134675Y498283D01*
X134342Y498200D01*
X134133Y497950D01*
X134008Y497658D01*
Y496617D01*
G01Y497658D02*
X132800Y498283D01*
G01X134883Y499758D02*
X135133Y500008D01*
X135258Y500300D01*
X135300Y500633D01*
X135217Y501050D01*
X135008Y501342D01*
X134758Y501425D01*
X134508Y501383D01*
X134300Y501217D01*
X133883Y500383D01*
X133592Y500008D01*
X133175Y499758D01*
X132800Y499675D01*
Y501425D01*
G01Y503567D02*
X133342Y503650D01*
X133800Y503775D01*
X134217Y503942D01*
X134675Y504150D01*
X135300Y504483D01*
Y502817D01*
G01X133842Y505958D02*
X134133Y506250D01*
X134300Y506500D01*
X134383Y506833D01*
X134300Y507125D01*
X134133Y507333D01*
X133883Y507500D01*
X133592Y507542D01*
X133342Y507500D01*
X133092Y507333D01*
X132883Y507083D01*
X132800Y506792D01*
X132883Y506458D01*
X133133Y506167D01*
X133508Y506000D01*
X133925Y505958D01*
X134467Y506042D01*
X134758Y506167D01*
X135050Y506375D01*
X135258Y506667D01*
X135300Y506958D01*
X135217Y507250D01*
X135008Y507458D01*
G01X137500Y471117D02*
X140000D01*
Y472158D01*
X139875Y472492D01*
X139708Y472700D01*
X139375Y472783D01*
X139042Y472700D01*
X138833Y472450D01*
X138708Y472158D01*
Y471117D01*
G01Y472158D02*
X137500Y472783D01*
G01Y474967D02*
X138042Y475050D01*
X138500Y475175D01*
X138917Y475342D01*
X139375Y475550D01*
X140000Y475883D01*
Y474217D01*
G01X137500Y478150D02*
X137542Y478442D01*
X137667Y478775D01*
X137875Y478983D01*
X138167Y479067D01*
X138458Y478983D01*
X138708Y478733D01*
X138833Y478358D01*
Y477942D01*
X138917Y477692D01*
X139125Y477483D01*
X139417Y477400D01*
X139708Y477525D01*
X139917Y477817D01*
X140000Y478150D01*
X139917Y478483D01*
X139708Y478775D01*
X139417Y478900D01*
X139125Y478817D01*
X138917Y478608D01*
X138833Y478358D01*
Y477942D01*
X138708Y477567D01*
X138458Y477317D01*
X138167Y477233D01*
X137875Y477317D01*
X137667Y477525D01*
X137542Y477858D01*
X137500Y478150D01*
G01X138000Y480333D02*
X137708Y480583D01*
X137542Y480917D01*
X137500Y481292D01*
X137542Y481625D01*
X137750Y481958D01*
X138000Y482167D01*
X138250Y482208D01*
X138542Y482125D01*
X138750Y481833D01*
X138833Y481542D01*
Y481167D01*
G01Y481542D02*
X138958Y481792D01*
X139167Y482000D01*
X139417Y482083D01*
X139667Y482000D01*
X139875Y481792D01*
X140000Y481417D01*
X139958Y481042D01*
X139792Y480667D01*
G01X138702Y494561D02*
X142702D01*
Y487161D01*
G01X130733Y502717D02*
Y505217D01*
X129692D01*
X129358Y505092D01*
X129150Y504925D01*
X129067Y504592D01*
X129150Y504259D01*
X129400Y504050D01*
X129692Y503925D01*
X130733D01*
G01X129692D02*
X129067Y502717D01*
G01X126883D02*
X126800Y503259D01*
X126675Y503717D01*
X126508Y504134D01*
X126300Y504592D01*
X125967Y505217D01*
X127633D01*
G01X124617Y503217D02*
X124367Y502925D01*
X124033Y502759D01*
X123658Y502717D01*
X123325Y502759D01*
X122992Y502967D01*
X122783Y503217D01*
X122742Y503467D01*
X122825Y503759D01*
X123117Y503967D01*
X123408Y504050D01*
X123783D01*
G01X123408D02*
X123158Y504175D01*
X122950Y504384D01*
X122867Y504634D01*
X122950Y504884D01*
X123158Y505092D01*
X123533Y505217D01*
X123908Y505175D01*
X124283Y505009D01*
G01X120100Y502717D02*
Y505217D01*
X121642Y503425D01*
X119558D01*
G01X123770Y497350D02*
Y501350D01*
X131170D01*
G01X116483Y502700D02*
Y505200D01*
X115442D01*
X115108Y505075D01*
X114900Y504908D01*
X114817Y504575D01*
X114900Y504242D01*
X115150Y504033D01*
X115442Y503908D01*
X116483D01*
G01X115442D02*
X114817Y502700D01*
G01X112633D02*
X112550Y503242D01*
X112425Y503700D01*
X112258Y504117D01*
X112050Y504575D01*
X111717Y505200D01*
X113383D01*
G01X110367Y503200D02*
X110117Y502908D01*
X109783Y502742D01*
X109408Y502700D01*
X109075Y502742D01*
X108742Y502950D01*
X108533Y503200D01*
X108492Y503450D01*
X108575Y503742D01*
X108867Y503950D01*
X109158Y504033D01*
X109533D01*
G01X109158D02*
X108908Y504158D01*
X108700Y504367D01*
X108617Y504617D01*
X108700Y504867D01*
X108908Y505075D01*
X109283Y505200D01*
X109658Y505158D01*
X110033Y504992D01*
G01X107142Y504783D02*
X106892Y505033D01*
X106600Y505158D01*
X106267Y505200D01*
X105850Y505117D01*
X105558Y504908D01*
X105475Y504658D01*
X105517Y504408D01*
X105683Y504200D01*
X106517Y503783D01*
X106892Y503492D01*
X107142Y503075D01*
X107225Y502700D01*
X105475D01*
G01X123330Y501550D02*
Y497550D01*
X115930D01*
G01X136500Y496617D02*
X139000D01*
Y497658D01*
X138875Y497992D01*
X138708Y498200D01*
X138375Y498283D01*
X138042Y498200D01*
X137833Y497950D01*
X137708Y497658D01*
Y496617D01*
G01Y497658D02*
X136500Y498283D01*
G01X137000Y499633D02*
X136708Y499883D01*
X136542Y500217D01*
X136500Y500592D01*
X136542Y500925D01*
X136750Y501258D01*
X137000Y501467D01*
X137250Y501508D01*
X137542Y501425D01*
X137750Y501133D01*
X137833Y500842D01*
Y500467D01*
G01Y500842D02*
X137958Y501092D01*
X138167Y501300D01*
X138417Y501383D01*
X138667Y501300D01*
X138875Y501092D01*
X139000Y500717D01*
X138958Y500342D01*
X138792Y499967D01*
G01X136500Y504150D02*
X139000D01*
X137208Y502608D01*
Y504692D01*
G01X136500Y506750D02*
X136542Y507042D01*
X136667Y507375D01*
X136875Y507583D01*
X137167Y507667D01*
X137458Y507583D01*
X137708Y507333D01*
X137833Y506958D01*
Y506542D01*
X137917Y506292D01*
X138125Y506083D01*
X138417Y506000D01*
X138708Y506125D01*
X138917Y506417D01*
X139000Y506750D01*
X138917Y507083D01*
X138708Y507375D01*
X138417Y507500D01*
X138125Y507417D01*
X137917Y507208D01*
X137833Y506958D01*
Y506542D01*
X137708Y506167D01*
X137458Y505917D01*
X137167Y505833D01*
X136875Y505917D01*
X136667Y506125D01*
X136542Y506458D01*
X136500Y506750D01*
G01X130883Y514700D02*
Y517200D01*
X129842D01*
X129508Y517075D01*
X129300Y516908D01*
X129217Y516575D01*
X129300Y516242D01*
X129550Y516033D01*
X129842Y515908D01*
X130883D01*
G01X129842D02*
X129217Y514700D01*
G01X127742Y515742D02*
X127450Y516033D01*
X127200Y516200D01*
X126867Y516283D01*
X126575Y516200D01*
X126367Y516033D01*
X126200Y515783D01*
X126158Y515492D01*
X126200Y515242D01*
X126367Y514992D01*
X126617Y514783D01*
X126908Y514700D01*
X127242Y514783D01*
X127533Y515033D01*
X127700Y515408D01*
X127742Y515825D01*
X127658Y516367D01*
X127533Y516658D01*
X127325Y516950D01*
X127033Y517158D01*
X126742Y517200D01*
X126450Y517117D01*
X126242Y516908D01*
G01X123850Y514700D02*
Y517200D01*
X124350Y516700D01*
G01Y514700D02*
X123350D01*
G01X121542Y516783D02*
X121292Y517033D01*
X121000Y517158D01*
X120667Y517200D01*
X120250Y517117D01*
X119958Y516908D01*
X119875Y516658D01*
X119917Y516408D01*
X120083Y516200D01*
X120917Y515783D01*
X121292Y515492D01*
X121542Y515075D01*
X121625Y514700D01*
X119875D01*
G01X130883Y511000D02*
Y513500D01*
X129842D01*
X129508Y513375D01*
X129300Y513208D01*
X129217Y512875D01*
X129300Y512542D01*
X129550Y512333D01*
X129842Y512208D01*
X130883D01*
G01X129842D02*
X129217Y511000D01*
G01X127742Y512042D02*
X127450Y512333D01*
X127200Y512500D01*
X126867Y512583D01*
X126575Y512500D01*
X126367Y512333D01*
X126200Y512083D01*
X126158Y511792D01*
X126200Y511542D01*
X126367Y511292D01*
X126617Y511083D01*
X126908Y511000D01*
X127242Y511083D01*
X127533Y511333D01*
X127700Y511708D01*
X127742Y512125D01*
X127658Y512667D01*
X127533Y512958D01*
X127325Y513250D01*
X127033Y513458D01*
X126742Y513500D01*
X126450Y513417D01*
X126242Y513208D01*
G01X123850Y511000D02*
Y513500D01*
X124350Y513000D01*
G01Y511000D02*
X123350D01*
G01X120750D02*
Y513500D01*
X121250Y513000D01*
G01Y511000D02*
X120250D01*
G01X136200Y527350D02*
X133700D01*
G01X136200Y526392D02*
Y528308D01*
G01X133700Y529617D02*
X136200D01*
Y530617D01*
X136075Y530950D01*
X135783Y531200D01*
X135450Y531283D01*
X135117Y531200D01*
X134867Y530992D01*
X134742Y530617D01*
Y529617D01*
G01X135783Y532758D02*
X136033Y533008D01*
X136158Y533300D01*
X136200Y533633D01*
X136117Y534050D01*
X135908Y534342D01*
X135658Y534425D01*
X135408Y534383D01*
X135200Y534217D01*
X134783Y533383D01*
X134492Y533008D01*
X134075Y532758D01*
X133700Y532675D01*
Y534425D01*
G01X133992Y535942D02*
X133783Y536233D01*
X133700Y536567D01*
X133783Y536900D01*
X134033Y537192D01*
X134408Y537400D01*
X134783Y537483D01*
X135242D01*
X135617Y537400D01*
X135950Y537192D01*
X136117Y536942D01*
X136200Y536650D01*
X136117Y536317D01*
X135950Y536067D01*
X135700Y535900D01*
X135367Y535817D01*
X135075Y535900D01*
X134783Y536108D01*
X134617Y536358D01*
X134575Y536650D01*
X134658Y536983D01*
X134867Y537233D01*
X135242Y537483D01*
G01X131160Y527386D02*
X128660D01*
G01X131160Y526428D02*
Y528344D01*
G01X128660Y529653D02*
X131160D01*
Y530653D01*
X131035Y530986D01*
X130743Y531236D01*
X130410Y531319D01*
X130077Y531236D01*
X129827Y531028D01*
X129702Y530653D01*
Y529653D01*
G01X128660Y533586D02*
X131160D01*
X130660Y533086D01*
G01X128660D02*
Y534086D01*
G01Y536686D02*
X128702Y536978D01*
X128827Y537311D01*
X129035Y537519D01*
X129327Y537603D01*
X129618Y537519D01*
X129868Y537269D01*
X129993Y536894D01*
Y536478D01*
X130077Y536228D01*
X130285Y536019D01*
X130577Y535936D01*
X130868Y536061D01*
X131077Y536353D01*
X131160Y536686D01*
X131077Y537019D01*
X130868Y537311D01*
X130577Y537436D01*
X130285Y537353D01*
X130077Y537144D01*
X129993Y536894D01*
Y536478D01*
X129868Y536103D01*
X129618Y535853D01*
X129327Y535769D01*
X129035Y535853D01*
X128827Y536061D01*
X128702Y536394D01*
X128660Y536686D01*
G01X141100Y527550D02*
X138600D01*
G01X141100Y526592D02*
Y528508D01*
G01X138600Y529817D02*
X141100D01*
Y530817D01*
X140975Y531150D01*
X140683Y531400D01*
X140350Y531483D01*
X140017Y531400D01*
X139767Y531192D01*
X139642Y530817D01*
Y529817D01*
G01X140683Y532958D02*
X140933Y533208D01*
X141058Y533500D01*
X141100Y533833D01*
X141017Y534250D01*
X140808Y534542D01*
X140558Y534625D01*
X140308Y534583D01*
X140100Y534417D01*
X139683Y533583D01*
X139392Y533208D01*
X138975Y532958D01*
X138600Y532875D01*
Y534625D01*
G01Y536767D02*
X139142Y536850D01*
X139600Y536975D01*
X140017Y537142D01*
X140475Y537350D01*
X141100Y537683D01*
Y536017D01*
G01X128917Y481067D02*
Y479275D01*
X128750Y478900D01*
X128417Y478650D01*
X128000Y478567D01*
X127583Y478650D01*
X127250Y478900D01*
X127083Y479275D01*
Y481067D01*
G01X124900Y478567D02*
Y481067D01*
X125400Y480567D01*
G01Y478567D02*
X124400D01*
G01X121800Y481067D02*
X122133Y480984D01*
X122383Y480775D01*
X122550Y480525D01*
X122675Y480192D01*
X122717Y479817D01*
X122675Y479442D01*
X122550Y479109D01*
X122383Y478859D01*
X122133Y478650D01*
X121800Y478567D01*
X121467Y478650D01*
X121217Y478859D01*
X121050Y479109D01*
X120925Y479442D01*
X120883Y479817D01*
X120925Y480192D01*
X121050Y480525D01*
X121217Y480775D01*
X121467Y480984D01*
X121800Y481067D01*
G01X118200Y478567D02*
Y481067D01*
X119742Y479275D01*
X117658D01*
G01X116900Y482650D02*
X130300D01*
G01X116900Y492650D02*
Y482650D01*
G01X130300Y492650D02*
X116900D01*
G01X130300Y482650D02*
Y492650D01*
G01X106822Y565802D02*
X106947Y565552D01*
X107030Y565260D01*
Y564927D01*
X106905Y564552D01*
X106697Y564260D01*
X106447Y564052D01*
X106030Y563885D01*
X105655Y563843D01*
X105280Y563927D01*
X105030Y564052D01*
X104780Y564302D01*
X104613Y564593D01*
X104530Y564885D01*
Y565177D01*
X104613Y565468D01*
X104738Y565718D01*
X104905Y565927D01*
G01X105572Y567193D02*
X105863Y567485D01*
X106030Y567735D01*
X106113Y568068D01*
X106030Y568360D01*
X105863Y568568D01*
X105613Y568735D01*
X105322Y568777D01*
X105072Y568735D01*
X104822Y568568D01*
X104613Y568318D01*
X104530Y568027D01*
X104613Y567693D01*
X104863Y567402D01*
X105238Y567235D01*
X105655Y567193D01*
X106197Y567277D01*
X106488Y567402D01*
X106780Y567610D01*
X106988Y567902D01*
X107030Y568193D01*
X106947Y568485D01*
X106738Y568693D01*
G01X104530Y571002D02*
X105072Y571085D01*
X105530Y571210D01*
X105947Y571377D01*
X106405Y571585D01*
X107030Y571918D01*
Y570252D01*
G01X110979Y565331D02*
X111104Y565081D01*
X111187Y564789D01*
Y564456D01*
X111062Y564081D01*
X110854Y563789D01*
X110604Y563581D01*
X110187Y563414D01*
X109812Y563372D01*
X109437Y563456D01*
X109187Y563581D01*
X108937Y563831D01*
X108770Y564122D01*
X108687Y564414D01*
Y564706D01*
X108770Y564997D01*
X108895Y565247D01*
X109062Y565456D01*
G01X109729Y566722D02*
X110020Y567014D01*
X110187Y567264D01*
X110270Y567597D01*
X110187Y567889D01*
X110020Y568097D01*
X109770Y568264D01*
X109479Y568306D01*
X109229Y568264D01*
X108979Y568097D01*
X108770Y567847D01*
X108687Y567556D01*
X108770Y567222D01*
X109020Y566931D01*
X109395Y566764D01*
X109812Y566722D01*
X110354Y566806D01*
X110645Y566931D01*
X110937Y567139D01*
X111145Y567431D01*
X111187Y567722D01*
X111104Y568014D01*
X110895Y568222D01*
G01X108979Y569906D02*
X108770Y570197D01*
X108687Y570531D01*
X108770Y570864D01*
X109020Y571156D01*
X109395Y571364D01*
X109770Y571447D01*
X110229D01*
X110604Y571364D01*
X110937Y571156D01*
X111104Y570906D01*
X111187Y570614D01*
X111104Y570281D01*
X110937Y570031D01*
X110687Y569864D01*
X110354Y569781D01*
X110062Y569864D01*
X109770Y570072D01*
X109604Y570322D01*
X109562Y570614D01*
X109645Y570947D01*
X109854Y571197D01*
X110229Y571447D01*
G01X114573Y565832D02*
X114698Y565582D01*
X114781Y565290D01*
Y564957D01*
X114656Y564582D01*
X114448Y564290D01*
X114198Y564082D01*
X113781Y563915D01*
X113406Y563873D01*
X113031Y563957D01*
X112781Y564082D01*
X112531Y564332D01*
X112364Y564623D01*
X112281Y564915D01*
Y565207D01*
X112364Y565498D01*
X112489Y565748D01*
X112656Y565957D01*
G01X112281Y567932D02*
X112823Y568015D01*
X113281Y568140D01*
X113698Y568307D01*
X114156Y568515D01*
X114781Y568848D01*
Y567182D01*
G01Y571115D02*
X114698Y570782D01*
X114489Y570532D01*
X114239Y570365D01*
X113906Y570240D01*
X113531Y570198D01*
X113156Y570240D01*
X112823Y570365D01*
X112573Y570532D01*
X112364Y570782D01*
X112281Y571115D01*
X112364Y571448D01*
X112573Y571698D01*
X112823Y571865D01*
X113156Y571990D01*
X113531Y572032D01*
X113906Y571990D01*
X114239Y571865D01*
X114489Y571698D01*
X114698Y571448D01*
X114781Y571115D01*
G01X107233Y581959D02*
X107483Y582084D01*
X107775Y582167D01*
X108108D01*
X108483Y582042D01*
X108775Y581834D01*
X108983Y581584D01*
X109150Y581167D01*
X109192Y580792D01*
X109108Y580417D01*
X108983Y580167D01*
X108733Y579917D01*
X108442Y579750D01*
X108150Y579667D01*
X107858D01*
X107567Y579750D01*
X107317Y579875D01*
X107108Y580042D01*
G01X105133Y579667D02*
X105050Y580209D01*
X104925Y580667D01*
X104758Y581084D01*
X104550Y581542D01*
X104217Y582167D01*
X105883D01*
G01X102867Y580167D02*
X102617Y579875D01*
X102283Y579709D01*
X101908Y579667D01*
X101575Y579709D01*
X101242Y579917D01*
X101033Y580167D01*
X100992Y580417D01*
X101075Y580709D01*
X101367Y580917D01*
X101658Y581000D01*
X102033D01*
G01X101658D02*
X101408Y581125D01*
X101200Y581334D01*
X101117Y581584D01*
X101200Y581834D01*
X101408Y582042D01*
X101783Y582167D01*
X102158Y582125D01*
X102533Y581959D01*
G01X134533Y583109D02*
X134783Y583234D01*
X135075Y583317D01*
X135408D01*
X135783Y583192D01*
X136075Y582984D01*
X136283Y582734D01*
X136450Y582317D01*
X136492Y581942D01*
X136408Y581567D01*
X136283Y581317D01*
X136033Y581067D01*
X135742Y580900D01*
X135450Y580817D01*
X135158D01*
X134867Y580900D01*
X134617Y581025D01*
X134408Y581192D01*
G01X132433Y580817D02*
X132350Y581359D01*
X132225Y581817D01*
X132058Y582234D01*
X131850Y582692D01*
X131517Y583317D01*
X133183D01*
G01X129250Y580817D02*
Y583317D01*
X129750Y582817D01*
G01Y580817D02*
X128750D01*
G01X95885Y582219D02*
X96010Y581969D01*
X96093Y581677D01*
Y581344D01*
X95968Y580969D01*
X95760Y580677D01*
X95510Y580469D01*
X95093Y580302D01*
X94718Y580260D01*
X94343Y580344D01*
X94093Y580469D01*
X93843Y580719D01*
X93676Y581010D01*
X93593Y581302D01*
Y581594D01*
X93676Y581885D01*
X93801Y582135D01*
X93968Y582344D01*
G01X93593Y584319D02*
X94135Y584402D01*
X94593Y584527D01*
X95010Y584694D01*
X95468Y584902D01*
X96093Y585235D01*
Y583569D01*
G01X95676Y586710D02*
X95926Y586960D01*
X96051Y587252D01*
X96093Y587585D01*
X96010Y588002D01*
X95801Y588294D01*
X95551Y588377D01*
X95301Y588335D01*
X95093Y588169D01*
X94676Y587335D01*
X94385Y586960D01*
X93968Y586710D01*
X93593Y586627D01*
Y588377D01*
G01X113392Y591067D02*
X113517Y590817D01*
X113600Y590525D01*
Y590192D01*
X113475Y589817D01*
X113267Y589525D01*
X113017Y589317D01*
X112600Y589150D01*
X112225Y589108D01*
X111850Y589192D01*
X111600Y589317D01*
X111350Y589567D01*
X111183Y589858D01*
X111100Y590150D01*
Y590442D01*
X111183Y590733D01*
X111308Y590983D01*
X111475Y591192D01*
G01X111392Y592542D02*
X111183Y592833D01*
X111100Y593167D01*
X111183Y593500D01*
X111433Y593792D01*
X111808Y594000D01*
X112183Y594083D01*
X112642D01*
X113017Y594000D01*
X113350Y593792D01*
X113517Y593542D01*
X113600Y593250D01*
X113517Y592917D01*
X113350Y592667D01*
X113100Y592500D01*
X112767Y592417D01*
X112475Y592500D01*
X112183Y592708D01*
X112017Y592958D01*
X111975Y593250D01*
X112058Y593583D01*
X112267Y593833D01*
X112642Y594083D01*
G01X111100Y596850D02*
X113600D01*
X111808Y595308D01*
Y597392D01*
G01X109892Y591067D02*
X110017Y590817D01*
X110100Y590525D01*
Y590192D01*
X109975Y589817D01*
X109767Y589525D01*
X109517Y589317D01*
X109100Y589150D01*
X108725Y589108D01*
X108350Y589192D01*
X108100Y589317D01*
X107850Y589567D01*
X107683Y589858D01*
X107600Y590150D01*
Y590442D01*
X107683Y590733D01*
X107808Y590983D01*
X107975Y591192D01*
G01X107892Y592542D02*
X107683Y592833D01*
X107600Y593167D01*
X107683Y593500D01*
X107933Y593792D01*
X108308Y594000D01*
X108683Y594083D01*
X109142D01*
X109517Y594000D01*
X109850Y593792D01*
X110017Y593542D01*
X110100Y593250D01*
X110017Y592917D01*
X109850Y592667D01*
X109600Y592500D01*
X109267Y592417D01*
X108975Y592500D01*
X108683Y592708D01*
X108517Y592958D01*
X108475Y593250D01*
X108558Y593583D01*
X108767Y593833D01*
X109142Y594083D01*
G01X108100Y595433D02*
X107808Y595683D01*
X107642Y596017D01*
X107600Y596392D01*
X107642Y596725D01*
X107850Y597058D01*
X108100Y597267D01*
X108350Y597308D01*
X108642Y597225D01*
X108850Y596933D01*
X108933Y596642D01*
Y596267D01*
G01Y596642D02*
X109058Y596892D01*
X109267Y597100D01*
X109517Y597183D01*
X109767Y597100D01*
X109975Y596892D01*
X110100Y596517D01*
X110058Y596142D01*
X109892Y595767D01*
G01X118909Y544167D02*
X119034Y543917D01*
X119117Y543625D01*
Y543292D01*
X118992Y542917D01*
X118784Y542625D01*
X118534Y542417D01*
X118117Y542250D01*
X117742Y542208D01*
X117367Y542292D01*
X117117Y542417D01*
X116867Y542667D01*
X116700Y542958D01*
X116617Y543250D01*
Y543542D01*
X116700Y543833D01*
X116825Y544083D01*
X116992Y544292D01*
G01X116617Y546350D02*
X119117D01*
X118617Y545850D01*
G01X116617D02*
Y546850D01*
G01X119117Y549450D02*
X119034Y549117D01*
X118825Y548867D01*
X118575Y548700D01*
X118242Y548575D01*
X117867Y548533D01*
X117492Y548575D01*
X117159Y548700D01*
X116909Y548867D01*
X116700Y549117D01*
X116617Y549450D01*
X116700Y549783D01*
X116909Y550033D01*
X117159Y550200D01*
X117492Y550325D01*
X117867Y550367D01*
X118242Y550325D01*
X118575Y550200D01*
X118825Y550033D01*
X119034Y549783D01*
X119117Y549450D01*
G01X117659Y551758D02*
X117950Y552050D01*
X118117Y552300D01*
X118200Y552633D01*
X118117Y552925D01*
X117950Y553133D01*
X117700Y553300D01*
X117409Y553342D01*
X117159Y553300D01*
X116909Y553133D01*
X116700Y552883D01*
X116617Y552592D01*
X116700Y552258D01*
X116950Y551967D01*
X117325Y551800D01*
X117742Y551758D01*
X118284Y551842D01*
X118575Y551967D01*
X118867Y552175D01*
X119075Y552467D01*
X119117Y552758D01*
X119034Y553050D01*
X118825Y553258D01*
G01X123491Y572116D02*
X123616Y571866D01*
X123699Y571574D01*
Y571241D01*
X123574Y570866D01*
X123366Y570574D01*
X123116Y570366D01*
X122699Y570199D01*
X122324Y570157D01*
X121949Y570241D01*
X121699Y570366D01*
X121449Y570616D01*
X121282Y570907D01*
X121199Y571199D01*
Y571491D01*
X121282Y571782D01*
X121407Y572032D01*
X121574Y572241D01*
G01Y573382D02*
X121366Y573632D01*
X121241Y573924D01*
X121199Y574299D01*
X121282Y574674D01*
X121449Y574966D01*
X121741Y575174D01*
X122074Y575216D01*
X122407Y575132D01*
X122616Y574924D01*
X122782Y574632D01*
X122824Y574341D01*
X122782Y574049D01*
X122616Y573674D01*
X123699Y573799D01*
Y574924D01*
G01X121199Y577316D02*
X121741Y577399D01*
X122199Y577524D01*
X122616Y577691D01*
X123074Y577899D01*
X123699Y578232D01*
Y576566D01*
G01X147400Y530600D02*
X143400D01*
Y538000D01*
G01X116483Y559167D02*
Y561667D01*
X115442D01*
X115108Y561542D01*
X114900Y561375D01*
X114817Y561042D01*
X114900Y560709D01*
X115150Y560500D01*
X115442Y560375D01*
X116483D01*
G01X115442D02*
X114817Y559167D01*
G01X113342Y561250D02*
X113092Y561500D01*
X112800Y561625D01*
X112467Y561667D01*
X112050Y561584D01*
X111758Y561375D01*
X111675Y561125D01*
X111717Y560875D01*
X111883Y560667D01*
X112717Y560250D01*
X113092Y559959D01*
X113342Y559542D01*
X113425Y559167D01*
X111675D01*
G01X110242Y561250D02*
X109992Y561500D01*
X109700Y561625D01*
X109367Y561667D01*
X108950Y561584D01*
X108658Y561375D01*
X108575Y561125D01*
X108617Y560875D01*
X108783Y560667D01*
X109617Y560250D01*
X109992Y559959D01*
X110242Y559542D01*
X110325Y559167D01*
X108575D01*
G01X107142Y561250D02*
X106892Y561500D01*
X106600Y561625D01*
X106267Y561667D01*
X105850Y561584D01*
X105558Y561375D01*
X105475Y561125D01*
X105517Y560875D01*
X105683Y560667D01*
X106517Y560250D01*
X106892Y559959D01*
X107142Y559542D01*
X107225Y559167D01*
X105475D01*
G01X103476Y562166D02*
Y558166D01*
X96076D01*
G01X116927Y554406D02*
Y556906D01*
X115886D01*
X115552Y556781D01*
X115344Y556614D01*
X115261Y556281D01*
X115344Y555948D01*
X115594Y555739D01*
X115886Y555614D01*
X116927D01*
G01X115886D02*
X115261Y554406D01*
G01X113786Y556489D02*
X113536Y556739D01*
X113244Y556864D01*
X112911Y556906D01*
X112494Y556823D01*
X112202Y556614D01*
X112119Y556364D01*
X112161Y556114D01*
X112327Y555906D01*
X113161Y555489D01*
X113536Y555198D01*
X113786Y554781D01*
X113869Y554406D01*
X112119D01*
G01X110686Y556489D02*
X110436Y556739D01*
X110144Y556864D01*
X109811Y556906D01*
X109394Y556823D01*
X109102Y556614D01*
X109019Y556364D01*
X109061Y556114D01*
X109227Y555906D01*
X110061Y555489D01*
X110436Y555198D01*
X110686Y554781D01*
X110769Y554406D01*
X109019D01*
G01X107711Y554906D02*
X107461Y554614D01*
X107127Y554448D01*
X106752Y554406D01*
X106419Y554448D01*
X106086Y554656D01*
X105877Y554906D01*
X105836Y555156D01*
X105919Y555448D01*
X106211Y555656D01*
X106502Y555739D01*
X106877D01*
G01X106502D02*
X106252Y555864D01*
X106044Y556073D01*
X105961Y556323D01*
X106044Y556573D01*
X106252Y556781D01*
X106627Y556906D01*
X107002Y556864D01*
X107377Y556698D01*
G01X103444Y557240D02*
Y553240D01*
X96044D01*
G01X142251Y568634D02*
X144751D01*
Y569675D01*
X144626Y570009D01*
X144459Y570217D01*
X144126Y570300D01*
X143793Y570217D01*
X143584Y569967D01*
X143459Y569675D01*
Y568634D01*
G01Y569675D02*
X142251Y570300D01*
G01Y572567D02*
X144751D01*
X144251Y572067D01*
G01X142251D02*
Y573067D01*
G01Y576167D02*
X144751D01*
X142959Y574625D01*
Y576709D01*
G01X142626Y577850D02*
X142418Y578100D01*
X142293Y578392D01*
X142251Y578767D01*
X142334Y579142D01*
X142501Y579434D01*
X142793Y579642D01*
X143126Y579684D01*
X143459Y579600D01*
X143668Y579392D01*
X143834Y579100D01*
X143876Y578809D01*
X143834Y578517D01*
X143668Y578142D01*
X144751Y578267D01*
Y579392D01*
G01X150533Y580617D02*
Y583117D01*
X149492D01*
X149158Y582992D01*
X148950Y582825D01*
X148867Y582492D01*
X148950Y582159D01*
X149200Y581950D01*
X149492Y581825D01*
X150533D01*
G01X149492D02*
X148867Y580617D01*
G01X147517Y581117D02*
X147267Y580825D01*
X146933Y580659D01*
X146558Y580617D01*
X146225Y580659D01*
X145892Y580867D01*
X145683Y581117D01*
X145642Y581367D01*
X145725Y581659D01*
X146017Y581867D01*
X146308Y581950D01*
X146683D01*
G01X146308D02*
X146058Y582075D01*
X145850Y582284D01*
X145767Y582534D01*
X145850Y582784D01*
X146058Y582992D01*
X146433Y583117D01*
X146808Y583075D01*
X147183Y582909D01*
G01X143500Y580617D02*
Y583117D01*
X144000Y582617D01*
G01Y580617D02*
X143000D01*
G01X140400D02*
X140108Y580659D01*
X139775Y580784D01*
X139567Y580992D01*
X139483Y581284D01*
X139567Y581575D01*
X139817Y581825D01*
X140192Y581950D01*
X140608D01*
X140858Y582034D01*
X141067Y582242D01*
X141150Y582534D01*
X141025Y582825D01*
X140733Y583034D01*
X140400Y583117D01*
X140067Y583034D01*
X139775Y582825D01*
X139650Y582534D01*
X139733Y582242D01*
X139942Y582034D01*
X140192Y581950D01*
X140608D01*
X140983Y581825D01*
X141233Y581575D01*
X141317Y581284D01*
X141233Y580992D01*
X141025Y580784D01*
X140692Y580659D01*
X140400Y580617D01*
G01X151500Y546067D02*
Y543567D01*
G01X152458Y546067D02*
X150542D01*
G01X149233Y543567D02*
Y546067D01*
X148233D01*
X147900Y545942D01*
X147650Y545650D01*
X147567Y545317D01*
X147650Y544984D01*
X147858Y544734D01*
X148233Y544609D01*
X149233D01*
G01X145300Y543567D02*
Y546067D01*
X145800Y545567D01*
G01Y543567D02*
X144800D01*
G01X142283D02*
X142200Y544109D01*
X142075Y544567D01*
X141908Y544984D01*
X141700Y545442D01*
X141367Y546067D01*
X143033D01*
G01X115757Y536783D02*
X116007Y536908D01*
X116299Y536991D01*
X116632D01*
X117007Y536866D01*
X117299Y536658D01*
X117507Y536408D01*
X117674Y535991D01*
X117716Y535616D01*
X117632Y535241D01*
X117507Y534991D01*
X117257Y534741D01*
X116966Y534574D01*
X116674Y534491D01*
X116382D01*
X116091Y534574D01*
X115841Y534699D01*
X115632Y534866D01*
G01X114366Y535533D02*
X114074Y535824D01*
X113824Y535991D01*
X113491Y536074D01*
X113199Y535991D01*
X112991Y535824D01*
X112824Y535574D01*
X112782Y535283D01*
X112824Y535033D01*
X112991Y534783D01*
X113241Y534574D01*
X113532Y534491D01*
X113866Y534574D01*
X114157Y534824D01*
X114324Y535199D01*
X114366Y535616D01*
X114282Y536158D01*
X114157Y536449D01*
X113949Y536741D01*
X113657Y536949D01*
X113366Y536991D01*
X113074Y536908D01*
X112866Y536699D01*
G01X109974Y534491D02*
Y536991D01*
X111516Y535199D01*
X109432D01*
G01X128182Y549152D02*
X128307Y548902D01*
X128390Y548610D01*
Y548277D01*
X128265Y547902D01*
X128057Y547610D01*
X127807Y547402D01*
X127390Y547235D01*
X127015Y547193D01*
X126640Y547277D01*
X126390Y547402D01*
X126140Y547652D01*
X125973Y547943D01*
X125890Y548235D01*
Y548527D01*
X125973Y548818D01*
X126098Y549068D01*
X126265Y549277D01*
G01X126182Y550627D02*
X125973Y550918D01*
X125890Y551252D01*
X125973Y551585D01*
X126223Y551877D01*
X126598Y552085D01*
X126973Y552168D01*
X127432D01*
X127807Y552085D01*
X128140Y551877D01*
X128307Y551627D01*
X128390Y551335D01*
X128307Y551002D01*
X128140Y550752D01*
X127890Y550585D01*
X127557Y550502D01*
X127265Y550585D01*
X126973Y550793D01*
X126807Y551043D01*
X126765Y551335D01*
X126848Y551668D01*
X127057Y551918D01*
X127432Y552168D01*
G01X126182Y553727D02*
X125973Y554018D01*
X125890Y554352D01*
X125973Y554685D01*
X126223Y554977D01*
X126598Y555185D01*
X126973Y555268D01*
X127432D01*
X127807Y555185D01*
X128140Y554977D01*
X128307Y554727D01*
X128390Y554435D01*
X128307Y554102D01*
X128140Y553852D01*
X127890Y553685D01*
X127557Y553602D01*
X127265Y553685D01*
X126973Y553893D01*
X126807Y554143D01*
X126765Y554435D01*
X126848Y554768D01*
X127057Y555018D01*
X127432Y555268D01*
G01X132837Y549183D02*
X132962Y548933D01*
X133045Y548641D01*
Y548308D01*
X132920Y547933D01*
X132712Y547641D01*
X132462Y547433D01*
X132045Y547266D01*
X131670Y547224D01*
X131295Y547308D01*
X131045Y547433D01*
X130795Y547683D01*
X130628Y547974D01*
X130545Y548266D01*
Y548558D01*
X130628Y548849D01*
X130753Y549099D01*
X130920Y549308D01*
G01X130837Y550658D02*
X130628Y550949D01*
X130545Y551283D01*
X130628Y551616D01*
X130878Y551908D01*
X131253Y552116D01*
X131628Y552199D01*
X132087D01*
X132462Y552116D01*
X132795Y551908D01*
X132962Y551658D01*
X133045Y551366D01*
X132962Y551033D01*
X132795Y550783D01*
X132545Y550616D01*
X132212Y550533D01*
X131920Y550616D01*
X131628Y550824D01*
X131462Y551074D01*
X131420Y551366D01*
X131503Y551699D01*
X131712Y551949D01*
X132087Y552199D01*
G01X130545Y554383D02*
X131087Y554466D01*
X131545Y554591D01*
X131962Y554758D01*
X132420Y554966D01*
X133045Y555299D01*
Y553633D01*
G01X105459Y588717D02*
X105584Y588467D01*
X105667Y588175D01*
Y587842D01*
X105542Y587467D01*
X105334Y587175D01*
X105084Y586967D01*
X104667Y586800D01*
X104292Y586758D01*
X103917Y586842D01*
X103667Y586967D01*
X103417Y587217D01*
X103250Y587508D01*
X103167Y587800D01*
Y588092D01*
X103250Y588383D01*
X103375Y588633D01*
X103542Y588842D01*
G01X103459Y590192D02*
X103250Y590483D01*
X103167Y590817D01*
X103250Y591150D01*
X103500Y591442D01*
X103875Y591650D01*
X104250Y591733D01*
X104709D01*
X105084Y591650D01*
X105417Y591442D01*
X105584Y591192D01*
X105667Y590900D01*
X105584Y590567D01*
X105417Y590317D01*
X105167Y590150D01*
X104834Y590067D01*
X104542Y590150D01*
X104250Y590358D01*
X104084Y590608D01*
X104042Y590900D01*
X104125Y591233D01*
X104334Y591483D01*
X104709Y591733D01*
G01X105250Y593208D02*
X105500Y593458D01*
X105625Y593750D01*
X105667Y594083D01*
X105584Y594500D01*
X105375Y594792D01*
X105125Y594875D01*
X104875Y594833D01*
X104667Y594667D01*
X104250Y593833D01*
X103959Y593458D01*
X103542Y593208D01*
X103167Y593125D01*
Y594875D01*
G01X129929Y572658D02*
X130054Y572408D01*
X130137Y572116D01*
Y571783D01*
X130012Y571408D01*
X129804Y571116D01*
X129554Y570908D01*
X129137Y570741D01*
X128762Y570699D01*
X128387Y570783D01*
X128137Y570908D01*
X127887Y571158D01*
X127720Y571449D01*
X127637Y571741D01*
Y572033D01*
X127720Y572324D01*
X127845Y572574D01*
X128012Y572783D01*
G01X128679Y574049D02*
X128970Y574341D01*
X129137Y574591D01*
X129220Y574924D01*
X129137Y575216D01*
X128970Y575424D01*
X128720Y575591D01*
X128429Y575633D01*
X128179Y575591D01*
X127929Y575424D01*
X127720Y575174D01*
X127637Y574883D01*
X127720Y574549D01*
X127970Y574258D01*
X128345Y574091D01*
X128762Y574049D01*
X129304Y574133D01*
X129595Y574258D01*
X129887Y574466D01*
X130095Y574758D01*
X130137Y575049D01*
X130054Y575341D01*
X129845Y575549D01*
G01X130137Y577941D02*
X130054Y577608D01*
X129845Y577358D01*
X129595Y577191D01*
X129262Y577066D01*
X128887Y577024D01*
X128512Y577066D01*
X128179Y577191D01*
X127929Y577358D01*
X127720Y577608D01*
X127637Y577941D01*
X127720Y578274D01*
X127929Y578524D01*
X128179Y578691D01*
X128512Y578816D01*
X128887Y578858D01*
X129262Y578816D01*
X129595Y578691D01*
X129845Y578524D01*
X130054Y578274D01*
X130137Y577941D01*
G01X134609Y572558D02*
X134734Y572308D01*
X134817Y572016D01*
Y571683D01*
X134692Y571308D01*
X134484Y571016D01*
X134234Y570808D01*
X133817Y570641D01*
X133442Y570599D01*
X133067Y570683D01*
X132817Y570808D01*
X132567Y571058D01*
X132400Y571349D01*
X132317Y571641D01*
Y571933D01*
X132400Y572224D01*
X132525Y572474D01*
X132692Y572683D01*
G01Y573824D02*
X132484Y574074D01*
X132359Y574366D01*
X132317Y574741D01*
X132400Y575116D01*
X132567Y575408D01*
X132859Y575616D01*
X133192Y575658D01*
X133525Y575574D01*
X133734Y575366D01*
X133900Y575074D01*
X133942Y574783D01*
X133900Y574491D01*
X133734Y574116D01*
X134817Y574241D01*
Y575366D01*
G01X132609Y577133D02*
X132400Y577424D01*
X132317Y577758D01*
X132400Y578091D01*
X132650Y578383D01*
X133025Y578591D01*
X133400Y578674D01*
X133859D01*
X134234Y578591D01*
X134567Y578383D01*
X134734Y578133D01*
X134817Y577841D01*
X134734Y577508D01*
X134567Y577258D01*
X134317Y577091D01*
X133984Y577008D01*
X133692Y577091D01*
X133400Y577299D01*
X133234Y577549D01*
X133192Y577841D01*
X133275Y578174D01*
X133484Y578424D01*
X133859Y578674D01*
G01X139299Y572590D02*
X139424Y572340D01*
X139507Y572048D01*
Y571715D01*
X139382Y571340D01*
X139174Y571048D01*
X138924Y570840D01*
X138507Y570673D01*
X138132Y570631D01*
X137757Y570715D01*
X137507Y570840D01*
X137257Y571090D01*
X137090Y571381D01*
X137007Y571673D01*
Y571965D01*
X137090Y572256D01*
X137215Y572506D01*
X137382Y572715D01*
G01Y573856D02*
X137174Y574106D01*
X137049Y574398D01*
X137007Y574773D01*
X137090Y575148D01*
X137257Y575440D01*
X137549Y575648D01*
X137882Y575690D01*
X138215Y575606D01*
X138424Y575398D01*
X138590Y575106D01*
X138632Y574815D01*
X138590Y574523D01*
X138424Y574148D01*
X139507Y574273D01*
Y575398D01*
G01X137007Y577873D02*
X137049Y578165D01*
X137174Y578498D01*
X137382Y578706D01*
X137674Y578790D01*
X137965Y578706D01*
X138215Y578456D01*
X138340Y578081D01*
Y577665D01*
X138424Y577415D01*
X138632Y577206D01*
X138924Y577123D01*
X139215Y577248D01*
X139424Y577540D01*
X139507Y577873D01*
X139424Y578206D01*
X139215Y578498D01*
X138924Y578623D01*
X138632Y578540D01*
X138424Y578331D01*
X138340Y578081D01*
Y577665D01*
X138215Y577290D01*
X137965Y577040D01*
X137674Y576956D01*
X137382Y577040D01*
X137174Y577248D01*
X137049Y577581D01*
X137007Y577873D01*
G01X117481Y590804D02*
X117606Y590554D01*
X117689Y590262D01*
Y589929D01*
X117564Y589554D01*
X117356Y589262D01*
X117106Y589054D01*
X116689Y588887D01*
X116314Y588845D01*
X115939Y588929D01*
X115689Y589054D01*
X115439Y589304D01*
X115272Y589595D01*
X115189Y589887D01*
Y590179D01*
X115272Y590470D01*
X115397Y590720D01*
X115564Y590929D01*
G01Y592070D02*
X115356Y592320D01*
X115231Y592612D01*
X115189Y592987D01*
X115272Y593362D01*
X115439Y593654D01*
X115731Y593862D01*
X116064Y593904D01*
X116397Y593820D01*
X116606Y593612D01*
X116772Y593320D01*
X116814Y593029D01*
X116772Y592737D01*
X116606Y592362D01*
X117689Y592487D01*
Y593612D01*
G01X115189Y596587D02*
X117689D01*
X115897Y595045D01*
Y597129D01*
G01X123379Y547553D02*
X123504Y547303D01*
X123587Y547011D01*
Y546678D01*
X123462Y546303D01*
X123254Y546011D01*
X123004Y545803D01*
X122587Y545636D01*
X122212Y545594D01*
X121837Y545678D01*
X121587Y545803D01*
X121337Y546053D01*
X121170Y546344D01*
X121087Y546636D01*
Y546928D01*
X121170Y547219D01*
X121295Y547469D01*
X121462Y547678D01*
G01X121087Y549736D02*
X123587D01*
X123087Y549236D01*
G01X121087D02*
Y550236D01*
G01X123587Y552836D02*
X123504Y552503D01*
X123295Y552253D01*
X123045Y552086D01*
X122712Y551961D01*
X122337Y551919D01*
X121962Y551961D01*
X121629Y552086D01*
X121379Y552253D01*
X121170Y552503D01*
X121087Y552836D01*
X121170Y553169D01*
X121379Y553419D01*
X121629Y553586D01*
X121962Y553711D01*
X122337Y553753D01*
X122712Y553711D01*
X123045Y553586D01*
X123295Y553419D01*
X123504Y553169D01*
X123587Y552836D01*
G01X121087Y556436D02*
X123587D01*
X121795Y554894D01*
Y556978D01*
G01X101717Y590817D02*
X99217D01*
Y592483D01*
G01X99717Y593833D02*
X99425Y594083D01*
X99259Y594417D01*
X99217Y594792D01*
X99259Y595125D01*
X99467Y595458D01*
X99717Y595667D01*
X99967Y595708D01*
X100259Y595625D01*
X100467Y595333D01*
X100550Y595042D01*
Y594667D01*
G01Y595042D02*
X100675Y595292D01*
X100884Y595500D01*
X101134Y595583D01*
X101384Y595500D01*
X101592Y595292D01*
X101717Y594917D01*
X101675Y594542D01*
X101509Y594167D01*
G01X126100Y600300D02*
X119100D01*
Y586900D01*
X126100D01*
Y600300D01*
G01X132733Y638792D02*
X132983Y638917D01*
X133275Y639000D01*
X133608D01*
X133983Y638875D01*
X134275Y638667D01*
X134483Y638417D01*
X134650Y638000D01*
X134692Y637625D01*
X134608Y637250D01*
X134483Y637000D01*
X134233Y636750D01*
X133942Y636583D01*
X133650Y636500D01*
X133358D01*
X133067Y636583D01*
X132817Y636708D01*
X132608Y636875D01*
G01X130550Y636500D02*
Y639000D01*
X131050Y638500D01*
G01Y636500D02*
X130050D01*
G01X127450Y639000D02*
X127783Y638917D01*
X128033Y638708D01*
X128200Y638458D01*
X128325Y638125D01*
X128367Y637750D01*
X128325Y637375D01*
X128200Y637042D01*
X128033Y636792D01*
X127783Y636583D01*
X127450Y636500D01*
X127117Y636583D01*
X126867Y636792D01*
X126700Y637042D01*
X126575Y637375D01*
X126533Y637750D01*
X126575Y638125D01*
X126700Y638458D01*
X126867Y638708D01*
X127117Y638917D01*
X127450Y639000D01*
G01X125267Y637000D02*
X125017Y636708D01*
X124683Y636542D01*
X124308Y636500D01*
X123975Y636542D01*
X123642Y636750D01*
X123433Y637000D01*
X123392Y637250D01*
X123475Y637542D01*
X123767Y637750D01*
X124058Y637833D01*
X124433D01*
G01X124058D02*
X123808Y637958D01*
X123600Y638167D01*
X123517Y638417D01*
X123600Y638667D01*
X123808Y638875D01*
X124183Y639000D01*
X124558Y638958D01*
X124933Y638792D01*
G01X133433Y632492D02*
X133683Y632617D01*
X133975Y632700D01*
X134308D01*
X134683Y632575D01*
X134975Y632367D01*
X135183Y632117D01*
X135350Y631700D01*
X135392Y631325D01*
X135308Y630950D01*
X135183Y630700D01*
X134933Y630450D01*
X134642Y630283D01*
X134350Y630200D01*
X134058D01*
X133767Y630283D01*
X133517Y630408D01*
X133308Y630575D01*
G01X131250Y630200D02*
Y632700D01*
X131750Y632200D01*
G01Y630200D02*
X130750D01*
G01X128150Y632700D02*
X128483Y632617D01*
X128733Y632408D01*
X128900Y632158D01*
X129025Y631825D01*
X129067Y631450D01*
X129025Y631075D01*
X128900Y630742D01*
X128733Y630492D01*
X128483Y630283D01*
X128150Y630200D01*
X127817Y630283D01*
X127567Y630492D01*
X127400Y630742D01*
X127275Y631075D01*
X127233Y631450D01*
X127275Y631825D01*
X127400Y632158D01*
X127567Y632408D01*
X127817Y632617D01*
X128150Y632700D01*
G01X125967Y630575D02*
X125717Y630367D01*
X125425Y630242D01*
X125050Y630200D01*
X124675Y630283D01*
X124383Y630450D01*
X124175Y630742D01*
X124133Y631075D01*
X124217Y631408D01*
X124425Y631617D01*
X124717Y631783D01*
X125008Y631825D01*
X125300Y631783D01*
X125675Y631617D01*
X125550Y632700D01*
X124425D01*
G01X146183Y638792D02*
X146433Y638917D01*
X146725Y639000D01*
X147058D01*
X147433Y638875D01*
X147725Y638667D01*
X147933Y638417D01*
X148100Y638000D01*
X148142Y637625D01*
X148058Y637250D01*
X147933Y637000D01*
X147683Y636750D01*
X147392Y636583D01*
X147100Y636500D01*
X146808D01*
X146517Y636583D01*
X146267Y636708D01*
X146058Y636875D01*
G01X144708Y636792D02*
X144417Y636583D01*
X144083Y636500D01*
X143750Y636583D01*
X143458Y636833D01*
X143250Y637208D01*
X143167Y637583D01*
Y638042D01*
X143250Y638417D01*
X143458Y638750D01*
X143708Y638917D01*
X144000Y639000D01*
X144333Y638917D01*
X144583Y638750D01*
X144750Y638500D01*
X144833Y638167D01*
X144750Y637875D01*
X144542Y637583D01*
X144292Y637417D01*
X144000Y637375D01*
X143667Y637458D01*
X143417Y637667D01*
X143167Y638042D01*
G01X140900Y636500D02*
Y639000D01*
X141400Y638500D01*
G01Y636500D02*
X140400D01*
G01X146183Y647292D02*
X146433Y647417D01*
X146725Y647500D01*
X147058D01*
X147433Y647375D01*
X147725Y647167D01*
X147933Y646917D01*
X148100Y646500D01*
X148142Y646125D01*
X148058Y645750D01*
X147933Y645500D01*
X147683Y645250D01*
X147392Y645083D01*
X147100Y645000D01*
X146808D01*
X146517Y645083D01*
X146267Y645208D01*
X146058Y645375D01*
G01X144000Y645000D02*
X143708Y645042D01*
X143375Y645167D01*
X143167Y645375D01*
X143083Y645667D01*
X143167Y645958D01*
X143417Y646208D01*
X143792Y646333D01*
X144208D01*
X144458Y646417D01*
X144667Y646625D01*
X144750Y646917D01*
X144625Y647208D01*
X144333Y647417D01*
X144000Y647500D01*
X143667Y647417D01*
X143375Y647208D01*
X143250Y646917D01*
X143333Y646625D01*
X143542Y646417D01*
X143792Y646333D01*
X144208D01*
X144583Y646208D01*
X144833Y645958D01*
X144917Y645667D01*
X144833Y645375D01*
X144625Y645167D01*
X144292Y645042D01*
X144000Y645000D01*
G01X141608Y645292D02*
X141317Y645083D01*
X140983Y645000D01*
X140650Y645083D01*
X140358Y645333D01*
X140150Y645708D01*
X140067Y646083D01*
Y646542D01*
X140150Y646917D01*
X140358Y647250D01*
X140608Y647417D01*
X140900Y647500D01*
X141233Y647417D01*
X141483Y647250D01*
X141650Y647000D01*
X141733Y646667D01*
X141650Y646375D01*
X141442Y646083D01*
X141192Y645917D01*
X140900Y645875D01*
X140567Y645958D01*
X140317Y646167D01*
X140067Y646542D01*
G01X149443Y655815D02*
Y658315D01*
X148402D01*
X148068Y658190D01*
X147860Y658023D01*
X147777Y657690D01*
X147860Y657357D01*
X148110Y657148D01*
X148402Y657023D01*
X149443D01*
G01X148402D02*
X147777Y655815D01*
G01X146427Y656315D02*
X146177Y656023D01*
X145843Y655857D01*
X145468Y655815D01*
X145135Y655857D01*
X144802Y656065D01*
X144593Y656315D01*
X144552Y656565D01*
X144635Y656857D01*
X144927Y657065D01*
X145218Y657148D01*
X145593D01*
G01X145218D02*
X144968Y657273D01*
X144760Y657482D01*
X144677Y657732D01*
X144760Y657982D01*
X144968Y658190D01*
X145343Y658315D01*
X145718Y658273D01*
X146093Y658107D01*
G01X143202Y657898D02*
X142952Y658148D01*
X142660Y658273D01*
X142327Y658315D01*
X141910Y658232D01*
X141618Y658023D01*
X141535Y657773D01*
X141577Y657523D01*
X141743Y657315D01*
X142577Y656898D01*
X142952Y656607D01*
X143202Y656190D01*
X143285Y655815D01*
X141535D01*
G01X138810D02*
Y658315D01*
X140352Y656523D01*
X138268D01*
G01X135167Y617517D02*
X137667D01*
Y618558D01*
X137542Y618892D01*
X137375Y619100D01*
X137042Y619183D01*
X136709Y619100D01*
X136500Y618850D01*
X136375Y618558D01*
Y617517D01*
G01Y618558D02*
X135167Y619183D01*
G01X135667Y620533D02*
X135375Y620783D01*
X135209Y621117D01*
X135167Y621492D01*
X135209Y621825D01*
X135417Y622158D01*
X135667Y622367D01*
X135917Y622408D01*
X136209Y622325D01*
X136417Y622033D01*
X136500Y621742D01*
Y621367D01*
G01Y621742D02*
X136625Y621992D01*
X136834Y622200D01*
X137084Y622283D01*
X137334Y622200D01*
X137542Y621992D01*
X137667Y621617D01*
X137625Y621242D01*
X137459Y620867D01*
G01X135167Y624550D02*
X137667D01*
X137167Y624050D01*
G01X135167D02*
Y625050D01*
G01X136209Y626858D02*
X136500Y627150D01*
X136667Y627400D01*
X136750Y627733D01*
X136667Y628025D01*
X136500Y628233D01*
X136250Y628400D01*
X135959Y628442D01*
X135709Y628400D01*
X135459Y628233D01*
X135250Y627983D01*
X135167Y627692D01*
X135250Y627358D01*
X135500Y627067D01*
X135875Y626900D01*
X136292Y626858D01*
X136834Y626942D01*
X137125Y627067D01*
X137417Y627275D01*
X137625Y627567D01*
X137667Y627858D01*
X137584Y628150D01*
X137375Y628358D01*
G01X134276Y655603D02*
Y658103D01*
X133235D01*
X132901Y657978D01*
X132693Y657811D01*
X132610Y657478D01*
X132693Y657145D01*
X132943Y656936D01*
X133235Y656811D01*
X134276D01*
G01X133235D02*
X132610Y655603D01*
G01X131260Y656103D02*
X131010Y655811D01*
X130676Y655645D01*
X130301Y655603D01*
X129968Y655645D01*
X129635Y655853D01*
X129426Y656103D01*
X129385Y656353D01*
X129468Y656645D01*
X129760Y656853D01*
X130051Y656936D01*
X130426D01*
G01X130051D02*
X129801Y657061D01*
X129593Y657270D01*
X129510Y657520D01*
X129593Y657770D01*
X129801Y657978D01*
X130176Y658103D01*
X130551Y658061D01*
X130926Y657895D01*
G01X127243Y655603D02*
Y658103D01*
X127743Y657603D01*
G01Y655603D02*
X126743D01*
G01X124143D02*
Y658103D01*
X124643Y657603D01*
G01Y655603D02*
X123643D01*
G01X148483Y632000D02*
Y634500D01*
X147442D01*
X147108Y634375D01*
X146900Y634208D01*
X146817Y633875D01*
X146900Y633542D01*
X147150Y633333D01*
X147442Y633208D01*
X148483D01*
G01X147442D02*
X146817Y632000D01*
G01X145467Y632500D02*
X145217Y632208D01*
X144883Y632042D01*
X144508Y632000D01*
X144175Y632042D01*
X143842Y632250D01*
X143633Y632500D01*
X143592Y632750D01*
X143675Y633042D01*
X143967Y633250D01*
X144258Y633333D01*
X144633D01*
G01X144258D02*
X144008Y633458D01*
X143800Y633667D01*
X143717Y633917D01*
X143800Y634167D01*
X144008Y634375D01*
X144383Y634500D01*
X144758Y634458D01*
X145133Y634292D01*
G01X142242Y633042D02*
X141950Y633333D01*
X141700Y633500D01*
X141367Y633583D01*
X141075Y633500D01*
X140867Y633333D01*
X140700Y633083D01*
X140658Y632792D01*
X140700Y632542D01*
X140867Y632292D01*
X141117Y632083D01*
X141408Y632000D01*
X141742Y632083D01*
X142033Y632333D01*
X142200Y632708D01*
X142242Y633125D01*
X142158Y633667D01*
X142033Y633958D01*
X141825Y634250D01*
X141533Y634458D01*
X141242Y634500D01*
X140950Y634417D01*
X140742Y634208D01*
G01X138350Y632000D02*
X138058Y632042D01*
X137725Y632167D01*
X137517Y632375D01*
X137433Y632667D01*
X137517Y632958D01*
X137767Y633208D01*
X138142Y633333D01*
X138558D01*
X138808Y633417D01*
X139017Y633625D01*
X139100Y633917D01*
X138975Y634208D01*
X138683Y634417D01*
X138350Y634500D01*
X138017Y634417D01*
X137725Y634208D01*
X137600Y633917D01*
X137683Y633625D01*
X137892Y633417D01*
X138142Y633333D01*
X138558D01*
X138933Y633208D01*
X139183Y632958D01*
X139267Y632667D01*
X139183Y632375D01*
X138975Y632167D01*
X138642Y632042D01*
X138350Y632000D01*
G01X143583Y606367D02*
Y608867D01*
X142542D01*
X142208Y608742D01*
X142000Y608575D01*
X141917Y608242D01*
X142000Y607909D01*
X142250Y607700D01*
X142542Y607575D01*
X143583D01*
G01X142542D02*
X141917Y606367D01*
G01X140567Y606867D02*
X140317Y606575D01*
X139983Y606409D01*
X139608Y606367D01*
X139275Y606409D01*
X138942Y606617D01*
X138733Y606867D01*
X138692Y607117D01*
X138775Y607409D01*
X139067Y607617D01*
X139358Y607700D01*
X139733D01*
G01X139358D02*
X139108Y607825D01*
X138900Y608034D01*
X138817Y608284D01*
X138900Y608534D01*
X139108Y608742D01*
X139483Y608867D01*
X139858Y608825D01*
X140233Y608659D01*
G01X137467Y606867D02*
X137217Y606575D01*
X136883Y606409D01*
X136508Y606367D01*
X136175Y606409D01*
X135842Y606617D01*
X135633Y606867D01*
X135592Y607117D01*
X135675Y607409D01*
X135967Y607617D01*
X136258Y607700D01*
X136633D01*
G01X136258D02*
X136008Y607825D01*
X135800Y608034D01*
X135717Y608284D01*
X135800Y608534D01*
X136008Y608742D01*
X136383Y608867D01*
X136758Y608825D01*
X137133Y608659D01*
G01X134242Y607409D02*
X133950Y607700D01*
X133700Y607867D01*
X133367Y607950D01*
X133075Y607867D01*
X132867Y607700D01*
X132700Y607450D01*
X132658Y607159D01*
X132700Y606909D01*
X132867Y606659D01*
X133117Y606450D01*
X133408Y606367D01*
X133742Y606450D01*
X134033Y606700D01*
X134200Y607075D01*
X134242Y607492D01*
X134158Y608034D01*
X134033Y608325D01*
X133825Y608617D01*
X133533Y608825D01*
X133242Y608867D01*
X132950Y608784D01*
X132742Y608575D01*
G01X125092Y600854D02*
Y604854D01*
X132492D01*
G01X130167Y617517D02*
X132667D01*
Y618558D01*
X132542Y618892D01*
X132375Y619100D01*
X132042Y619183D01*
X131709Y619100D01*
X131500Y618850D01*
X131375Y618558D01*
Y617517D01*
G01Y618558D02*
X130167Y619183D01*
G01Y621367D02*
X130709Y621450D01*
X131167Y621575D01*
X131584Y621742D01*
X132042Y621950D01*
X132667Y622283D01*
Y620617D01*
G01X130167Y624550D02*
X130209Y624842D01*
X130334Y625175D01*
X130542Y625383D01*
X130834Y625467D01*
X131125Y625383D01*
X131375Y625133D01*
X131500Y624758D01*
Y624342D01*
X131584Y624092D01*
X131792Y623883D01*
X132084Y623800D01*
X132375Y623925D01*
X132584Y624217D01*
X132667Y624550D01*
X132584Y624883D01*
X132375Y625175D01*
X132084Y625300D01*
X131792Y625217D01*
X131584Y625008D01*
X131500Y624758D01*
Y624342D01*
X131375Y623967D01*
X131125Y623717D01*
X130834Y623633D01*
X130542Y623717D01*
X130334Y623925D01*
X130209Y624258D01*
X130167Y624550D01*
G01X132250Y626858D02*
X132500Y627108D01*
X132625Y627400D01*
X132667Y627733D01*
X132584Y628150D01*
X132375Y628442D01*
X132125Y628525D01*
X131875Y628483D01*
X131667Y628317D01*
X131250Y627483D01*
X130959Y627108D01*
X130542Y626858D01*
X130167Y626775D01*
Y628525D01*
G01X129800Y612700D02*
X125800D01*
Y620100D01*
G01X134685Y651393D02*
Y653893D01*
X133644D01*
X133310Y653768D01*
X133102Y653601D01*
X133019Y653268D01*
X133102Y652935D01*
X133352Y652726D01*
X133644Y652601D01*
X134685D01*
G01X133644D02*
X133019Y651393D01*
G01X131544Y652435D02*
X131252Y652726D01*
X131002Y652893D01*
X130669Y652976D01*
X130377Y652893D01*
X130169Y652726D01*
X130002Y652476D01*
X129960Y652185D01*
X130002Y651935D01*
X130169Y651685D01*
X130419Y651476D01*
X130710Y651393D01*
X131044Y651476D01*
X131335Y651726D01*
X131502Y652101D01*
X131544Y652518D01*
X131460Y653060D01*
X131335Y653351D01*
X131127Y653643D01*
X130835Y653851D01*
X130544Y653893D01*
X130252Y653810D01*
X130044Y653601D01*
G01X128360Y651685D02*
X128069Y651476D01*
X127735Y651393D01*
X127402Y651476D01*
X127110Y651726D01*
X126902Y652101D01*
X126819Y652476D01*
Y652935D01*
X126902Y653310D01*
X127110Y653643D01*
X127360Y653810D01*
X127652Y653893D01*
X127985Y653810D01*
X128235Y653643D01*
X128402Y653393D01*
X128485Y653060D01*
X128402Y652768D01*
X128194Y652476D01*
X127944Y652310D01*
X127652Y652268D01*
X127319Y652351D01*
X127069Y652560D01*
X126819Y652935D01*
G01X124635Y651393D02*
X124552Y651935D01*
X124427Y652393D01*
X124260Y652810D01*
X124052Y653268D01*
X123719Y653893D01*
X125385D01*
G01X144783Y599467D02*
Y601967D01*
X143742D01*
X143408Y601842D01*
X143200Y601675D01*
X143117Y601342D01*
X143200Y601009D01*
X143450Y600800D01*
X143742Y600675D01*
X144783D01*
G01X143742D02*
X143117Y599467D01*
G01X141767Y599967D02*
X141517Y599675D01*
X141183Y599509D01*
X140808Y599467D01*
X140475Y599509D01*
X140142Y599717D01*
X139933Y599967D01*
X139892Y600217D01*
X139975Y600509D01*
X140267Y600717D01*
X140558Y600800D01*
X140933D01*
G01X140558D02*
X140308Y600925D01*
X140100Y601134D01*
X140017Y601384D01*
X140100Y601634D01*
X140308Y601842D01*
X140683Y601967D01*
X141058Y601925D01*
X141433Y601759D01*
G01X138542Y601550D02*
X138292Y601800D01*
X138000Y601925D01*
X137667Y601967D01*
X137250Y601884D01*
X136958Y601675D01*
X136875Y601425D01*
X136917Y601175D01*
X137083Y600967D01*
X137917Y600550D01*
X138292Y600259D01*
X138542Y599842D01*
X138625Y599467D01*
X136875D01*
G01X134650D02*
Y601967D01*
X135150Y601467D01*
G01Y599467D02*
X134150D01*
G01X142000Y612050D02*
X139500D01*
G01X142000Y611092D02*
Y613008D01*
G01X139500Y614317D02*
X142000D01*
Y615317D01*
X141875Y615650D01*
X141583Y615900D01*
X141250Y615983D01*
X140917Y615900D01*
X140667Y615692D01*
X140542Y615317D01*
Y614317D01*
G01Y617458D02*
X140833Y617750D01*
X141000Y618000D01*
X141083Y618333D01*
X141000Y618625D01*
X140833Y618833D01*
X140583Y619000D01*
X140292Y619042D01*
X140042Y619000D01*
X139792Y618833D01*
X139583Y618583D01*
X139500Y618292D01*
X139583Y617958D01*
X139833Y617667D01*
X140208Y617500D01*
X140625Y617458D01*
X141167Y617542D01*
X141458Y617667D01*
X141750Y617875D01*
X141958Y618167D01*
X142000Y618458D01*
X141917Y618750D01*
X141708Y618958D01*
G01X139500Y621850D02*
X142000D01*
X140208Y620308D01*
Y622392D01*
G01X132733Y645292D02*
X132983Y645417D01*
X133275Y645500D01*
X133608D01*
X133983Y645375D01*
X134275Y645167D01*
X134483Y644917D01*
X134650Y644500D01*
X134692Y644125D01*
X134608Y643750D01*
X134483Y643500D01*
X134233Y643250D01*
X133942Y643083D01*
X133650Y643000D01*
X133358D01*
X133067Y643083D01*
X132817Y643208D01*
X132608Y643375D01*
G01X130550Y643000D02*
Y645500D01*
X131050Y645000D01*
G01Y643000D02*
X130050D01*
G01X127450Y645500D02*
X127783Y645417D01*
X128033Y645208D01*
X128200Y644958D01*
X128325Y644625D01*
X128367Y644250D01*
X128325Y643875D01*
X128200Y643542D01*
X128033Y643292D01*
X127783Y643083D01*
X127450Y643000D01*
X127117Y643083D01*
X126867Y643292D01*
X126700Y643542D01*
X126575Y643875D01*
X126533Y644250D01*
X126575Y644625D01*
X126700Y644958D01*
X126867Y645208D01*
X127117Y645417D01*
X127450Y645500D01*
G01X125142Y645083D02*
X124892Y645333D01*
X124600Y645458D01*
X124267Y645500D01*
X123850Y645417D01*
X123558Y645208D01*
X123475Y644958D01*
X123517Y644708D01*
X123683Y644500D01*
X124517Y644083D01*
X124892Y643792D01*
X125142Y643375D01*
X125225Y643000D01*
X123475D01*
G01X146683Y643292D02*
X146933Y643417D01*
X147225Y643500D01*
X147558D01*
X147933Y643375D01*
X148225Y643167D01*
X148433Y642917D01*
X148600Y642500D01*
X148642Y642125D01*
X148558Y641750D01*
X148433Y641500D01*
X148183Y641250D01*
X147892Y641083D01*
X147600Y641000D01*
X147308D01*
X147017Y641083D01*
X146767Y641208D01*
X146558Y641375D01*
G01X145208Y641292D02*
X144917Y641083D01*
X144583Y641000D01*
X144250Y641083D01*
X143958Y641333D01*
X143750Y641708D01*
X143667Y642083D01*
Y642542D01*
X143750Y642917D01*
X143958Y643250D01*
X144208Y643417D01*
X144500Y643500D01*
X144833Y643417D01*
X145083Y643250D01*
X145250Y643000D01*
X145333Y642667D01*
X145250Y642375D01*
X145042Y642083D01*
X144792Y641917D01*
X144500Y641875D01*
X144167Y641958D01*
X143917Y642167D01*
X143667Y642542D01*
G01X141400Y643500D02*
X141733Y643417D01*
X141983Y643208D01*
X142150Y642958D01*
X142275Y642625D01*
X142317Y642250D01*
X142275Y641875D01*
X142150Y641542D01*
X141983Y641292D01*
X141733Y641083D01*
X141400Y641000D01*
X141067Y641083D01*
X140817Y641292D01*
X140650Y641542D01*
X140525Y641875D01*
X140483Y642250D01*
X140525Y642625D01*
X140650Y642958D01*
X140817Y643208D01*
X141067Y643417D01*
X141400Y643500D01*
G01X134683Y649800D02*
Y647300D01*
X133017D01*
G01X131667Y647675D02*
X131417Y647467D01*
X131125Y647342D01*
X130750Y647300D01*
X130375Y647383D01*
X130083Y647550D01*
X129875Y647842D01*
X129833Y648175D01*
X129917Y648508D01*
X130125Y648717D01*
X130417Y648883D01*
X130708Y648925D01*
X131000Y648883D01*
X131375Y648717D01*
X131250Y649800D01*
X130125D01*
G01X103233Y717459D02*
X103483Y717584D01*
X103775Y717667D01*
X104108D01*
X104483Y717542D01*
X104775Y717334D01*
X104983Y717084D01*
X105150Y716667D01*
X105192Y716292D01*
X105108Y715917D01*
X104983Y715667D01*
X104733Y715417D01*
X104442Y715250D01*
X104150Y715167D01*
X103858D01*
X103567Y715250D01*
X103317Y715375D01*
X103108Y715542D01*
G01X101050Y715167D02*
Y717667D01*
X101550Y717167D01*
G01Y715167D02*
X100550D01*
G01X98033D02*
X97950Y715709D01*
X97825Y716167D01*
X97658Y716584D01*
X97450Y717042D01*
X97117Y717667D01*
X98783D01*
G01X95558Y715459D02*
X95267Y715250D01*
X94933Y715167D01*
X94600Y715250D01*
X94308Y715500D01*
X94100Y715875D01*
X94017Y716250D01*
Y716709D01*
X94100Y717084D01*
X94308Y717417D01*
X94558Y717584D01*
X94850Y717667D01*
X95183Y717584D01*
X95433Y717417D01*
X95600Y717167D01*
X95683Y716834D01*
X95600Y716542D01*
X95392Y716250D01*
X95142Y716084D01*
X94850Y716042D01*
X94517Y716125D01*
X94267Y716334D01*
X94017Y716709D01*
G01X104983Y719167D02*
Y721667D01*
X103942D01*
X103608Y721542D01*
X103400Y721375D01*
X103317Y721042D01*
X103400Y720709D01*
X103650Y720500D01*
X103942Y720375D01*
X104983D01*
G01X103942D02*
X103317Y719167D01*
G01X100550D02*
Y721667D01*
X102092Y719875D01*
X100008D01*
G01X97950Y719167D02*
X97658Y719209D01*
X97325Y719334D01*
X97117Y719542D01*
X97033Y719834D01*
X97117Y720125D01*
X97367Y720375D01*
X97742Y720500D01*
X98158D01*
X98408Y720584D01*
X98617Y720792D01*
X98700Y721084D01*
X98575Y721375D01*
X98283Y721584D01*
X97950Y721667D01*
X97617Y721584D01*
X97325Y721375D01*
X97200Y721084D01*
X97283Y720792D01*
X97492Y720584D01*
X97742Y720500D01*
X98158D01*
X98533Y720375D01*
X98783Y720125D01*
X98867Y719834D01*
X98783Y719542D01*
X98575Y719334D01*
X98242Y719209D01*
X97950Y719167D01*
G01X95767Y719667D02*
X95517Y719375D01*
X95183Y719209D01*
X94808Y719167D01*
X94475Y719209D01*
X94142Y719417D01*
X93933Y719667D01*
X93892Y719917D01*
X93975Y720209D01*
X94267Y720417D01*
X94558Y720500D01*
X94933D01*
G01X94558D02*
X94308Y720625D01*
X94100Y720834D01*
X94017Y721084D01*
X94100Y721334D01*
X94308Y721542D01*
X94683Y721667D01*
X95058Y721625D01*
X95433Y721459D01*
G01X168498Y458957D02*
Y461457D01*
X167457D01*
X167123Y461332D01*
X166915Y461165D01*
X166832Y460832D01*
X166915Y460499D01*
X167165Y460290D01*
X167457Y460165D01*
X168498D01*
G01X167457D02*
X166832Y458957D01*
G01X165482Y459457D02*
X165232Y459165D01*
X164898Y458999D01*
X164523Y458957D01*
X164190Y458999D01*
X163857Y459207D01*
X163648Y459457D01*
X163607Y459707D01*
X163690Y459999D01*
X163982Y460207D01*
X164273Y460290D01*
X164648D01*
G01X164273D02*
X164023Y460415D01*
X163815Y460624D01*
X163732Y460874D01*
X163815Y461124D01*
X164023Y461332D01*
X164398Y461457D01*
X164773Y461415D01*
X165148Y461249D01*
G01X162382Y459457D02*
X162132Y459165D01*
X161798Y458999D01*
X161423Y458957D01*
X161090Y458999D01*
X160757Y459207D01*
X160548Y459457D01*
X160507Y459707D01*
X160590Y459999D01*
X160882Y460207D01*
X161173Y460290D01*
X161548D01*
G01X161173D02*
X160923Y460415D01*
X160715Y460624D01*
X160632Y460874D01*
X160715Y461124D01*
X160923Y461332D01*
X161298Y461457D01*
X161673Y461415D01*
X162048Y461249D01*
G01X158448Y458957D02*
X158365Y459499D01*
X158240Y459957D01*
X158073Y460374D01*
X157865Y460832D01*
X157532Y461457D01*
X159198D01*
G01X168648Y442238D02*
Y444738D01*
X167607D01*
X167273Y444613D01*
X167065Y444446D01*
X166982Y444113D01*
X167065Y443780D01*
X167315Y443571D01*
X167607Y443446D01*
X168648D01*
G01X167607D02*
X166982Y442238D01*
G01X165632Y442738D02*
X165382Y442446D01*
X165048Y442280D01*
X164673Y442238D01*
X164340Y442280D01*
X164007Y442488D01*
X163798Y442738D01*
X163757Y442988D01*
X163840Y443280D01*
X164132Y443488D01*
X164423Y443571D01*
X164798D01*
G01X164423D02*
X164173Y443696D01*
X163965Y443905D01*
X163882Y444155D01*
X163965Y444405D01*
X164173Y444613D01*
X164548Y444738D01*
X164923Y444696D01*
X165298Y444530D01*
G01X161115Y442238D02*
Y444738D01*
X162657Y442946D01*
X160573D01*
G01X158598Y442238D02*
X158515Y442780D01*
X158390Y443238D01*
X158223Y443655D01*
X158015Y444113D01*
X157682Y444738D01*
X159348D01*
G01X168633Y438100D02*
Y440600D01*
X167592D01*
X167258Y440475D01*
X167050Y440308D01*
X166967Y439975D01*
X167050Y439642D01*
X167300Y439433D01*
X167592Y439308D01*
X168633D01*
G01X167592D02*
X166967Y438100D01*
G01X165617Y438600D02*
X165367Y438308D01*
X165033Y438142D01*
X164658Y438100D01*
X164325Y438142D01*
X163992Y438350D01*
X163783Y438600D01*
X163742Y438850D01*
X163825Y439142D01*
X164117Y439350D01*
X164408Y439433D01*
X164783D01*
G01X164408D02*
X164158Y439558D01*
X163950Y439767D01*
X163867Y440017D01*
X163950Y440267D01*
X164158Y440475D01*
X164533Y440600D01*
X164908Y440558D01*
X165283Y440392D01*
G01X161100Y438100D02*
Y440600D01*
X162642Y438808D01*
X160558D01*
G01X158500Y438100D02*
Y440600D01*
X159000Y440100D01*
G01Y438100D02*
X158000D01*
G01X155100Y462200D02*
Y458200D01*
X147700D01*
G01X168648Y450638D02*
Y453138D01*
X167607D01*
X167273Y453013D01*
X167065Y452846D01*
X166982Y452513D01*
X167065Y452180D01*
X167315Y451971D01*
X167607Y451846D01*
X168648D01*
G01X167607D02*
X166982Y450638D01*
G01X165632Y451138D02*
X165382Y450846D01*
X165048Y450680D01*
X164673Y450638D01*
X164340Y450680D01*
X164007Y450888D01*
X163798Y451138D01*
X163757Y451388D01*
X163840Y451680D01*
X164132Y451888D01*
X164423Y451971D01*
X164798D01*
G01X164423D02*
X164173Y452096D01*
X163965Y452305D01*
X163882Y452555D01*
X163965Y452805D01*
X164173Y453013D01*
X164548Y453138D01*
X164923Y453096D01*
X165298Y452930D01*
G01X162532Y451138D02*
X162282Y450846D01*
X161948Y450680D01*
X161573Y450638D01*
X161240Y450680D01*
X160907Y450888D01*
X160698Y451138D01*
X160657Y451388D01*
X160740Y451680D01*
X161032Y451888D01*
X161323Y451971D01*
X161698D01*
G01X161323D02*
X161073Y452096D01*
X160865Y452305D01*
X160782Y452555D01*
X160865Y452805D01*
X161073Y453013D01*
X161448Y453138D01*
X161823Y453096D01*
X162198Y452930D01*
G01X159223Y450930D02*
X158932Y450721D01*
X158598Y450638D01*
X158265Y450721D01*
X157973Y450971D01*
X157765Y451346D01*
X157682Y451721D01*
Y452180D01*
X157765Y452555D01*
X157973Y452888D01*
X158223Y453055D01*
X158515Y453138D01*
X158848Y453055D01*
X159098Y452888D01*
X159265Y452638D01*
X159348Y452305D01*
X159265Y452013D01*
X159057Y451721D01*
X158807Y451555D01*
X158515Y451513D01*
X158182Y451596D01*
X157932Y451805D01*
X157682Y452180D01*
G01X168618Y446462D02*
Y448962D01*
X167577D01*
X167243Y448837D01*
X167035Y448670D01*
X166952Y448337D01*
X167035Y448004D01*
X167285Y447795D01*
X167577Y447670D01*
X168618D01*
G01X167577D02*
X166952Y446462D01*
G01X165477Y448545D02*
X165227Y448795D01*
X164935Y448920D01*
X164602Y448962D01*
X164185Y448879D01*
X163893Y448670D01*
X163810Y448420D01*
X163852Y448170D01*
X164018Y447962D01*
X164852Y447545D01*
X165227Y447254D01*
X165477Y446837D01*
X165560Y446462D01*
X163810D01*
G01X161585D02*
X161293Y446504D01*
X160960Y446629D01*
X160752Y446837D01*
X160668Y447129D01*
X160752Y447420D01*
X161002Y447670D01*
X161377Y447795D01*
X161793D01*
X162043Y447879D01*
X162252Y448087D01*
X162335Y448379D01*
X162210Y448670D01*
X161918Y448879D01*
X161585Y448962D01*
X161252Y448879D01*
X160960Y448670D01*
X160835Y448379D01*
X160918Y448087D01*
X161127Y447879D01*
X161377Y447795D01*
X161793D01*
X162168Y447670D01*
X162418Y447420D01*
X162502Y447129D01*
X162418Y446837D01*
X162210Y446629D01*
X161877Y446504D01*
X161585Y446462D01*
G01X159402Y446837D02*
X159152Y446629D01*
X158860Y446504D01*
X158485Y446462D01*
X158110Y446545D01*
X157818Y446712D01*
X157610Y447004D01*
X157568Y447337D01*
X157652Y447670D01*
X157860Y447879D01*
X158152Y448045D01*
X158443Y448087D01*
X158735Y448045D01*
X159110Y447879D01*
X158985Y448962D01*
X157860D01*
G01X200783Y456767D02*
Y459267D01*
X199742D01*
X199408Y459142D01*
X199200Y458975D01*
X199117Y458642D01*
X199200Y458309D01*
X199450Y458100D01*
X199742Y457975D01*
X200783D01*
G01X199742D02*
X199117Y456767D01*
G01X197767Y457267D02*
X197517Y456975D01*
X197183Y456809D01*
X196808Y456767D01*
X196475Y456809D01*
X196142Y457017D01*
X195933Y457267D01*
X195892Y457517D01*
X195975Y457809D01*
X196267Y458017D01*
X196558Y458100D01*
X196933D01*
G01X196558D02*
X196308Y458225D01*
X196100Y458434D01*
X196017Y458684D01*
X196100Y458934D01*
X196308Y459142D01*
X196683Y459267D01*
X197058Y459225D01*
X197433Y459059D01*
G01X193250Y456767D02*
Y459267D01*
X194792Y457475D01*
X192708D01*
G01X190150Y456767D02*
Y459267D01*
X191692Y457475D01*
X189608D01*
G01X168548Y454838D02*
Y457338D01*
X167507D01*
X167173Y457213D01*
X166965Y457046D01*
X166882Y456713D01*
X166965Y456380D01*
X167215Y456171D01*
X167507Y456046D01*
X168548D01*
G01X167507D02*
X166882Y454838D01*
G01X165407Y456921D02*
X165157Y457171D01*
X164865Y457296D01*
X164532Y457338D01*
X164115Y457255D01*
X163823Y457046D01*
X163740Y456796D01*
X163782Y456546D01*
X163948Y456338D01*
X164782Y455921D01*
X165157Y455630D01*
X165407Y455213D01*
X165490Y454838D01*
X163740D01*
G01X161515D02*
X161223Y454880D01*
X160890Y455005D01*
X160682Y455213D01*
X160598Y455505D01*
X160682Y455796D01*
X160932Y456046D01*
X161307Y456171D01*
X161723D01*
X161973Y456255D01*
X162182Y456463D01*
X162265Y456755D01*
X162140Y457046D01*
X161848Y457255D01*
X161515Y457338D01*
X161182Y457255D01*
X160890Y457046D01*
X160765Y456755D01*
X160848Y456463D01*
X161057Y456255D01*
X161307Y456171D01*
X161723D01*
X162098Y456046D01*
X162348Y455796D01*
X162432Y455505D01*
X162348Y455213D01*
X162140Y455005D01*
X161807Y454880D01*
X161515Y454838D01*
G01X159207Y456921D02*
X158957Y457171D01*
X158665Y457296D01*
X158332Y457338D01*
X157915Y457255D01*
X157623Y457046D01*
X157540Y456796D01*
X157582Y456546D01*
X157748Y456338D01*
X158582Y455921D01*
X158957Y455630D01*
X159207Y455213D01*
X159290Y454838D01*
X157540D01*
G01X200598Y460938D02*
Y463438D01*
X199557D01*
X199223Y463313D01*
X199015Y463146D01*
X198932Y462813D01*
X199015Y462480D01*
X199265Y462271D01*
X199557Y462146D01*
X200598D01*
G01X199557D02*
X198932Y460938D01*
G01X197582Y461438D02*
X197332Y461146D01*
X196998Y460980D01*
X196623Y460938D01*
X196290Y460980D01*
X195957Y461188D01*
X195748Y461438D01*
X195707Y461688D01*
X195790Y461980D01*
X196082Y462188D01*
X196373Y462271D01*
X196748D01*
G01X196373D02*
X196123Y462396D01*
X195915Y462605D01*
X195832Y462855D01*
X195915Y463105D01*
X196123Y463313D01*
X196498Y463438D01*
X196873Y463396D01*
X197248Y463230D01*
G01X193065Y460938D02*
Y463438D01*
X194607Y461646D01*
X192523D01*
G01X191257Y463021D02*
X191007Y463271D01*
X190715Y463396D01*
X190382Y463438D01*
X189965Y463355D01*
X189673Y463146D01*
X189590Y462896D01*
X189632Y462646D01*
X189798Y462438D01*
X190632Y462021D01*
X191007Y461730D01*
X191257Y461313D01*
X191340Y460938D01*
X189590D01*
G01X183917Y457500D02*
Y455708D01*
X183750Y455333D01*
X183417Y455083D01*
X183000Y455000D01*
X182583Y455083D01*
X182250Y455333D01*
X182083Y455708D01*
Y457500D01*
G01X180692Y457083D02*
X180442Y457333D01*
X180150Y457458D01*
X179817Y457500D01*
X179400Y457417D01*
X179108Y457208D01*
X179025Y456958D01*
X179067Y456708D01*
X179233Y456500D01*
X180067Y456083D01*
X180442Y455792D01*
X180692Y455375D01*
X180775Y455000D01*
X179025D01*
G01X176883D02*
X176800Y455542D01*
X176675Y456000D01*
X176508Y456417D01*
X176300Y456875D01*
X175967Y457500D01*
X177633D01*
G01X200350Y454567D02*
Y452067D01*
G01X201308Y454567D02*
X199392D01*
G01X198083Y452067D02*
Y454567D01*
X197083D01*
X196750Y454442D01*
X196500Y454150D01*
X196417Y453817D01*
X196500Y453484D01*
X196708Y453234D01*
X197083Y453109D01*
X198083D01*
G01X194150Y452067D02*
Y454567D01*
X194650Y454067D01*
G01Y452067D02*
X193650D01*
G01X191758Y452359D02*
X191467Y452150D01*
X191133Y452067D01*
X190800Y452150D01*
X190508Y452400D01*
X190300Y452775D01*
X190217Y453150D01*
Y453609D01*
X190300Y453984D01*
X190508Y454317D01*
X190758Y454484D01*
X191050Y454567D01*
X191383Y454484D01*
X191633Y454317D01*
X191800Y454067D01*
X191883Y453734D01*
X191800Y453442D01*
X191592Y453150D01*
X191342Y452984D01*
X191050Y452942D01*
X190717Y453025D01*
X190467Y453234D01*
X190217Y453609D01*
G01X205156Y498612D02*
X205281Y498362D01*
X205364Y498070D01*
Y497737D01*
X205239Y497362D01*
X205031Y497070D01*
X204781Y496862D01*
X204364Y496695D01*
X203989Y496653D01*
X203614Y496737D01*
X203364Y496862D01*
X203114Y497112D01*
X202947Y497403D01*
X202864Y497695D01*
Y497987D01*
X202947Y498278D01*
X203072Y498528D01*
X203239Y498737D01*
G01Y499878D02*
X203031Y500128D01*
X202906Y500420D01*
X202864Y500795D01*
X202947Y501170D01*
X203114Y501462D01*
X203406Y501670D01*
X203739Y501712D01*
X204072Y501628D01*
X204281Y501420D01*
X204447Y501128D01*
X204489Y500837D01*
X204447Y500545D01*
X204281Y500170D01*
X205364Y500295D01*
Y501420D01*
G01Y503895D02*
X205281Y503562D01*
X205072Y503312D01*
X204822Y503145D01*
X204489Y503020D01*
X204114Y502978D01*
X203739Y503020D01*
X203406Y503145D01*
X203156Y503312D01*
X202947Y503562D01*
X202864Y503895D01*
X202947Y504228D01*
X203156Y504478D01*
X203406Y504645D01*
X203739Y504770D01*
X204114Y504812D01*
X204489Y504770D01*
X204822Y504645D01*
X205072Y504478D01*
X205281Y504228D01*
X205364Y503895D01*
G01X203239Y506078D02*
X203031Y506328D01*
X202906Y506620D01*
X202864Y506995D01*
X202947Y507370D01*
X203114Y507662D01*
X203406Y507870D01*
X203739Y507912D01*
X204072Y507828D01*
X204281Y507620D01*
X204447Y507328D01*
X204489Y507037D01*
X204447Y506745D01*
X204281Y506370D01*
X205364Y506495D01*
Y507620D01*
G01X168383Y486109D02*
X168633Y486234D01*
X168925Y486317D01*
X169258D01*
X169633Y486192D01*
X169925Y485984D01*
X170133Y485734D01*
X170300Y485317D01*
X170342Y484942D01*
X170258Y484567D01*
X170133Y484317D01*
X169883Y484067D01*
X169592Y483900D01*
X169300Y483817D01*
X169008D01*
X168717Y483900D01*
X168467Y484025D01*
X168258Y484192D01*
G01X167117D02*
X166867Y483984D01*
X166575Y483859D01*
X166200Y483817D01*
X165825Y483900D01*
X165533Y484067D01*
X165325Y484359D01*
X165283Y484692D01*
X165367Y485025D01*
X165575Y485234D01*
X165867Y485400D01*
X166158Y485442D01*
X166450Y485400D01*
X166825Y485234D01*
X166700Y486317D01*
X165575D01*
G01X163100D02*
X163433Y486234D01*
X163683Y486025D01*
X163850Y485775D01*
X163975Y485442D01*
X164017Y485067D01*
X163975Y484692D01*
X163850Y484359D01*
X163683Y484109D01*
X163433Y483900D01*
X163100Y483817D01*
X162767Y483900D01*
X162517Y484109D01*
X162350Y484359D01*
X162225Y484692D01*
X162183Y485067D01*
X162225Y485442D01*
X162350Y485775D01*
X162517Y486025D01*
X162767Y486234D01*
X163100Y486317D01*
G01X160792Y484859D02*
X160500Y485150D01*
X160250Y485317D01*
X159917Y485400D01*
X159625Y485317D01*
X159417Y485150D01*
X159250Y484900D01*
X159208Y484609D01*
X159250Y484359D01*
X159417Y484109D01*
X159667Y483900D01*
X159958Y483817D01*
X160292Y483900D01*
X160583Y484150D01*
X160750Y484525D01*
X160792Y484942D01*
X160708Y485484D01*
X160583Y485775D01*
X160375Y486067D01*
X160083Y486275D01*
X159792Y486317D01*
X159500Y486234D01*
X159292Y486025D01*
G01X182037Y480860D02*
X184537D01*
Y481901D01*
X184412Y482235D01*
X184245Y482443D01*
X183912Y482526D01*
X183579Y482443D01*
X183370Y482193D01*
X183245Y481901D01*
Y480860D01*
G01Y481901D02*
X182037Y482526D01*
G01X182537Y483876D02*
X182245Y484126D01*
X182079Y484460D01*
X182037Y484835D01*
X182079Y485168D01*
X182287Y485501D01*
X182537Y485710D01*
X182787Y485751D01*
X183079Y485668D01*
X183287Y485376D01*
X183370Y485085D01*
Y484710D01*
G01Y485085D02*
X183495Y485335D01*
X183704Y485543D01*
X183954Y485626D01*
X184204Y485543D01*
X184412Y485335D01*
X184537Y484960D01*
X184495Y484585D01*
X184329Y484210D01*
G01X182037Y487810D02*
X182579Y487893D01*
X183037Y488018D01*
X183454Y488185D01*
X183912Y488393D01*
X184537Y488726D01*
Y487060D01*
G01X182037Y490993D02*
X184537D01*
X184037Y490493D01*
G01X182037D02*
Y491493D01*
G01X176900Y501100D02*
X172900D01*
Y508500D01*
G01X189851Y480676D02*
X192351D01*
Y481717D01*
X192226Y482051D01*
X192059Y482259D01*
X191726Y482342D01*
X191393Y482259D01*
X191184Y482009D01*
X191059Y481717D01*
Y480676D01*
G01Y481717D02*
X189851Y482342D01*
G01Y484609D02*
X192351D01*
X191851Y484109D01*
G01X189851D02*
Y485109D01*
G01Y487709D02*
X189893Y488001D01*
X190018Y488334D01*
X190226Y488542D01*
X190518Y488626D01*
X190809Y488542D01*
X191059Y488292D01*
X191184Y487917D01*
Y487501D01*
X191268Y487251D01*
X191476Y487042D01*
X191768Y486959D01*
X192059Y487084D01*
X192268Y487376D01*
X192351Y487709D01*
X192268Y488042D01*
X192059Y488334D01*
X191768Y488459D01*
X191476Y488376D01*
X191268Y488167D01*
X191184Y487917D01*
Y487501D01*
X191059Y487126D01*
X190809Y486876D01*
X190518Y486792D01*
X190226Y486876D01*
X190018Y487084D01*
X189893Y487417D01*
X189851Y487709D01*
G01X190351Y489892D02*
X190059Y490142D01*
X189893Y490476D01*
X189851Y490851D01*
X189893Y491184D01*
X190101Y491517D01*
X190351Y491726D01*
X190601Y491767D01*
X190893Y491684D01*
X191101Y491392D01*
X191184Y491101D01*
Y490726D01*
G01Y491101D02*
X191309Y491351D01*
X191518Y491559D01*
X191768Y491642D01*
X192018Y491559D01*
X192226Y491351D01*
X192351Y490976D01*
X192309Y490601D01*
X192143Y490226D01*
G01X181100Y508500D02*
X185100D01*
Y501100D01*
G01X180900Y510217D02*
X183400D01*
Y511258D01*
X183275Y511592D01*
X183108Y511800D01*
X182775Y511883D01*
X182442Y511800D01*
X182233Y511550D01*
X182108Y511258D01*
Y510217D01*
G01Y511258D02*
X180900Y511883D01*
G01Y514150D02*
X183400D01*
X182900Y513650D01*
G01X180900D02*
Y514650D01*
G01Y517250D02*
X180942Y517542D01*
X181067Y517875D01*
X181275Y518083D01*
X181567Y518167D01*
X181858Y518083D01*
X182108Y517833D01*
X182233Y517458D01*
Y517042D01*
X182317Y516792D01*
X182525Y516583D01*
X182817Y516500D01*
X183108Y516625D01*
X183317Y516917D01*
X183400Y517250D01*
X183317Y517583D01*
X183108Y517875D01*
X182817Y518000D01*
X182525Y517917D01*
X182317Y517708D01*
X182233Y517458D01*
Y517042D01*
X182108Y516667D01*
X181858Y516417D01*
X181567Y516333D01*
X181275Y516417D01*
X181067Y516625D01*
X180942Y516958D01*
X180900Y517250D01*
G01Y520850D02*
X183400D01*
X181608Y519308D01*
Y521392D01*
G01X177200Y530400D02*
X181200D01*
Y523000D01*
G01X178230Y481605D02*
X180730D01*
Y482646D01*
X180605Y482980D01*
X180438Y483188D01*
X180105Y483271D01*
X179772Y483188D01*
X179563Y482938D01*
X179438Y482646D01*
Y481605D01*
G01Y482646D02*
X178230Y483271D01*
G01X180313Y484746D02*
X180563Y484996D01*
X180688Y485288D01*
X180730Y485621D01*
X180647Y486038D01*
X180438Y486330D01*
X180188Y486413D01*
X179938Y486371D01*
X179730Y486205D01*
X179313Y485371D01*
X179022Y484996D01*
X178605Y484746D01*
X178230Y484663D01*
Y486413D01*
G01Y488555D02*
X178772Y488638D01*
X179230Y488763D01*
X179647Y488930D01*
X180105Y489138D01*
X180730Y489471D01*
Y487805D01*
G01Y491738D02*
X180647Y491405D01*
X180438Y491155D01*
X180188Y490988D01*
X179855Y490863D01*
X179480Y490821D01*
X179105Y490863D01*
X178772Y490988D01*
X178522Y491155D01*
X178313Y491405D01*
X178230Y491738D01*
X178313Y492071D01*
X178522Y492321D01*
X178772Y492488D01*
X179105Y492613D01*
X179480Y492655D01*
X179855Y492613D01*
X180188Y492488D01*
X180438Y492321D01*
X180647Y492071D01*
X180730Y491738D01*
G01X168800Y508500D02*
X172800D01*
Y501100D01*
G01X203924Y474690D02*
X206424D01*
Y475731D01*
X206299Y476065D01*
X206132Y476273D01*
X205799Y476356D01*
X205466Y476273D01*
X205257Y476023D01*
X205132Y475731D01*
Y474690D01*
G01Y475731D02*
X203924Y476356D01*
G01X206007Y477831D02*
X206257Y478081D01*
X206382Y478373D01*
X206424Y478706D01*
X206341Y479123D01*
X206132Y479415D01*
X205882Y479498D01*
X205632Y479456D01*
X205424Y479290D01*
X205007Y478456D01*
X204716Y478081D01*
X204299Y477831D01*
X203924Y477748D01*
Y479498D01*
G01Y481723D02*
X203966Y482015D01*
X204091Y482348D01*
X204299Y482556D01*
X204591Y482640D01*
X204882Y482556D01*
X205132Y482306D01*
X205257Y481931D01*
Y481515D01*
X205341Y481265D01*
X205549Y481056D01*
X205841Y480973D01*
X206132Y481098D01*
X206341Y481390D01*
X206424Y481723D01*
X206341Y482056D01*
X206132Y482348D01*
X205841Y482473D01*
X205549Y482390D01*
X205341Y482181D01*
X205257Y481931D01*
Y481515D01*
X205132Y481140D01*
X204882Y480890D01*
X204591Y480806D01*
X204299Y480890D01*
X204091Y481098D01*
X203966Y481431D01*
X203924Y481723D01*
G01X204966Y484031D02*
X205257Y484323D01*
X205424Y484573D01*
X205507Y484906D01*
X205424Y485198D01*
X205257Y485406D01*
X205007Y485573D01*
X204716Y485615D01*
X204466Y485573D01*
X204216Y485406D01*
X204007Y485156D01*
X203924Y484865D01*
X204007Y484531D01*
X204257Y484240D01*
X204632Y484073D01*
X205049Y484031D01*
X205591Y484115D01*
X205882Y484240D01*
X206174Y484448D01*
X206382Y484740D01*
X206424Y485031D01*
X206341Y485323D01*
X206132Y485531D01*
G01X193869Y501089D02*
X189869D01*
Y508489D01*
G01X162083Y504200D02*
Y506700D01*
X161042D01*
X160708Y506575D01*
X160500Y506408D01*
X160417Y506075D01*
X160500Y505742D01*
X160750Y505533D01*
X161042Y505408D01*
X162083D01*
G01X161042D02*
X160417Y504200D01*
G01X159067Y504700D02*
X158817Y504408D01*
X158483Y504242D01*
X158108Y504200D01*
X157775Y504242D01*
X157442Y504450D01*
X157233Y504700D01*
X157192Y504950D01*
X157275Y505242D01*
X157567Y505450D01*
X157858Y505533D01*
X158233D01*
G01X157858D02*
X157608Y505658D01*
X157400Y505867D01*
X157317Y506117D01*
X157400Y506367D01*
X157608Y506575D01*
X157983Y506700D01*
X158358Y506658D01*
X158733Y506492D01*
G01X155967Y504575D02*
X155717Y504367D01*
X155425Y504242D01*
X155050Y504200D01*
X154675Y504283D01*
X154383Y504450D01*
X154175Y504742D01*
X154133Y505075D01*
X154217Y505408D01*
X154425Y505617D01*
X154717Y505783D01*
X155008Y505825D01*
X155300Y505783D01*
X155675Y505617D01*
X155550Y506700D01*
X154425D01*
G01X151950D02*
X152283Y506617D01*
X152533Y506408D01*
X152700Y506158D01*
X152825Y505825D01*
X152867Y505450D01*
X152825Y505075D01*
X152700Y504742D01*
X152533Y504492D01*
X152283Y504283D01*
X151950Y504200D01*
X151617Y504283D01*
X151367Y504492D01*
X151200Y504742D01*
X151075Y505075D01*
X151033Y505450D01*
X151075Y505825D01*
X151200Y506158D01*
X151367Y506408D01*
X151617Y506617D01*
X151950Y506700D01*
G01X163930Y512140D02*
Y508140D01*
X156530D01*
G01X169000Y515100D02*
X165000D01*
Y522500D01*
G01X185930Y480676D02*
X188430D01*
Y481717D01*
X188305Y482051D01*
X188138Y482259D01*
X187805Y482342D01*
X187472Y482259D01*
X187263Y482009D01*
X187138Y481717D01*
Y480676D01*
G01Y481717D02*
X185930Y482342D01*
G01X188013Y483817D02*
X188263Y484067D01*
X188388Y484359D01*
X188430Y484692D01*
X188347Y485109D01*
X188138Y485401D01*
X187888Y485484D01*
X187638Y485442D01*
X187430Y485276D01*
X187013Y484442D01*
X186722Y484067D01*
X186305Y483817D01*
X185930Y483734D01*
Y485484D01*
G01X186222Y487001D02*
X186013Y487292D01*
X185930Y487626D01*
X186013Y487959D01*
X186263Y488251D01*
X186638Y488459D01*
X187013Y488542D01*
X187472D01*
X187847Y488459D01*
X188180Y488251D01*
X188347Y488001D01*
X188430Y487709D01*
X188347Y487376D01*
X188180Y487126D01*
X187930Y486959D01*
X187597Y486876D01*
X187305Y486959D01*
X187013Y487167D01*
X186847Y487417D01*
X186805Y487709D01*
X186888Y488042D01*
X187097Y488292D01*
X187472Y488542D01*
G01X188013Y490017D02*
X188263Y490267D01*
X188388Y490559D01*
X188430Y490892D01*
X188347Y491309D01*
X188138Y491601D01*
X187888Y491684D01*
X187638Y491642D01*
X187430Y491476D01*
X187013Y490642D01*
X186722Y490267D01*
X186305Y490017D01*
X185930Y489934D01*
Y491684D01*
G01X177000Y508500D02*
X181000D01*
Y501100D01*
G01X178183Y510400D02*
Y512900D01*
X177142D01*
X176808Y512775D01*
X176600Y512608D01*
X176517Y512275D01*
X176600Y511942D01*
X176850Y511733D01*
X177142Y511608D01*
X178183D01*
G01X177142D02*
X176517Y510400D01*
G01X175042Y512483D02*
X174792Y512733D01*
X174500Y512858D01*
X174167Y512900D01*
X173750Y512817D01*
X173458Y512608D01*
X173375Y512358D01*
X173417Y512108D01*
X173583Y511900D01*
X174417Y511483D01*
X174792Y511192D01*
X175042Y510775D01*
X175125Y510400D01*
X173375D01*
G01X171858Y510692D02*
X171567Y510483D01*
X171233Y510400D01*
X170900Y510483D01*
X170608Y510733D01*
X170400Y511108D01*
X170317Y511483D01*
Y511942D01*
X170400Y512317D01*
X170608Y512650D01*
X170858Y512817D01*
X171150Y512900D01*
X171483Y512817D01*
X171733Y512650D01*
X171900Y512400D01*
X171983Y512067D01*
X171900Y511775D01*
X171692Y511483D01*
X171442Y511317D01*
X171150Y511275D01*
X170817Y511358D01*
X170567Y511567D01*
X170317Y511942D01*
G01X168967Y510900D02*
X168717Y510608D01*
X168383Y510442D01*
X168008Y510400D01*
X167675Y510442D01*
X167342Y510650D01*
X167133Y510900D01*
X167092Y511150D01*
X167175Y511442D01*
X167467Y511650D01*
X167758Y511733D01*
X168133D01*
G01X167758D02*
X167508Y511858D01*
X167300Y512067D01*
X167217Y512317D01*
X167300Y512567D01*
X167508Y512775D01*
X167883Y512900D01*
X168258Y512858D01*
X168633Y512692D01*
G01X179300Y519000D02*
Y515000D01*
X171900D01*
G01X207703Y474833D02*
X210203D01*
Y475874D01*
X210078Y476208D01*
X209911Y476416D01*
X209578Y476499D01*
X209245Y476416D01*
X209036Y476166D01*
X208911Y475874D01*
Y474833D01*
G01Y475874D02*
X207703Y476499D01*
G01X209786Y477974D02*
X210036Y478224D01*
X210161Y478516D01*
X210203Y478849D01*
X210120Y479266D01*
X209911Y479558D01*
X209661Y479641D01*
X209411Y479599D01*
X209203Y479433D01*
X208786Y478599D01*
X208495Y478224D01*
X208078Y477974D01*
X207703Y477891D01*
Y479641D01*
G01X207995Y481158D02*
X207786Y481449D01*
X207703Y481783D01*
X207786Y482116D01*
X208036Y482408D01*
X208411Y482616D01*
X208786Y482699D01*
X209245D01*
X209620Y482616D01*
X209953Y482408D01*
X210120Y482158D01*
X210203Y481866D01*
X210120Y481533D01*
X209953Y481283D01*
X209703Y481116D01*
X209370Y481033D01*
X209078Y481116D01*
X208786Y481324D01*
X208620Y481574D01*
X208578Y481866D01*
X208661Y482199D01*
X208870Y482449D01*
X209245Y482699D01*
G01X207703Y485466D02*
X210203D01*
X208411Y483924D01*
Y486008D01*
G01X201892Y497622D02*
X197892D01*
Y505022D01*
G01X153000Y501800D02*
X157000D01*
Y494400D01*
G01X173881Y481960D02*
X176381D01*
Y483001D01*
X176256Y483335D01*
X176089Y483543D01*
X175756Y483626D01*
X175423Y483543D01*
X175214Y483293D01*
X175089Y483001D01*
Y481960D01*
G01Y483001D02*
X173881Y483626D01*
G01X174381Y484976D02*
X174089Y485226D01*
X173923Y485560D01*
X173881Y485935D01*
X173923Y486268D01*
X174131Y486601D01*
X174381Y486810D01*
X174631Y486851D01*
X174923Y486768D01*
X175131Y486476D01*
X175214Y486185D01*
Y485810D01*
G01Y486185D02*
X175339Y486435D01*
X175548Y486643D01*
X175798Y486726D01*
X176048Y486643D01*
X176256Y486435D01*
X176381Y486060D01*
X176339Y485685D01*
X176173Y485310D01*
G01X175964Y488201D02*
X176214Y488451D01*
X176339Y488743D01*
X176381Y489076D01*
X176298Y489493D01*
X176089Y489785D01*
X175839Y489868D01*
X175589Y489826D01*
X175381Y489660D01*
X174964Y488826D01*
X174673Y488451D01*
X174256Y488201D01*
X173881Y488118D01*
Y489868D01*
G01X174256Y491176D02*
X174048Y491426D01*
X173923Y491718D01*
X173881Y492093D01*
X173964Y492468D01*
X174131Y492760D01*
X174423Y492968D01*
X174756Y493010D01*
X175089Y492926D01*
X175298Y492718D01*
X175464Y492426D01*
X175506Y492135D01*
X175464Y491843D01*
X175298Y491468D01*
X176381Y491593D01*
Y492718D01*
G01X164700Y508500D02*
X168700D01*
Y501100D01*
G01X149400Y482817D02*
X151900D01*
Y483858D01*
X151775Y484192D01*
X151608Y484400D01*
X151275Y484483D01*
X150942Y484400D01*
X150733Y484150D01*
X150608Y483858D01*
Y482817D01*
G01Y483858D02*
X149400Y484483D01*
G01X149900Y485833D02*
X149608Y486083D01*
X149442Y486417D01*
X149400Y486792D01*
X149442Y487125D01*
X149650Y487458D01*
X149900Y487667D01*
X150150Y487708D01*
X150442Y487625D01*
X150650Y487333D01*
X150733Y487042D01*
Y486667D01*
G01Y487042D02*
X150858Y487292D01*
X151067Y487500D01*
X151317Y487583D01*
X151567Y487500D01*
X151775Y487292D01*
X151900Y486917D01*
X151858Y486542D01*
X151692Y486167D01*
G01X150442Y489058D02*
X150733Y489350D01*
X150900Y489600D01*
X150983Y489933D01*
X150900Y490225D01*
X150733Y490433D01*
X150483Y490600D01*
X150192Y490642D01*
X149942Y490600D01*
X149692Y490433D01*
X149483Y490183D01*
X149400Y489892D01*
X149483Y489558D01*
X149733Y489267D01*
X150108Y489100D01*
X150525Y489058D01*
X151067Y489142D01*
X151358Y489267D01*
X151650Y489475D01*
X151858Y489767D01*
X151900Y490058D01*
X151817Y490350D01*
X151608Y490558D01*
G01X151483Y492158D02*
X151733Y492408D01*
X151858Y492700D01*
X151900Y493033D01*
X151817Y493450D01*
X151608Y493742D01*
X151358Y493825D01*
X151108Y493783D01*
X150900Y493617D01*
X150483Y492783D01*
X150192Y492408D01*
X149775Y492158D01*
X149400Y492075D01*
Y493825D01*
G01X164800Y488900D02*
X160800D01*
Y496300D01*
G01X198116Y480219D02*
X200616D01*
Y481260D01*
X200491Y481594D01*
X200324Y481802D01*
X199991Y481885D01*
X199658Y481802D01*
X199449Y481552D01*
X199324Y481260D01*
Y480219D01*
G01Y481260D02*
X198116Y481885D01*
G01Y484152D02*
X200616D01*
X200116Y483652D01*
G01X198116D02*
Y484652D01*
G01X198491Y486335D02*
X198283Y486585D01*
X198158Y486877D01*
X198116Y487252D01*
X198199Y487627D01*
X198366Y487919D01*
X198658Y488127D01*
X198991Y488169D01*
X199324Y488085D01*
X199533Y487877D01*
X199699Y487585D01*
X199741Y487294D01*
X199699Y487002D01*
X199533Y486627D01*
X200616Y486752D01*
Y487877D01*
G01X200199Y489560D02*
X200449Y489810D01*
X200574Y490102D01*
X200616Y490435D01*
X200533Y490852D01*
X200324Y491144D01*
X200074Y491227D01*
X199824Y491185D01*
X199616Y491019D01*
X199199Y490185D01*
X198908Y489810D01*
X198491Y489560D01*
X198116Y489477D01*
Y491227D01*
G01X185300Y508400D02*
X189300D01*
Y501000D01*
G01X155867Y481217D02*
X158367D01*
Y482258D01*
X158242Y482592D01*
X158075Y482800D01*
X157742Y482883D01*
X157409Y482800D01*
X157200Y482550D01*
X157075Y482258D01*
Y481217D01*
G01Y482258D02*
X155867Y482883D01*
G01X156367Y484233D02*
X156075Y484483D01*
X155909Y484817D01*
X155867Y485192D01*
X155909Y485525D01*
X156117Y485858D01*
X156367Y486067D01*
X156617Y486108D01*
X156909Y486025D01*
X157117Y485733D01*
X157200Y485442D01*
Y485067D01*
G01Y485442D02*
X157325Y485692D01*
X157534Y485900D01*
X157784Y485983D01*
X158034Y485900D01*
X158242Y485692D01*
X158367Y485317D01*
X158325Y484942D01*
X158159Y484567D01*
G01X156909Y487458D02*
X157200Y487750D01*
X157367Y488000D01*
X157450Y488333D01*
X157367Y488625D01*
X157200Y488833D01*
X156950Y489000D01*
X156659Y489042D01*
X156409Y489000D01*
X156159Y488833D01*
X155950Y488583D01*
X155867Y488292D01*
X155950Y487958D01*
X156200Y487667D01*
X156575Y487500D01*
X156992Y487458D01*
X157534Y487542D01*
X157825Y487667D01*
X158117Y487875D01*
X158325Y488167D01*
X158367Y488458D01*
X158284Y488750D01*
X158075Y488958D01*
G01X155867Y491850D02*
X158367D01*
X156575Y490308D01*
Y492392D01*
G01X164861Y496320D02*
X168861D01*
Y488920D01*
G01X164700Y515100D02*
X160700D01*
Y522500D01*
G01X161600Y525700D02*
Y529700D01*
X169000D01*
G01X173200Y520400D02*
X169200D01*
Y527800D01*
G01X161300Y524300D02*
X157300D01*
Y531700D01*
G01X144300Y501500D02*
X148300D01*
Y494100D01*
G01X154965Y483057D02*
Y479057D01*
X147565D01*
G01X147715Y462338D02*
Y466338D01*
X155115D01*
G01X147715Y470738D02*
Y474738D01*
X155115D01*
G01X155085Y470562D02*
Y466562D01*
X147685D01*
G01X192315Y469838D02*
Y473838D01*
X199715D01*
G01X147615Y474938D02*
Y478938D01*
X155015D01*
G01X192415Y473938D02*
Y477938D01*
X199815D01*
G01X148500Y501780D02*
X152500D01*
Y494380D01*
G01X159388Y524134D02*
Y520134D01*
X151988D01*
G01X159358Y519677D02*
Y515677D01*
X151958D01*
G01X200600Y513150D02*
Y515650D01*
X199559D01*
X199225Y515525D01*
X199017Y515358D01*
X198934Y515025D01*
X199017Y514692D01*
X199267Y514483D01*
X199559Y514358D01*
X200600D01*
G01X199559D02*
X198934Y513150D01*
G01X197459Y514192D02*
X197167Y514483D01*
X196917Y514650D01*
X196584Y514733D01*
X196292Y514650D01*
X196084Y514483D01*
X195917Y514233D01*
X195875Y513942D01*
X195917Y513692D01*
X196084Y513442D01*
X196334Y513233D01*
X196625Y513150D01*
X196959Y513233D01*
X197250Y513483D01*
X197417Y513858D01*
X197459Y514275D01*
X197375Y514817D01*
X197250Y515108D01*
X197042Y515400D01*
X196750Y515608D01*
X196459Y515650D01*
X196167Y515567D01*
X195959Y515358D01*
G01X193567Y513150D02*
Y515650D01*
X194067Y515150D01*
G01Y513150D02*
X193067D01*
G01X191384Y513650D02*
X191134Y513358D01*
X190800Y513192D01*
X190425Y513150D01*
X190092Y513192D01*
X189759Y513400D01*
X189550Y513650D01*
X189509Y513900D01*
X189592Y514192D01*
X189884Y514400D01*
X190175Y514483D01*
X190550D01*
G01X190175D02*
X189925Y514608D01*
X189717Y514817D01*
X189634Y515067D01*
X189717Y515317D01*
X189925Y515525D01*
X190300Y515650D01*
X190675Y515608D01*
X191050Y515442D01*
G01X188111Y514781D02*
X184111D01*
Y522181D01*
G01X147100Y503750D02*
X144600D01*
G01X147100Y502792D02*
Y504708D01*
G01X144600Y506017D02*
X147100D01*
Y507017D01*
X146975Y507350D01*
X146683Y507600D01*
X146350Y507683D01*
X146017Y507600D01*
X145767Y507392D01*
X145642Y507017D01*
Y506017D01*
G01X144600Y509950D02*
X144642Y510242D01*
X144767Y510575D01*
X144975Y510783D01*
X145267Y510867D01*
X145558Y510783D01*
X145808Y510533D01*
X145933Y510158D01*
Y509742D01*
X146017Y509492D01*
X146225Y509283D01*
X146517Y509200D01*
X146808Y509325D01*
X147017Y509617D01*
X147100Y509950D01*
X147017Y510283D01*
X146808Y510575D01*
X146517Y510700D01*
X146225Y510617D01*
X146017Y510408D01*
X145933Y510158D01*
Y509742D01*
X145808Y509367D01*
X145558Y509117D01*
X145267Y509033D01*
X144975Y509117D01*
X144767Y509325D01*
X144642Y509658D01*
X144600Y509950D01*
G01Y513550D02*
X147100D01*
X145308Y512008D01*
Y514092D01*
G01X177472Y467703D02*
X169472D01*
Y479653D01*
X177472D01*
Y467703D01*
G01X171322Y479653D02*
X173322Y477653D01*
X175322Y479653D01*
G01X177052Y593932D02*
X177302Y594057D01*
X177594Y594140D01*
X177927D01*
X178302Y594015D01*
X178594Y593807D01*
X178802Y593557D01*
X178969Y593140D01*
X179011Y592765D01*
X178927Y592390D01*
X178802Y592140D01*
X178552Y591890D01*
X178261Y591723D01*
X177969Y591640D01*
X177677D01*
X177386Y591723D01*
X177136Y591848D01*
X176927Y592015D01*
G01X175786D02*
X175536Y591807D01*
X175244Y591682D01*
X174869Y591640D01*
X174494Y591723D01*
X174202Y591890D01*
X173994Y592182D01*
X173952Y592515D01*
X174036Y592848D01*
X174244Y593057D01*
X174536Y593223D01*
X174827Y593265D01*
X175119Y593223D01*
X175494Y593057D01*
X175369Y594140D01*
X174244D01*
G01X172686Y592140D02*
X172436Y591848D01*
X172102Y591682D01*
X171727Y591640D01*
X171394Y591682D01*
X171061Y591890D01*
X170852Y592140D01*
X170811Y592390D01*
X170894Y592682D01*
X171186Y592890D01*
X171477Y592973D01*
X171852D01*
G01X171477D02*
X171227Y593098D01*
X171019Y593307D01*
X170936Y593557D01*
X171019Y593807D01*
X171227Y594015D01*
X171602Y594140D01*
X171977Y594098D01*
X172352Y593932D01*
G01X214083Y546172D02*
X214333Y546297D01*
X214625Y546380D01*
X214958D01*
X215333Y546255D01*
X215625Y546047D01*
X215833Y545797D01*
X216000Y545380D01*
X216042Y545005D01*
X215958Y544630D01*
X215833Y544380D01*
X215583Y544130D01*
X215292Y543963D01*
X215000Y543880D01*
X214708D01*
X214417Y543963D01*
X214167Y544088D01*
X213958Y544255D01*
G01X212608Y544172D02*
X212317Y543963D01*
X211983Y543880D01*
X211650Y543963D01*
X211358Y544213D01*
X211150Y544588D01*
X211067Y544963D01*
Y545422D01*
X211150Y545797D01*
X211358Y546130D01*
X211608Y546297D01*
X211900Y546380D01*
X212233Y546297D01*
X212483Y546130D01*
X212650Y545880D01*
X212733Y545547D01*
X212650Y545255D01*
X212442Y544963D01*
X212192Y544797D01*
X211900Y544755D01*
X211567Y544838D01*
X211317Y545047D01*
X211067Y545422D01*
G01X209508Y544172D02*
X209217Y543963D01*
X208883Y543880D01*
X208550Y543963D01*
X208258Y544213D01*
X208050Y544588D01*
X207967Y544963D01*
Y545422D01*
X208050Y545797D01*
X208258Y546130D01*
X208508Y546297D01*
X208800Y546380D01*
X209133Y546297D01*
X209383Y546130D01*
X209550Y545880D01*
X209633Y545547D01*
X209550Y545255D01*
X209342Y544963D01*
X209092Y544797D01*
X208800Y544755D01*
X208467Y544838D01*
X208217Y545047D01*
X207967Y545422D01*
G01X206408Y544172D02*
X206117Y543963D01*
X205783Y543880D01*
X205450Y543963D01*
X205158Y544213D01*
X204950Y544588D01*
X204867Y544963D01*
Y545422D01*
X204950Y545797D01*
X205158Y546130D01*
X205408Y546297D01*
X205700Y546380D01*
X206033Y546297D01*
X206283Y546130D01*
X206450Y545880D01*
X206533Y545547D01*
X206450Y545255D01*
X206242Y544963D01*
X205992Y544797D01*
X205700Y544755D01*
X205367Y544838D01*
X205117Y545047D01*
X204867Y545422D01*
G01X184600Y530600D02*
X180600D01*
Y538000D01*
G01X200600Y530800D02*
X196600D01*
Y538200D01*
G01X188900Y530700D02*
X184900D01*
Y538100D01*
G01X189000Y538000D02*
X193000D01*
Y530600D01*
G01X180600Y530400D02*
X176600D01*
Y537800D01*
G01X200700Y538100D02*
X204700D01*
Y530700D01*
G01X208900Y538000D02*
X212900D01*
Y530600D01*
G01X176500Y530400D02*
X172500D01*
Y537800D01*
G01X204800Y537980D02*
X208800D01*
Y530580D01*
G01X158501Y558867D02*
X154501D01*
Y566267D01*
G01X170087Y585147D02*
Y589147D01*
X177487D01*
G01X169733Y572967D02*
Y575467D01*
X168692D01*
X168358Y575342D01*
X168150Y575175D01*
X168067Y574842D01*
X168150Y574509D01*
X168400Y574300D01*
X168692Y574175D01*
X169733D01*
G01X168692D02*
X168067Y572967D01*
G01X165800D02*
Y575467D01*
X166300Y574967D01*
G01Y572967D02*
X165300D01*
G01X162200D02*
Y575467D01*
X163742Y573675D01*
X161658D01*
G01X159600Y572967D02*
Y575467D01*
X160100Y574967D01*
G01Y572967D02*
X159100D01*
G01X177802Y576058D02*
Y572058D01*
X170402D01*
G01X207217Y548317D02*
X209717D01*
Y549358D01*
X209592Y549692D01*
X209425Y549900D01*
X209092Y549983D01*
X208759Y549900D01*
X208550Y549650D01*
X208425Y549358D01*
Y548317D01*
G01Y549358D02*
X207217Y549983D01*
G01X207717Y551333D02*
X207425Y551583D01*
X207259Y551917D01*
X207217Y552292D01*
X207259Y552625D01*
X207467Y552958D01*
X207717Y553167D01*
X207967Y553208D01*
X208259Y553125D01*
X208467Y552833D01*
X208550Y552542D01*
Y552167D01*
G01Y552542D02*
X208675Y552792D01*
X208884Y553000D01*
X209134Y553083D01*
X209384Y553000D01*
X209592Y552792D01*
X209717Y552417D01*
X209675Y552042D01*
X209509Y551667D01*
G01X208259Y554558D02*
X208550Y554850D01*
X208717Y555100D01*
X208800Y555433D01*
X208717Y555725D01*
X208550Y555933D01*
X208300Y556100D01*
X208009Y556142D01*
X207759Y556100D01*
X207509Y555933D01*
X207300Y555683D01*
X207217Y555392D01*
X207300Y555058D01*
X207550Y554767D01*
X207925Y554600D01*
X208342Y554558D01*
X208884Y554642D01*
X209175Y554767D01*
X209467Y554975D01*
X209675Y555267D01*
X209717Y555558D01*
X209634Y555850D01*
X209425Y556058D01*
G01X207717Y557533D02*
X207425Y557783D01*
X207259Y558117D01*
X207217Y558492D01*
X207259Y558825D01*
X207467Y559158D01*
X207717Y559367D01*
X207967Y559408D01*
X208259Y559325D01*
X208467Y559033D01*
X208550Y558742D01*
Y558367D01*
G01Y558742D02*
X208675Y558992D01*
X208884Y559200D01*
X209134Y559283D01*
X209384Y559200D01*
X209592Y558992D01*
X209717Y558617D01*
X209675Y558242D01*
X209509Y557867D01*
G01X198890Y561900D02*
X194890D01*
Y569300D01*
G01X202910Y557790D02*
X198910D01*
Y565190D01*
G01X153754Y590802D02*
Y586802D01*
X146354D01*
G01X210950Y595517D02*
Y593017D01*
G01X211908Y595517D02*
X209992D01*
G01X208683Y593017D02*
Y595517D01*
X207683D01*
X207350Y595392D01*
X207100Y595100D01*
X207017Y594767D01*
X207100Y594434D01*
X207308Y594184D01*
X207683Y594059D01*
X208683D01*
G01X204750Y593017D02*
X204458Y593059D01*
X204125Y593184D01*
X203917Y593392D01*
X203833Y593684D01*
X203917Y593975D01*
X204167Y594225D01*
X204542Y594350D01*
X204958D01*
X205208Y594434D01*
X205417Y594642D01*
X205500Y594934D01*
X205375Y595225D01*
X205083Y595434D01*
X204750Y595517D01*
X204417Y595434D01*
X204125Y595225D01*
X204000Y594934D01*
X204083Y594642D01*
X204292Y594434D01*
X204542Y594350D01*
X204958D01*
X205333Y594225D01*
X205583Y593975D01*
X205667Y593684D01*
X205583Y593392D01*
X205375Y593184D01*
X205042Y593059D01*
X204750Y593017D01*
G01X201650Y595517D02*
X201983Y595434D01*
X202233Y595225D01*
X202400Y594975D01*
X202525Y594642D01*
X202567Y594267D01*
X202525Y593892D01*
X202400Y593559D01*
X202233Y593309D01*
X201983Y593100D01*
X201650Y593017D01*
X201317Y593100D01*
X201067Y593309D01*
X200900Y593559D01*
X200775Y593892D01*
X200733Y594267D01*
X200775Y594642D01*
X200900Y594975D01*
X201067Y595225D01*
X201317Y595434D01*
X201650Y595517D01*
G01X216150Y587000D02*
Y584500D01*
G01X217108Y587000D02*
X215192D01*
G01X213883Y584500D02*
Y587000D01*
X212883D01*
X212550Y586875D01*
X212300Y586583D01*
X212217Y586250D01*
X212300Y585917D01*
X212508Y585667D01*
X212883Y585542D01*
X213883D01*
G01X209950Y584500D02*
X209658Y584542D01*
X209325Y584667D01*
X209117Y584875D01*
X209033Y585167D01*
X209117Y585458D01*
X209367Y585708D01*
X209742Y585833D01*
X210158D01*
X210408Y585917D01*
X210617Y586125D01*
X210700Y586417D01*
X210575Y586708D01*
X210283Y586917D01*
X209950Y587000D01*
X209617Y586917D01*
X209325Y586708D01*
X209200Y586417D01*
X209283Y586125D01*
X209492Y585917D01*
X209742Y585833D01*
X210158D01*
X210533Y585708D01*
X210783Y585458D01*
X210867Y585167D01*
X210783Y584875D01*
X210575Y584667D01*
X210242Y584542D01*
X209950Y584500D01*
G01X206850D02*
Y587000D01*
X207350Y586500D01*
G01Y584500D02*
X206350D01*
G01X164700Y588467D02*
Y585967D01*
G01X165658Y588467D02*
X163742D01*
G01X162433Y585967D02*
Y588467D01*
X161433D01*
X161100Y588342D01*
X160850Y588050D01*
X160767Y587717D01*
X160850Y587384D01*
X161058Y587134D01*
X161433Y587009D01*
X162433D01*
G01X159292D02*
X159000Y587300D01*
X158750Y587467D01*
X158417Y587550D01*
X158125Y587467D01*
X157917Y587300D01*
X157750Y587050D01*
X157708Y586759D01*
X157750Y586509D01*
X157917Y586259D01*
X158167Y586050D01*
X158458Y585967D01*
X158792Y586050D01*
X159083Y586300D01*
X159250Y586675D01*
X159292Y587092D01*
X159208Y587634D01*
X159083Y587925D01*
X158875Y588217D01*
X158583Y588425D01*
X158292Y588467D01*
X158000Y588384D01*
X157792Y588175D01*
G01X156192Y588050D02*
X155942Y588300D01*
X155650Y588425D01*
X155317Y588467D01*
X154900Y588384D01*
X154608Y588175D01*
X154525Y587925D01*
X154567Y587675D01*
X154733Y587467D01*
X155567Y587050D01*
X155942Y586759D01*
X156192Y586342D01*
X156275Y585967D01*
X154525D01*
G01X201500Y545167D02*
Y542667D01*
G01X202458Y545167D02*
X200542D01*
G01X199233Y542667D02*
Y545167D01*
X198233D01*
X197900Y545042D01*
X197650Y544750D01*
X197567Y544417D01*
X197650Y544084D01*
X197858Y543834D01*
X198233Y543709D01*
X199233D01*
G01X195383Y542667D02*
X195300Y543209D01*
X195175Y543667D01*
X195008Y544084D01*
X194800Y544542D01*
X194467Y545167D01*
X196133D01*
G01X192992Y544750D02*
X192742Y545000D01*
X192450Y545125D01*
X192117Y545167D01*
X191700Y545084D01*
X191408Y544875D01*
X191325Y544625D01*
X191367Y544375D01*
X191533Y544167D01*
X192367Y543750D01*
X192742Y543459D01*
X192992Y543042D01*
X193075Y542667D01*
X191325D01*
G01X217250Y591567D02*
Y589067D01*
G01X218208Y591567D02*
X216292D01*
G01X214983Y589067D02*
Y591567D01*
X213983D01*
X213650Y591442D01*
X213400Y591150D01*
X213317Y590817D01*
X213400Y590484D01*
X213608Y590234D01*
X213983Y590109D01*
X214983D01*
G01X211050Y589067D02*
X210758Y589109D01*
X210425Y589234D01*
X210217Y589442D01*
X210133Y589734D01*
X210217Y590025D01*
X210467Y590275D01*
X210842Y590400D01*
X211258D01*
X211508Y590484D01*
X211717Y590692D01*
X211800Y590984D01*
X211675Y591275D01*
X211383Y591484D01*
X211050Y591567D01*
X210717Y591484D01*
X210425Y591275D01*
X210300Y590984D01*
X210383Y590692D01*
X210592Y590484D01*
X210842Y590400D01*
X211258D01*
X211633Y590275D01*
X211883Y590025D01*
X211967Y589734D01*
X211883Y589442D01*
X211675Y589234D01*
X211342Y589109D01*
X211050Y589067D01*
G01X208742Y591150D02*
X208492Y591400D01*
X208200Y591525D01*
X207867Y591567D01*
X207450Y591484D01*
X207158Y591275D01*
X207075Y591025D01*
X207117Y590775D01*
X207283Y590567D01*
X208117Y590150D01*
X208492Y589859D01*
X208742Y589442D01*
X208825Y589067D01*
X207075D01*
G01X215200Y575367D02*
Y572867D01*
G01X216158Y575367D02*
X214242D01*
G01X212933Y572867D02*
Y575367D01*
X211933D01*
X211600Y575242D01*
X211350Y574950D01*
X211267Y574617D01*
X211350Y574284D01*
X211558Y574034D01*
X211933Y573909D01*
X212933D01*
G01X209000Y572867D02*
X208708Y572909D01*
X208375Y573034D01*
X208167Y573242D01*
X208083Y573534D01*
X208167Y573825D01*
X208417Y574075D01*
X208792Y574200D01*
X209208D01*
X209458Y574284D01*
X209667Y574492D01*
X209750Y574784D01*
X209625Y575075D01*
X209333Y575284D01*
X209000Y575367D01*
X208667Y575284D01*
X208375Y575075D01*
X208250Y574784D01*
X208333Y574492D01*
X208542Y574284D01*
X208792Y574200D01*
X209208D01*
X209583Y574075D01*
X209833Y573825D01*
X209917Y573534D01*
X209833Y573242D01*
X209625Y573034D01*
X209292Y572909D01*
X209000Y572867D01*
G01X206817Y573367D02*
X206567Y573075D01*
X206233Y572909D01*
X205858Y572867D01*
X205525Y572909D01*
X205192Y573117D01*
X204983Y573367D01*
X204942Y573617D01*
X205025Y573909D01*
X205317Y574117D01*
X205608Y574200D01*
X205983D01*
G01X205608D02*
X205358Y574325D01*
X205150Y574534D01*
X205067Y574784D01*
X205150Y575034D01*
X205358Y575242D01*
X205733Y575367D01*
X206108Y575325D01*
X206483Y575159D01*
G01X169850Y556767D02*
Y554267D01*
G01X170808Y556767D02*
X168892D01*
G01X167583Y554267D02*
Y556767D01*
X166583D01*
X166250Y556642D01*
X166000Y556350D01*
X165917Y556017D01*
X166000Y555684D01*
X166208Y555434D01*
X166583Y555309D01*
X167583D01*
G01X164442Y556350D02*
X164192Y556600D01*
X163900Y556725D01*
X163567Y556767D01*
X163150Y556684D01*
X162858Y556475D01*
X162775Y556225D01*
X162817Y555975D01*
X162983Y555767D01*
X163817Y555350D01*
X164192Y555059D01*
X164442Y554642D01*
X164525Y554267D01*
X162775D01*
G01X160550D02*
X160258Y554309D01*
X159925Y554434D01*
X159717Y554642D01*
X159633Y554934D01*
X159717Y555225D01*
X159967Y555475D01*
X160342Y555600D01*
X160758D01*
X161008Y555684D01*
X161217Y555892D01*
X161300Y556184D01*
X161175Y556475D01*
X160883Y556684D01*
X160550Y556767D01*
X160217Y556684D01*
X159925Y556475D01*
X159800Y556184D01*
X159883Y555892D01*
X160092Y555684D01*
X160342Y555600D01*
X160758D01*
X161133Y555475D01*
X161383Y555225D01*
X161467Y554934D01*
X161383Y554642D01*
X161175Y554434D01*
X160842Y554309D01*
X160550Y554267D01*
G01X213600Y564217D02*
Y561717D01*
G01X214558Y564217D02*
X212642D01*
G01X211333Y561717D02*
Y564217D01*
X210333D01*
X210000Y564092D01*
X209750Y563800D01*
X209667Y563467D01*
X209750Y563134D01*
X209958Y562884D01*
X210333Y562759D01*
X211333D01*
G01X207483Y561717D02*
X207400Y562259D01*
X207275Y562717D01*
X207108Y563134D01*
X206900Y563592D01*
X206567Y564217D01*
X208233D01*
G01X204300Y561717D02*
X204008Y561759D01*
X203675Y561884D01*
X203467Y562092D01*
X203383Y562384D01*
X203467Y562675D01*
X203717Y562925D01*
X204092Y563050D01*
X204508D01*
X204758Y563134D01*
X204967Y563342D01*
X205050Y563634D01*
X204925Y563925D01*
X204633Y564134D01*
X204300Y564217D01*
X203967Y564134D01*
X203675Y563925D01*
X203550Y563634D01*
X203633Y563342D01*
X203842Y563134D01*
X204092Y563050D01*
X204508D01*
X204883Y562925D01*
X205133Y562675D01*
X205217Y562384D01*
X205133Y562092D01*
X204925Y561884D01*
X204592Y561759D01*
X204300Y561717D01*
G01X215500Y568267D02*
Y565767D01*
G01X216458Y568267D02*
X214542D01*
G01X213233Y565767D02*
Y568267D01*
X212233D01*
X211900Y568142D01*
X211650Y567850D01*
X211567Y567517D01*
X211650Y567184D01*
X211858Y566934D01*
X212233Y566809D01*
X213233D01*
G01X210217Y566142D02*
X209967Y565934D01*
X209675Y565809D01*
X209300Y565767D01*
X208925Y565850D01*
X208633Y566017D01*
X208425Y566309D01*
X208383Y566642D01*
X208467Y566975D01*
X208675Y567184D01*
X208967Y567350D01*
X209258Y567392D01*
X209550Y567350D01*
X209925Y567184D01*
X209800Y568267D01*
X208675D01*
G01X206992Y567850D02*
X206742Y568100D01*
X206450Y568225D01*
X206117Y568267D01*
X205700Y568184D01*
X205408Y567975D01*
X205325Y567725D01*
X205367Y567475D01*
X205533Y567267D01*
X206367Y566850D01*
X206742Y566559D01*
X206992Y566142D01*
X207075Y565767D01*
X205325D01*
G01X215500Y582067D02*
Y579567D01*
G01X216458Y582067D02*
X214542D01*
G01X213233Y579567D02*
Y582067D01*
X212233D01*
X211900Y581942D01*
X211650Y581650D01*
X211567Y581317D01*
X211650Y580984D01*
X211858Y580734D01*
X212233Y580609D01*
X213233D01*
G01X210217Y579942D02*
X209967Y579734D01*
X209675Y579609D01*
X209300Y579567D01*
X208925Y579650D01*
X208633Y579817D01*
X208425Y580109D01*
X208383Y580442D01*
X208467Y580775D01*
X208675Y580984D01*
X208967Y581150D01*
X209258Y581192D01*
X209550Y581150D01*
X209925Y580984D01*
X209800Y582067D01*
X208675D01*
G01X206200Y579567D02*
Y582067D01*
X206700Y581567D01*
G01Y579567D02*
X205700D01*
G01X184200Y545950D02*
Y543450D01*
G01X185158Y545950D02*
X183242D01*
G01X181933Y543450D02*
Y545950D01*
X180933D01*
X180600Y545825D01*
X180350Y545533D01*
X180267Y545200D01*
X180350Y544867D01*
X180558Y544617D01*
X180933Y544492D01*
X181933D01*
G01X178792Y545533D02*
X178542Y545783D01*
X178250Y545908D01*
X177917Y545950D01*
X177500Y545867D01*
X177208Y545658D01*
X177125Y545408D01*
X177167Y545158D01*
X177333Y544950D01*
X178167Y544533D01*
X178542Y544242D01*
X178792Y543825D01*
X178875Y543450D01*
X177125D01*
G01X174900Y545950D02*
X175233Y545867D01*
X175483Y545658D01*
X175650Y545408D01*
X175775Y545075D01*
X175817Y544700D01*
X175775Y544325D01*
X175650Y543992D01*
X175483Y543742D01*
X175233Y543533D01*
X174900Y543450D01*
X174567Y543533D01*
X174317Y543742D01*
X174150Y543992D01*
X174025Y544325D01*
X173983Y544700D01*
X174025Y545075D01*
X174150Y545408D01*
X174317Y545658D01*
X174567Y545867D01*
X174900Y545950D01*
G01X173100Y548550D02*
Y546050D01*
G01X174058Y548550D02*
X172142D01*
G01X170833Y546050D02*
Y548550D01*
X169833D01*
X169500Y548425D01*
X169250Y548133D01*
X169167Y547800D01*
X169250Y547467D01*
X169458Y547217D01*
X169833Y547092D01*
X170833D01*
G01X167692Y548133D02*
X167442Y548383D01*
X167150Y548508D01*
X166817Y548550D01*
X166400Y548467D01*
X166108Y548258D01*
X166025Y548008D01*
X166067Y547758D01*
X166233Y547550D01*
X167067Y547133D01*
X167442Y546842D01*
X167692Y546425D01*
X167775Y546050D01*
X166025D01*
G01X163800D02*
Y548550D01*
X164300Y548050D01*
G01Y546050D02*
X163300D01*
G01X188283Y564959D02*
X188533Y565084D01*
X188825Y565167D01*
X189158D01*
X189533Y565042D01*
X189825Y564834D01*
X190033Y564584D01*
X190200Y564167D01*
X190242Y563792D01*
X190158Y563417D01*
X190033Y563167D01*
X189783Y562917D01*
X189492Y562750D01*
X189200Y562667D01*
X188908D01*
X188617Y562750D01*
X188367Y562875D01*
X188158Y563042D01*
G01X186100Y562667D02*
X185808Y562709D01*
X185475Y562834D01*
X185267Y563042D01*
X185183Y563334D01*
X185267Y563625D01*
X185517Y563875D01*
X185892Y564000D01*
X186308D01*
X186558Y564084D01*
X186767Y564292D01*
X186850Y564584D01*
X186725Y564875D01*
X186433Y565084D01*
X186100Y565167D01*
X185767Y565084D01*
X185475Y564875D01*
X185350Y564584D01*
X185433Y564292D01*
X185642Y564084D01*
X185892Y564000D01*
X186308D01*
X186683Y563875D01*
X186933Y563625D01*
X187017Y563334D01*
X186933Y563042D01*
X186725Y562834D01*
X186392Y562709D01*
X186100Y562667D01*
G01X183917Y563167D02*
X183667Y562875D01*
X183333Y562709D01*
X182958Y562667D01*
X182625Y562709D01*
X182292Y562917D01*
X182083Y563167D01*
X182042Y563417D01*
X182125Y563709D01*
X182417Y563917D01*
X182708Y564000D01*
X183083D01*
G01X182708D02*
X182458Y564125D01*
X182250Y564334D01*
X182167Y564584D01*
X182250Y564834D01*
X182458Y565042D01*
X182833Y565167D01*
X183208Y565125D01*
X183583Y564959D01*
G01X199972Y573402D02*
X200222Y573527D01*
X200514Y573610D01*
X200847D01*
X201222Y573485D01*
X201514Y573277D01*
X201722Y573027D01*
X201889Y572610D01*
X201931Y572235D01*
X201847Y571860D01*
X201722Y571610D01*
X201472Y571360D01*
X201181Y571193D01*
X200889Y571110D01*
X200597D01*
X200306Y571193D01*
X200056Y571318D01*
X199847Y571485D01*
G01X198497Y571402D02*
X198206Y571193D01*
X197872Y571110D01*
X197539Y571193D01*
X197247Y571443D01*
X197039Y571818D01*
X196956Y572193D01*
Y572652D01*
X197039Y573027D01*
X197247Y573360D01*
X197497Y573527D01*
X197789Y573610D01*
X198122Y573527D01*
X198372Y573360D01*
X198539Y573110D01*
X198622Y572777D01*
X198539Y572485D01*
X198331Y572193D01*
X198081Y572027D01*
X197789Y571985D01*
X197456Y572068D01*
X197206Y572277D01*
X196956Y572652D01*
G01X194689Y571110D02*
X194397Y571152D01*
X194064Y571277D01*
X193856Y571485D01*
X193772Y571777D01*
X193856Y572068D01*
X194106Y572318D01*
X194481Y572443D01*
X194897D01*
X195147Y572527D01*
X195356Y572735D01*
X195439Y573027D01*
X195314Y573318D01*
X195022Y573527D01*
X194689Y573610D01*
X194356Y573527D01*
X194064Y573318D01*
X193939Y573027D01*
X194022Y572735D01*
X194231Y572527D01*
X194481Y572443D01*
X194897D01*
X195272Y572318D01*
X195522Y572068D01*
X195606Y571777D01*
X195522Y571485D01*
X195314Y571277D01*
X194981Y571152D01*
X194689Y571110D01*
G01X169733Y570059D02*
X169983Y570184D01*
X170275Y570267D01*
X170608D01*
X170983Y570142D01*
X171275Y569934D01*
X171483Y569684D01*
X171650Y569267D01*
X171692Y568892D01*
X171608Y568517D01*
X171483Y568267D01*
X171233Y568017D01*
X170942Y567850D01*
X170650Y567767D01*
X170358D01*
X170067Y567850D01*
X169817Y567975D01*
X169608Y568142D01*
G01X168467D02*
X168217Y567934D01*
X167925Y567809D01*
X167550Y567767D01*
X167175Y567850D01*
X166883Y568017D01*
X166675Y568309D01*
X166633Y568642D01*
X166717Y568975D01*
X166925Y569184D01*
X167217Y569350D01*
X167508Y569392D01*
X167800Y569350D01*
X168175Y569184D01*
X168050Y570267D01*
X166925D01*
G01X165242Y568809D02*
X164950Y569100D01*
X164700Y569267D01*
X164367Y569350D01*
X164075Y569267D01*
X163867Y569100D01*
X163700Y568850D01*
X163658Y568559D01*
X163700Y568309D01*
X163867Y568059D01*
X164117Y567850D01*
X164408Y567767D01*
X164742Y567850D01*
X165033Y568100D01*
X165200Y568475D01*
X165242Y568892D01*
X165158Y569434D01*
X165033Y569725D01*
X164825Y570017D01*
X164533Y570225D01*
X164242Y570267D01*
X163950Y570184D01*
X163742Y569975D01*
G01X187109Y570367D02*
X187234Y570117D01*
X187317Y569825D01*
Y569492D01*
X187192Y569117D01*
X186984Y568825D01*
X186734Y568617D01*
X186317Y568450D01*
X185942Y568408D01*
X185567Y568492D01*
X185317Y568617D01*
X185067Y568867D01*
X184900Y569158D01*
X184817Y569450D01*
Y569742D01*
X184900Y570033D01*
X185025Y570283D01*
X185192Y570492D01*
G01X184817Y572550D02*
X187317D01*
X186817Y572050D01*
G01X184817D02*
Y573050D01*
G01X187317Y575650D02*
X187234Y575317D01*
X187025Y575067D01*
X186775Y574900D01*
X186442Y574775D01*
X186067Y574733D01*
X185692Y574775D01*
X185359Y574900D01*
X185109Y575067D01*
X184900Y575317D01*
X184817Y575650D01*
X184900Y575983D01*
X185109Y576233D01*
X185359Y576400D01*
X185692Y576525D01*
X186067Y576567D01*
X186442Y576525D01*
X186775Y576400D01*
X187025Y576233D01*
X187234Y575983D01*
X187317Y575650D01*
G01X184817Y578750D02*
X184859Y579042D01*
X184984Y579375D01*
X185192Y579583D01*
X185484Y579667D01*
X185775Y579583D01*
X186025Y579333D01*
X186150Y578958D01*
Y578542D01*
X186234Y578292D01*
X186442Y578083D01*
X186734Y578000D01*
X187025Y578125D01*
X187234Y578417D01*
X187317Y578750D01*
X187234Y579083D01*
X187025Y579375D01*
X186734Y579500D01*
X186442Y579417D01*
X186234Y579208D01*
X186150Y578958D01*
Y578542D01*
X186025Y578167D01*
X185775Y577917D01*
X185484Y577833D01*
X185192Y577917D01*
X184984Y578125D01*
X184859Y578458D01*
X184817Y578750D01*
G01X190133Y588309D02*
X190383Y588434D01*
X190675Y588517D01*
X191008D01*
X191383Y588392D01*
X191675Y588184D01*
X191883Y587934D01*
X192050Y587517D01*
X192092Y587142D01*
X192008Y586767D01*
X191883Y586517D01*
X191633Y586267D01*
X191342Y586100D01*
X191050Y586017D01*
X190758D01*
X190467Y586100D01*
X190217Y586225D01*
X190008Y586392D01*
G01X187950Y586017D02*
Y588517D01*
X188450Y588017D01*
G01Y586017D02*
X187450D01*
G01X184850Y588517D02*
X185183Y588434D01*
X185433Y588225D01*
X185600Y587975D01*
X185725Y587642D01*
X185767Y587267D01*
X185725Y586892D01*
X185600Y586559D01*
X185433Y586309D01*
X185183Y586100D01*
X184850Y586017D01*
X184517Y586100D01*
X184267Y586309D01*
X184100Y586559D01*
X183975Y586892D01*
X183933Y587267D01*
X183975Y587642D01*
X184100Y587975D01*
X184267Y588225D01*
X184517Y588434D01*
X184850Y588517D01*
G01X181833Y586017D02*
X181750Y586559D01*
X181625Y587017D01*
X181458Y587434D01*
X181250Y587892D01*
X180917Y588517D01*
X182583D01*
G01X203633Y589509D02*
X203883Y589634D01*
X204175Y589717D01*
X204508D01*
X204883Y589592D01*
X205175Y589384D01*
X205383Y589134D01*
X205550Y588717D01*
X205592Y588342D01*
X205508Y587967D01*
X205383Y587717D01*
X205133Y587467D01*
X204842Y587300D01*
X204550Y587217D01*
X204258D01*
X203967Y587300D01*
X203717Y587425D01*
X203508Y587592D01*
G01X201450Y587217D02*
Y589717D01*
X201950Y589217D01*
G01Y587217D02*
X200950D01*
G01X198350Y589717D02*
X198683Y589634D01*
X198933Y589425D01*
X199100Y589175D01*
X199225Y588842D01*
X199267Y588467D01*
X199225Y588092D01*
X199100Y587759D01*
X198933Y587509D01*
X198683Y587300D01*
X198350Y587217D01*
X198017Y587300D01*
X197767Y587509D01*
X197600Y587759D01*
X197475Y588092D01*
X197433Y588467D01*
X197475Y588842D01*
X197600Y589175D01*
X197767Y589425D01*
X198017Y589634D01*
X198350Y589717D01*
G01X195250Y587217D02*
Y589717D01*
X195750Y589217D01*
G01Y587217D02*
X194750D01*
G01X168083Y566225D02*
X168333Y566350D01*
X168625Y566433D01*
X168958D01*
X169333Y566308D01*
X169625Y566100D01*
X169833Y565850D01*
X170000Y565433D01*
X170042Y565058D01*
X169958Y564683D01*
X169833Y564433D01*
X169583Y564183D01*
X169292Y564016D01*
X169000Y563933D01*
X168708D01*
X168417Y564016D01*
X168167Y564141D01*
X167958Y564308D01*
G01X165900Y563933D02*
Y566433D01*
X166400Y565933D01*
G01Y563933D02*
X165400D01*
G01X162800Y566433D02*
X163133Y566350D01*
X163383Y566141D01*
X163550Y565891D01*
X163675Y565558D01*
X163717Y565183D01*
X163675Y564808D01*
X163550Y564475D01*
X163383Y564225D01*
X163133Y564016D01*
X162800Y563933D01*
X162467Y564016D01*
X162217Y564225D01*
X162050Y564475D01*
X161925Y564808D01*
X161883Y565183D01*
X161925Y565558D01*
X162050Y565891D01*
X162217Y566141D01*
X162467Y566350D01*
X162800Y566433D01*
G01X159700D02*
X160033Y566350D01*
X160283Y566141D01*
X160450Y565891D01*
X160575Y565558D01*
X160617Y565183D01*
X160575Y564808D01*
X160450Y564475D01*
X160283Y564225D01*
X160033Y564016D01*
X159700Y563933D01*
X159367Y564016D01*
X159117Y564225D01*
X158950Y564475D01*
X158825Y564808D01*
X158783Y565183D01*
X158825Y565558D01*
X158950Y565891D01*
X159117Y566141D01*
X159367Y566350D01*
X159700Y566433D01*
G01X171533Y562422D02*
X171783Y562547D01*
X172075Y562630D01*
X172408D01*
X172783Y562505D01*
X173075Y562297D01*
X173283Y562047D01*
X173450Y561630D01*
X173492Y561255D01*
X173408Y560880D01*
X173283Y560630D01*
X173033Y560380D01*
X172742Y560213D01*
X172450Y560130D01*
X172158D01*
X171867Y560213D01*
X171617Y560338D01*
X171408Y560505D01*
G01X170058Y560422D02*
X169767Y560213D01*
X169433Y560130D01*
X169100Y560213D01*
X168808Y560463D01*
X168600Y560838D01*
X168517Y561213D01*
Y561672D01*
X168600Y562047D01*
X168808Y562380D01*
X169058Y562547D01*
X169350Y562630D01*
X169683Y562547D01*
X169933Y562380D01*
X170100Y562130D01*
X170183Y561797D01*
X170100Y561505D01*
X169892Y561213D01*
X169642Y561047D01*
X169350Y561005D01*
X169017Y561088D01*
X168767Y561297D01*
X168517Y561672D01*
G01X166958Y560422D02*
X166667Y560213D01*
X166333Y560130D01*
X166000Y560213D01*
X165708Y560463D01*
X165500Y560838D01*
X165417Y561213D01*
Y561672D01*
X165500Y562047D01*
X165708Y562380D01*
X165958Y562547D01*
X166250Y562630D01*
X166583Y562547D01*
X166833Y562380D01*
X167000Y562130D01*
X167083Y561797D01*
X167000Y561505D01*
X166792Y561213D01*
X166542Y561047D01*
X166250Y561005D01*
X165917Y561088D01*
X165667Y561297D01*
X165417Y561672D01*
G01X163150Y560130D02*
X162858Y560172D01*
X162525Y560297D01*
X162317Y560505D01*
X162233Y560797D01*
X162317Y561088D01*
X162567Y561338D01*
X162942Y561463D01*
X163358D01*
X163608Y561547D01*
X163817Y561755D01*
X163900Y562047D01*
X163775Y562338D01*
X163483Y562547D01*
X163150Y562630D01*
X162817Y562547D01*
X162525Y562338D01*
X162400Y562047D01*
X162483Y561755D01*
X162692Y561547D01*
X162942Y561463D01*
X163358D01*
X163733Y561338D01*
X163983Y561088D01*
X164067Y560797D01*
X163983Y560505D01*
X163775Y560297D01*
X163442Y560172D01*
X163150Y560130D01*
G01X177062Y597379D02*
X177312Y597504D01*
X177604Y597587D01*
X177937D01*
X178312Y597462D01*
X178604Y597254D01*
X178812Y597004D01*
X178979Y596587D01*
X179021Y596212D01*
X178937Y595837D01*
X178812Y595587D01*
X178562Y595337D01*
X178271Y595170D01*
X177979Y595087D01*
X177687D01*
X177396Y595170D01*
X177146Y595295D01*
X176937Y595462D01*
G01X175796D02*
X175546Y595254D01*
X175254Y595129D01*
X174879Y595087D01*
X174504Y595170D01*
X174212Y595337D01*
X174004Y595629D01*
X173962Y595962D01*
X174046Y596295D01*
X174254Y596504D01*
X174546Y596670D01*
X174837Y596712D01*
X175129Y596670D01*
X175504Y596504D01*
X175379Y597587D01*
X174254D01*
G01X172696Y595462D02*
X172446Y595254D01*
X172154Y595129D01*
X171779Y595087D01*
X171404Y595170D01*
X171112Y595337D01*
X170904Y595629D01*
X170862Y595962D01*
X170946Y596295D01*
X171154Y596504D01*
X171446Y596670D01*
X171737Y596712D01*
X172029Y596670D01*
X172404Y596504D01*
X172279Y597587D01*
X171154D01*
G01X161933Y636667D02*
Y639167D01*
X160892D01*
X160558Y639042D01*
X160350Y638875D01*
X160267Y638542D01*
X160350Y638209D01*
X160600Y638000D01*
X160892Y637875D01*
X161933D01*
G01X160892D02*
X160267Y636667D01*
G01X158000D02*
Y639167D01*
X158500Y638667D01*
G01Y636667D02*
X157500D01*
G01X155608Y636959D02*
X155317Y636750D01*
X154983Y636667D01*
X154650Y636750D01*
X154358Y637000D01*
X154150Y637375D01*
X154067Y637750D01*
Y638209D01*
X154150Y638584D01*
X154358Y638917D01*
X154608Y639084D01*
X154900Y639167D01*
X155233Y639084D01*
X155483Y638917D01*
X155650Y638667D01*
X155733Y638334D01*
X155650Y638042D01*
X155442Y637750D01*
X155192Y637584D01*
X154900Y637542D01*
X154567Y637625D01*
X154317Y637834D01*
X154067Y638209D01*
G01X151800Y636667D02*
Y639167D01*
X152300Y638667D01*
G01Y636667D02*
X151300D01*
G01X202890Y613700D02*
Y609700D01*
X195490D01*
G01X203483Y657167D02*
Y659667D01*
X202442D01*
X202108Y659542D01*
X201900Y659375D01*
X201817Y659042D01*
X201900Y658709D01*
X202150Y658500D01*
X202442Y658375D01*
X203483D01*
G01X202442D02*
X201817Y657167D01*
G01X199550D02*
Y659667D01*
X200050Y659167D01*
G01Y657167D02*
X199050D01*
G01X197158Y657459D02*
X196867Y657250D01*
X196533Y657167D01*
X196200Y657250D01*
X195908Y657500D01*
X195700Y657875D01*
X195617Y658250D01*
Y658709D01*
X195700Y659084D01*
X195908Y659417D01*
X196158Y659584D01*
X196450Y659667D01*
X196783Y659584D01*
X197033Y659417D01*
X197200Y659167D01*
X197283Y658834D01*
X197200Y658542D01*
X196992Y658250D01*
X196742Y658084D01*
X196450Y658042D01*
X196117Y658125D01*
X195867Y658334D01*
X195617Y658709D01*
G01X194142Y659250D02*
X193892Y659500D01*
X193600Y659625D01*
X193267Y659667D01*
X192850Y659584D01*
X192558Y659375D01*
X192475Y659125D01*
X192517Y658875D01*
X192683Y658667D01*
X193517Y658250D01*
X193892Y657959D01*
X194142Y657542D01*
X194225Y657167D01*
X192475D01*
G01X200040Y622780D02*
Y626780D01*
X207440D01*
G01X163667Y632517D02*
X166167D01*
Y633558D01*
X166042Y633892D01*
X165875Y634100D01*
X165542Y634183D01*
X165209Y634100D01*
X165000Y633850D01*
X164875Y633558D01*
Y632517D01*
G01Y633558D02*
X163667Y634183D01*
G01X164167Y635533D02*
X163875Y635783D01*
X163709Y636117D01*
X163667Y636492D01*
X163709Y636825D01*
X163917Y637158D01*
X164167Y637367D01*
X164417Y637408D01*
X164709Y637325D01*
X164917Y637033D01*
X165000Y636742D01*
Y636367D01*
G01Y636742D02*
X165125Y636992D01*
X165334Y637200D01*
X165584Y637283D01*
X165834Y637200D01*
X166042Y636992D01*
X166167Y636617D01*
X166125Y636242D01*
X165959Y635867D01*
G01X163667Y639550D02*
X166167D01*
X165667Y639050D01*
G01X163667D02*
Y640050D01*
G01X164042Y641733D02*
X163834Y641983D01*
X163709Y642275D01*
X163667Y642650D01*
X163750Y643025D01*
X163917Y643317D01*
X164209Y643525D01*
X164542Y643567D01*
X164875Y643483D01*
X165084Y643275D01*
X165250Y642983D01*
X165292Y642692D01*
X165250Y642400D01*
X165084Y642025D01*
X166167Y642150D01*
Y643275D01*
G01X203020Y614140D02*
X207020D01*
Y606740D01*
G01X189667Y642017D02*
X192167D01*
Y643058D01*
X192042Y643392D01*
X191875Y643600D01*
X191542Y643683D01*
X191209Y643600D01*
X191000Y643350D01*
X190875Y643058D01*
Y642017D01*
G01Y643058D02*
X189667Y643683D01*
G01X190167Y645033D02*
X189875Y645283D01*
X189709Y645617D01*
X189667Y645992D01*
X189709Y646325D01*
X189917Y646658D01*
X190167Y646867D01*
X190417Y646908D01*
X190709Y646825D01*
X190917Y646533D01*
X191000Y646242D01*
Y645867D01*
G01Y646242D02*
X191125Y646492D01*
X191334Y646700D01*
X191584Y646783D01*
X191834Y646700D01*
X192042Y646492D01*
X192167Y646117D01*
X192125Y645742D01*
X191959Y645367D01*
G01X191750Y648258D02*
X192000Y648508D01*
X192125Y648800D01*
X192167Y649133D01*
X192084Y649550D01*
X191875Y649842D01*
X191625Y649925D01*
X191375Y649883D01*
X191167Y649717D01*
X190750Y648883D01*
X190459Y648508D01*
X190042Y648258D01*
X189667Y648175D01*
Y649925D01*
G01X190167Y651233D02*
X189875Y651483D01*
X189709Y651817D01*
X189667Y652192D01*
X189709Y652525D01*
X189917Y652858D01*
X190167Y653067D01*
X190417Y653108D01*
X190709Y653025D01*
X190917Y652733D01*
X191000Y652442D01*
Y652067D01*
G01Y652442D02*
X191125Y652692D01*
X191334Y652900D01*
X191584Y652983D01*
X191834Y652900D01*
X192042Y652692D01*
X192167Y652317D01*
X192125Y651942D01*
X191959Y651567D01*
G01X195191Y638588D02*
X199191D01*
Y631188D01*
G01X179900Y633300D02*
Y637300D01*
X187300D01*
G01X160083Y625767D02*
Y628267D01*
X159042D01*
X158708Y628142D01*
X158500Y627975D01*
X158417Y627642D01*
X158500Y627309D01*
X158750Y627100D01*
X159042Y626975D01*
X160083D01*
G01X159042D02*
X158417Y625767D01*
G01X157067Y626267D02*
X156817Y625975D01*
X156483Y625809D01*
X156108Y625767D01*
X155775Y625809D01*
X155442Y626017D01*
X155233Y626267D01*
X155192Y626517D01*
X155275Y626809D01*
X155567Y627017D01*
X155858Y627100D01*
X156233D01*
G01X155858D02*
X155608Y627225D01*
X155400Y627434D01*
X155317Y627684D01*
X155400Y627934D01*
X155608Y628142D01*
X155983Y628267D01*
X156358Y628225D01*
X156733Y628059D01*
G01X153842Y627850D02*
X153592Y628100D01*
X153300Y628225D01*
X152967Y628267D01*
X152550Y628184D01*
X152258Y627975D01*
X152175Y627725D01*
X152217Y627475D01*
X152383Y627267D01*
X153217Y626850D01*
X153592Y626559D01*
X153842Y626142D01*
X153925Y625767D01*
X152175D01*
G01X150742Y626809D02*
X150450Y627100D01*
X150200Y627267D01*
X149867Y627350D01*
X149575Y627267D01*
X149367Y627100D01*
X149200Y626850D01*
X149158Y626559D01*
X149200Y626309D01*
X149367Y626059D01*
X149617Y625850D01*
X149908Y625767D01*
X150242Y625850D01*
X150533Y626100D01*
X150700Y626475D01*
X150742Y626892D01*
X150658Y627434D01*
X150533Y627725D01*
X150325Y628017D01*
X150033Y628225D01*
X149742Y628267D01*
X149450Y628184D01*
X149242Y627975D01*
G01X158500Y604760D02*
Y608760D01*
X165900D01*
G01X152067Y608743D02*
X148067D01*
Y616143D01*
G01X185167Y641517D02*
X187667D01*
Y642558D01*
X187542Y642892D01*
X187375Y643100D01*
X187042Y643183D01*
X186709Y643100D01*
X186500Y642850D01*
X186375Y642558D01*
Y641517D01*
G01Y642558D02*
X185167Y643183D01*
G01X185667Y644533D02*
X185375Y644783D01*
X185209Y645117D01*
X185167Y645492D01*
X185209Y645825D01*
X185417Y646158D01*
X185667Y646367D01*
X185917Y646408D01*
X186209Y646325D01*
X186417Y646033D01*
X186500Y645742D01*
Y645367D01*
G01Y645742D02*
X186625Y645992D01*
X186834Y646200D01*
X187084Y646283D01*
X187334Y646200D01*
X187542Y645992D01*
X187667Y645617D01*
X187625Y645242D01*
X187459Y644867D01*
G01X185167Y648550D02*
X187667D01*
X187167Y648050D01*
G01X185167D02*
Y649050D01*
G01X187667Y651650D02*
X187584Y651317D01*
X187375Y651067D01*
X187125Y650900D01*
X186792Y650775D01*
X186417Y650733D01*
X186042Y650775D01*
X185709Y650900D01*
X185459Y651067D01*
X185250Y651317D01*
X185167Y651650D01*
X185250Y651983D01*
X185459Y652233D01*
X185709Y652400D01*
X186042Y652525D01*
X186417Y652567D01*
X186792Y652525D01*
X187125Y652400D01*
X187375Y652233D01*
X187584Y651983D01*
X187667Y651650D01*
G01X190911Y638648D02*
X194911D01*
Y631248D01*
G01X174893Y637303D02*
Y633303D01*
X167493D01*
G01X215533Y599867D02*
Y602367D01*
X214492D01*
X214158Y602242D01*
X213950Y602075D01*
X213867Y601742D01*
X213950Y601409D01*
X214200Y601200D01*
X214492Y601075D01*
X215533D01*
G01X214492D02*
X213867Y599867D01*
G01X212517Y600367D02*
X212267Y600075D01*
X211933Y599909D01*
X211558Y599867D01*
X211225Y599909D01*
X210892Y600117D01*
X210683Y600367D01*
X210642Y600617D01*
X210725Y600909D01*
X211017Y601117D01*
X211308Y601200D01*
X211683D01*
G01X211308D02*
X211058Y601325D01*
X210850Y601534D01*
X210767Y601784D01*
X210850Y602034D01*
X211058Y602242D01*
X211433Y602367D01*
X211808Y602325D01*
X212183Y602159D01*
G01X209292Y600909D02*
X209000Y601200D01*
X208750Y601367D01*
X208417Y601450D01*
X208125Y601367D01*
X207917Y601200D01*
X207750Y600950D01*
X207708Y600659D01*
X207750Y600409D01*
X207917Y600159D01*
X208167Y599950D01*
X208458Y599867D01*
X208792Y599950D01*
X209083Y600200D01*
X209250Y600575D01*
X209292Y600992D01*
X209208Y601534D01*
X209083Y601825D01*
X208875Y602117D01*
X208583Y602325D01*
X208292Y602367D01*
X208000Y602284D01*
X207792Y602075D01*
G01X206192Y600909D02*
X205900Y601200D01*
X205650Y601367D01*
X205317Y601450D01*
X205025Y601367D01*
X204817Y601200D01*
X204650Y600950D01*
X204608Y600659D01*
X204650Y600409D01*
X204817Y600159D01*
X205067Y599950D01*
X205358Y599867D01*
X205692Y599950D01*
X205983Y600200D01*
X206150Y600575D01*
X206192Y600992D01*
X206108Y601534D01*
X205983Y601825D01*
X205775Y602117D01*
X205483Y602325D01*
X205192Y602367D01*
X204900Y602284D01*
X204692Y602075D01*
G01X202160Y601340D02*
Y597340D01*
X194760D01*
G01X189650Y609360D02*
Y605360D01*
X182250D01*
G01X201700Y639270D02*
Y643270D01*
X209100D01*
G01X209190Y639250D02*
Y635250D01*
X201790D01*
G01X201200Y651100D02*
Y655100D01*
X208600D01*
G01X209108Y651294D02*
Y655294D01*
X216508D01*
G01X214983Y617167D02*
Y619667D01*
X213942D01*
X213608Y619542D01*
X213400Y619375D01*
X213317Y619042D01*
X213400Y618709D01*
X213650Y618500D01*
X213942Y618375D01*
X214983D01*
G01X213942D02*
X213317Y617167D01*
G01X211842Y619250D02*
X211592Y619500D01*
X211300Y619625D01*
X210967Y619667D01*
X210550Y619584D01*
X210258Y619375D01*
X210175Y619125D01*
X210217Y618875D01*
X210383Y618667D01*
X211217Y618250D01*
X211592Y617959D01*
X211842Y617542D01*
X211925Y617167D01*
X210175D01*
G01X207950D02*
X207658Y617209D01*
X207325Y617334D01*
X207117Y617542D01*
X207033Y617834D01*
X207117Y618125D01*
X207367Y618375D01*
X207742Y618500D01*
X208158D01*
X208408Y618584D01*
X208617Y618792D01*
X208700Y619084D01*
X208575Y619375D01*
X208283Y619584D01*
X207950Y619667D01*
X207617Y619584D01*
X207325Y619375D01*
X207200Y619084D01*
X207283Y618792D01*
X207492Y618584D01*
X207742Y618500D01*
X208158D01*
X208533Y618375D01*
X208783Y618125D01*
X208867Y617834D01*
X208783Y617542D01*
X208575Y617334D01*
X208242Y617209D01*
X207950Y617167D01*
G01X204850D02*
Y619667D01*
X205350Y619167D01*
G01Y617167D02*
X204350D01*
G01X203316Y622590D02*
Y618590D01*
X195916D01*
G01X162403Y631727D02*
Y634227D01*
X161362D01*
X161028Y634102D01*
X160820Y633935D01*
X160737Y633602D01*
X160820Y633269D01*
X161070Y633060D01*
X161362Y632935D01*
X162403D01*
G01X161362D02*
X160737Y631727D01*
G01X159262Y633810D02*
X159012Y634060D01*
X158720Y634185D01*
X158387Y634227D01*
X157970Y634144D01*
X157678Y633935D01*
X157595Y633685D01*
X157637Y633435D01*
X157803Y633227D01*
X158637Y632810D01*
X159012Y632519D01*
X159262Y632102D01*
X159345Y631727D01*
X157595D01*
G01X155453D02*
X155370Y632269D01*
X155245Y632727D01*
X155078Y633144D01*
X154870Y633602D01*
X154537Y634227D01*
X156203D01*
G01X152978Y632019D02*
X152687Y631810D01*
X152353Y631727D01*
X152020Y631810D01*
X151728Y632060D01*
X151520Y632435D01*
X151437Y632810D01*
Y633269D01*
X151520Y633644D01*
X151728Y633977D01*
X151978Y634144D01*
X152270Y634227D01*
X152603Y634144D01*
X152853Y633977D01*
X153020Y633727D01*
X153103Y633394D01*
X153020Y633102D01*
X152812Y632810D01*
X152562Y632644D01*
X152270Y632602D01*
X151937Y632685D01*
X151687Y632894D01*
X151437Y633269D01*
G01X195050Y605600D02*
Y609600D01*
X202450D01*
G01X167502Y627826D02*
Y631826D01*
X174902D01*
G01X180370Y598847D02*
Y601347D01*
X179329D01*
X178995Y601222D01*
X178787Y601055D01*
X178704Y600722D01*
X178787Y600389D01*
X179037Y600180D01*
X179329Y600055D01*
X180370D01*
G01X179329D02*
X178704Y598847D01*
G01X176437D02*
Y601347D01*
X176937Y600847D01*
G01Y598847D02*
X175937D01*
G01X172837D02*
Y601347D01*
X174379Y599555D01*
X172295D01*
G01X171154Y599347D02*
X170904Y599055D01*
X170570Y598889D01*
X170195Y598847D01*
X169862Y598889D01*
X169529Y599097D01*
X169320Y599347D01*
X169279Y599597D01*
X169362Y599889D01*
X169654Y600097D01*
X169945Y600180D01*
X170320D01*
G01X169945D02*
X169695Y600305D01*
X169487Y600514D01*
X169404Y600764D01*
X169487Y601014D01*
X169695Y601222D01*
X170070Y601347D01*
X170445Y601305D01*
X170820Y601139D01*
G01X153457Y604562D02*
Y600562D01*
X146057D01*
G01X167150Y597267D02*
Y594767D01*
G01X168108Y597267D02*
X166192D01*
G01X164883Y594767D02*
Y597267D01*
X163883D01*
X163550Y597142D01*
X163300Y596850D01*
X163217Y596517D01*
X163300Y596184D01*
X163508Y595934D01*
X163883Y595809D01*
X164883D01*
G01X161742D02*
X161450Y596100D01*
X161200Y596267D01*
X160867Y596350D01*
X160575Y596267D01*
X160367Y596100D01*
X160200Y595850D01*
X160158Y595559D01*
X160200Y595309D01*
X160367Y595059D01*
X160617Y594850D01*
X160908Y594767D01*
X161242Y594850D01*
X161533Y595100D01*
X161700Y595475D01*
X161742Y595892D01*
X161658Y596434D01*
X161533Y596725D01*
X161325Y597017D01*
X161033Y597225D01*
X160742Y597267D01*
X160450Y597184D01*
X160242Y596975D01*
G01X158767Y595142D02*
X158517Y594934D01*
X158225Y594809D01*
X157850Y594767D01*
X157475Y594850D01*
X157183Y595017D01*
X156975Y595309D01*
X156933Y595642D01*
X157017Y595975D01*
X157225Y596184D01*
X157517Y596350D01*
X157808Y596392D01*
X158100Y596350D01*
X158475Y596184D01*
X158350Y597267D01*
X157225D01*
G01X161500Y624067D02*
Y621567D01*
G01X162458Y624067D02*
X160542D01*
G01X159233Y621567D02*
Y624067D01*
X158233D01*
X157900Y623942D01*
X157650Y623650D01*
X157567Y623317D01*
X157650Y622984D01*
X157858Y622734D01*
X158233Y622609D01*
X159233D01*
G01X156092D02*
X155800Y622900D01*
X155550Y623067D01*
X155217Y623150D01*
X154925Y623067D01*
X154717Y622900D01*
X154550Y622650D01*
X154508Y622359D01*
X154550Y622109D01*
X154717Y621859D01*
X154967Y621650D01*
X155258Y621567D01*
X155592Y621650D01*
X155883Y621900D01*
X156050Y622275D01*
X156092Y622692D01*
X156008Y623234D01*
X155883Y623525D01*
X155675Y623817D01*
X155383Y624025D01*
X155092Y624067D01*
X154800Y623984D01*
X154592Y623775D01*
G01X152992Y622609D02*
X152700Y622900D01*
X152450Y623067D01*
X152117Y623150D01*
X151825Y623067D01*
X151617Y622900D01*
X151450Y622650D01*
X151408Y622359D01*
X151450Y622109D01*
X151617Y621859D01*
X151867Y621650D01*
X152158Y621567D01*
X152492Y621650D01*
X152783Y621900D01*
X152950Y622275D01*
X152992Y622692D01*
X152908Y623234D01*
X152783Y623525D01*
X152575Y623817D01*
X152283Y624025D01*
X151992Y624067D01*
X151700Y623984D01*
X151492Y623775D01*
G01X147167Y617850D02*
X144667D01*
G01X147167Y616892D02*
Y618808D01*
G01X144667Y620117D02*
X147167D01*
Y621117D01*
X147042Y621450D01*
X146750Y621700D01*
X146417Y621783D01*
X146084Y621700D01*
X145834Y621492D01*
X145709Y621117D01*
Y620117D01*
G01Y623258D02*
X146000Y623550D01*
X146167Y623800D01*
X146250Y624133D01*
X146167Y624425D01*
X146000Y624633D01*
X145750Y624800D01*
X145459Y624842D01*
X145209Y624800D01*
X144959Y624633D01*
X144750Y624383D01*
X144667Y624092D01*
X144750Y623758D01*
X145000Y623467D01*
X145375Y623300D01*
X145792Y623258D01*
X146334Y623342D01*
X146625Y623467D01*
X146917Y623675D01*
X147125Y623967D01*
X147167Y624258D01*
X147084Y624550D01*
X146875Y624758D01*
G01X145167Y626233D02*
X144875Y626483D01*
X144709Y626817D01*
X144667Y627192D01*
X144709Y627525D01*
X144917Y627858D01*
X145167Y628067D01*
X145417Y628108D01*
X145709Y628025D01*
X145917Y627733D01*
X146000Y627442D01*
Y627067D01*
G01Y627442D02*
X146125Y627692D01*
X146334Y627900D01*
X146584Y627983D01*
X146834Y627900D01*
X147042Y627692D01*
X147167Y627317D01*
X147125Y626942D01*
X146959Y626567D01*
G01X165600Y620467D02*
Y617967D01*
G01X166558Y620467D02*
X164642D01*
G01X163333Y617967D02*
Y620467D01*
X162333D01*
X162000Y620342D01*
X161750Y620050D01*
X161667Y619717D01*
X161750Y619384D01*
X161958Y619134D01*
X162333Y619009D01*
X163333D01*
G01X159400Y617967D02*
Y620467D01*
X159900Y619967D01*
G01Y617967D02*
X158900D01*
G01X157008Y618259D02*
X156717Y618050D01*
X156383Y617967D01*
X156050Y618050D01*
X155758Y618300D01*
X155550Y618675D01*
X155467Y619050D01*
Y619509D01*
X155550Y619884D01*
X155758Y620217D01*
X156008Y620384D01*
X156300Y620467D01*
X156633Y620384D01*
X156883Y620217D01*
X157050Y619967D01*
X157133Y619634D01*
X157050Y619342D01*
X156842Y619050D01*
X156592Y618884D01*
X156300Y618842D01*
X155967Y618925D01*
X155717Y619134D01*
X155467Y619509D01*
G01X153200Y620467D02*
X153533Y620384D01*
X153783Y620175D01*
X153950Y619925D01*
X154075Y619592D01*
X154117Y619217D01*
X154075Y618842D01*
X153950Y618509D01*
X153783Y618259D01*
X153533Y618050D01*
X153200Y617967D01*
X152867Y618050D01*
X152617Y618259D01*
X152450Y618509D01*
X152325Y618842D01*
X152283Y619217D01*
X152325Y619592D01*
X152450Y619925D01*
X152617Y620175D01*
X152867Y620384D01*
X153200Y620467D01*
G01X167930Y625490D02*
Y618490D01*
X181330D01*
Y625490D01*
X167930D01*
G01X214233Y667192D02*
X214483Y667317D01*
X214775Y667400D01*
X215108D01*
X215483Y667275D01*
X215775Y667067D01*
X215983Y666817D01*
X216150Y666400D01*
X216192Y666025D01*
X216108Y665650D01*
X215983Y665400D01*
X215733Y665150D01*
X215442Y664983D01*
X215150Y664900D01*
X214858D01*
X214567Y664983D01*
X214317Y665108D01*
X214108Y665275D01*
G01X212050Y664900D02*
Y667400D01*
X212550Y666900D01*
G01Y664900D02*
X211550D01*
G01X208950D02*
Y667400D01*
X209450Y666900D01*
G01Y664900D02*
X208450D01*
G01X205933D02*
X205850Y665442D01*
X205725Y665900D01*
X205558Y666317D01*
X205350Y666775D01*
X205017Y667400D01*
X206683D01*
G01X201733Y663459D02*
X201983Y663584D01*
X202275Y663667D01*
X202608D01*
X202983Y663542D01*
X203275Y663334D01*
X203483Y663084D01*
X203650Y662667D01*
X203692Y662292D01*
X203608Y661917D01*
X203483Y661667D01*
X203233Y661417D01*
X202942Y661250D01*
X202650Y661167D01*
X202358D01*
X202067Y661250D01*
X201817Y661375D01*
X201608Y661542D01*
G01X199550Y661167D02*
Y663667D01*
X200050Y663167D01*
G01Y661167D02*
X199050D01*
G01X197242Y663250D02*
X196992Y663500D01*
X196700Y663625D01*
X196367Y663667D01*
X195950Y663584D01*
X195658Y663375D01*
X195575Y663125D01*
X195617Y662875D01*
X195783Y662667D01*
X196617Y662250D01*
X196992Y661959D01*
X197242Y661542D01*
X197325Y661167D01*
X195575D01*
G01X193350D02*
Y663667D01*
X193850Y663167D01*
G01Y661167D02*
X192850D01*
G01X214433Y675359D02*
X214683Y675484D01*
X214975Y675567D01*
X215308D01*
X215683Y675442D01*
X215975Y675234D01*
X216183Y674984D01*
X216350Y674567D01*
X216392Y674192D01*
X216308Y673817D01*
X216183Y673567D01*
X215933Y673317D01*
X215642Y673150D01*
X215350Y673067D01*
X215058D01*
X214767Y673150D01*
X214517Y673275D01*
X214308Y673442D01*
G01X212250Y673067D02*
Y675567D01*
X212750Y675067D01*
G01Y673067D02*
X211750D01*
G01X209942Y675150D02*
X209692Y675400D01*
X209400Y675525D01*
X209067Y675567D01*
X208650Y675484D01*
X208358Y675275D01*
X208275Y675025D01*
X208317Y674775D01*
X208483Y674567D01*
X209317Y674150D01*
X209692Y673859D01*
X209942Y673442D01*
X210025Y673067D01*
X208275D01*
G01X205550D02*
Y675567D01*
X207092Y673775D01*
X205008D01*
G01X215883Y668700D02*
Y671200D01*
X214842D01*
X214508Y671075D01*
X214300Y670908D01*
X214217Y670575D01*
X214300Y670242D01*
X214550Y670033D01*
X214842Y669908D01*
X215883D01*
G01X214842D02*
X214217Y668700D01*
G01X211450D02*
Y671200D01*
X212992Y669408D01*
X210908D01*
G01X208850Y671200D02*
X209183Y671117D01*
X209433Y670908D01*
X209600Y670658D01*
X209725Y670325D01*
X209767Y669950D01*
X209725Y669575D01*
X209600Y669242D01*
X209433Y668992D01*
X209183Y668783D01*
X208850Y668700D01*
X208517Y668783D01*
X208267Y668992D01*
X208100Y669242D01*
X207975Y669575D01*
X207933Y669950D01*
X207975Y670325D01*
X208100Y670658D01*
X208267Y670908D01*
X208517Y671117D01*
X208850Y671200D01*
G01X205750Y668700D02*
Y671200D01*
X206250Y670700D01*
G01Y668700D02*
X205250D01*
G01X215983Y661000D02*
Y663500D01*
X214942D01*
X214608Y663375D01*
X214400Y663208D01*
X214317Y662875D01*
X214400Y662542D01*
X214650Y662333D01*
X214942Y662208D01*
X215983D01*
G01X214942D02*
X214317Y661000D01*
G01X211550D02*
Y663500D01*
X213092Y661708D01*
X211008D01*
G01X208950Y663500D02*
X209283Y663417D01*
X209533Y663208D01*
X209700Y662958D01*
X209825Y662625D01*
X209867Y662250D01*
X209825Y661875D01*
X209700Y661542D01*
X209533Y661292D01*
X209283Y661083D01*
X208950Y661000D01*
X208617Y661083D01*
X208367Y661292D01*
X208200Y661542D01*
X208075Y661875D01*
X208033Y662250D01*
X208075Y662625D01*
X208200Y662958D01*
X208367Y663208D01*
X208617Y663417D01*
X208950Y663500D01*
G01X205350Y661000D02*
Y663500D01*
X206892Y661708D01*
X204808D01*
G01X202983Y669167D02*
Y671667D01*
X201942D01*
X201608Y671542D01*
X201400Y671375D01*
X201317Y671042D01*
X201400Y670709D01*
X201650Y670500D01*
X201942Y670375D01*
X202983D01*
G01X201942D02*
X201317Y669167D01*
G01X198550D02*
Y671667D01*
X200092Y669875D01*
X198008D01*
G01X195950Y671667D02*
X196283Y671584D01*
X196533Y671375D01*
X196700Y671125D01*
X196825Y670792D01*
X196867Y670417D01*
X196825Y670042D01*
X196700Y669709D01*
X196533Y669459D01*
X196283Y669250D01*
X195950Y669167D01*
X195617Y669250D01*
X195367Y669459D01*
X195200Y669709D01*
X195075Y670042D01*
X195033Y670417D01*
X195075Y670792D01*
X195200Y671125D01*
X195367Y671375D01*
X195617Y671584D01*
X195950Y671667D01*
G01X192850Y669167D02*
X192558Y669209D01*
X192225Y669334D01*
X192017Y669542D01*
X191933Y669834D01*
X192017Y670125D01*
X192267Y670375D01*
X192642Y670500D01*
X193058D01*
X193308Y670584D01*
X193517Y670792D01*
X193600Y671084D01*
X193475Y671375D01*
X193183Y671584D01*
X192850Y671667D01*
X192517Y671584D01*
X192225Y671375D01*
X192100Y671084D01*
X192183Y670792D01*
X192392Y670584D01*
X192642Y670500D01*
X193058D01*
X193433Y670375D01*
X193683Y670125D01*
X193767Y669834D01*
X193683Y669542D01*
X193475Y669334D01*
X193142Y669209D01*
X192850Y669167D01*
G01X202983Y665167D02*
Y667667D01*
X201942D01*
X201608Y667542D01*
X201400Y667375D01*
X201317Y667042D01*
X201400Y666709D01*
X201650Y666500D01*
X201942Y666375D01*
X202983D01*
G01X201942D02*
X201317Y665167D01*
G01X198550D02*
Y667667D01*
X200092Y665875D01*
X198008D01*
G01X195950Y665167D02*
Y667667D01*
X196450Y667167D01*
G01Y665167D02*
X195450D01*
G01X192850D02*
Y667667D01*
X193350Y667167D01*
G01Y665167D02*
X192350D01*
G01X202983Y673167D02*
Y675667D01*
X201942D01*
X201608Y675542D01*
X201400Y675375D01*
X201317Y675042D01*
X201400Y674709D01*
X201650Y674500D01*
X201942Y674375D01*
X202983D01*
G01X201942D02*
X201317Y673167D01*
G01X198550D02*
Y675667D01*
X200092Y673875D01*
X198008D01*
G01X195950Y673167D02*
Y675667D01*
X196450Y675167D01*
G01Y673167D02*
X195450D01*
G01X192350D02*
Y675667D01*
X193892Y673875D01*
X191808D01*
G01X215683Y677267D02*
Y679767D01*
X214642D01*
X214308Y679642D01*
X214100Y679475D01*
X214017Y679142D01*
X214100Y678809D01*
X214350Y678600D01*
X214642Y678475D01*
X215683D01*
G01X214642D02*
X214017Y677267D01*
G01X211250D02*
Y679767D01*
X212792Y677975D01*
X210708D01*
G01X208650Y677267D02*
Y679767D01*
X209150Y679267D01*
G01Y677267D02*
X208150D01*
G01X206342Y678309D02*
X206050Y678600D01*
X205800Y678767D01*
X205467Y678850D01*
X205175Y678767D01*
X204967Y678600D01*
X204800Y678350D01*
X204758Y678059D01*
X204800Y677809D01*
X204967Y677559D01*
X205217Y677350D01*
X205508Y677267D01*
X205842Y677350D01*
X206133Y677600D01*
X206300Y677975D01*
X206342Y678392D01*
X206258Y678934D01*
X206133Y679225D01*
X205925Y679517D01*
X205633Y679725D01*
X205342Y679767D01*
X205050Y679684D01*
X204842Y679475D01*
G01X172959Y715767D02*
X173084Y715517D01*
X173167Y715225D01*
Y714892D01*
X173042Y714517D01*
X172834Y714225D01*
X172584Y714017D01*
X172167Y713850D01*
X171792Y713808D01*
X171417Y713892D01*
X171167Y714017D01*
X170917Y714267D01*
X170750Y714558D01*
X170667Y714850D01*
Y715142D01*
X170750Y715433D01*
X170875Y715683D01*
X171042Y715892D01*
G01X170667Y717950D02*
X173167D01*
X172667Y717450D01*
G01X170667D02*
Y718450D01*
G01Y720967D02*
X171209Y721050D01*
X171667Y721175D01*
X172084Y721342D01*
X172542Y721550D01*
X173167Y721883D01*
Y720217D01*
G01X170667Y724150D02*
X170709Y724442D01*
X170834Y724775D01*
X171042Y724983D01*
X171334Y725067D01*
X171625Y724983D01*
X171875Y724733D01*
X172000Y724358D01*
Y723942D01*
X172084Y723692D01*
X172292Y723483D01*
X172584Y723400D01*
X172875Y723525D01*
X173084Y723817D01*
X173167Y724150D01*
X173084Y724483D01*
X172875Y724775D01*
X172584Y724900D01*
X172292Y724817D01*
X172084Y724608D01*
X172000Y724358D01*
Y723942D01*
X171875Y723567D01*
X171625Y723317D01*
X171334Y723233D01*
X171042Y723317D01*
X170834Y723525D01*
X170709Y723858D01*
X170667Y724150D01*
G01X165167Y714017D02*
X167667D01*
Y715058D01*
X167542Y715392D01*
X167375Y715600D01*
X167042Y715683D01*
X166709Y715600D01*
X166500Y715350D01*
X166375Y715058D01*
Y714017D01*
G01Y715058D02*
X165167Y715683D01*
G01Y718450D02*
X167667D01*
X165875Y716908D01*
Y718992D01*
G01X165167Y721050D02*
X165209Y721342D01*
X165334Y721675D01*
X165542Y721883D01*
X165834Y721967D01*
X166125Y721883D01*
X166375Y721633D01*
X166500Y721258D01*
Y720842D01*
X166584Y720592D01*
X166792Y720383D01*
X167084Y720300D01*
X167375Y720425D01*
X167584Y720717D01*
X167667Y721050D01*
X167584Y721383D01*
X167375Y721675D01*
X167084Y721800D01*
X166792Y721717D01*
X166584Y721508D01*
X166500Y721258D01*
Y720842D01*
X166375Y720467D01*
X166125Y720217D01*
X165834Y720133D01*
X165542Y720217D01*
X165334Y720425D01*
X165209Y720758D01*
X165167Y721050D01*
G01Y724650D02*
X167667D01*
X165875Y723108D01*
Y725192D01*
G01X153200Y712500D02*
Y717700D01*
G01X146200Y712500D02*
Y720300D01*
G01X153200Y712500D02*
X146200D01*
G01X153200Y725900D02*
Y717200D01*
G01X146200Y719500D02*
Y725900D01*
G01D02*
X153200D01*
G01X245592Y499867D02*
X245717Y499617D01*
X245800Y499325D01*
Y498992D01*
X245675Y498617D01*
X245467Y498325D01*
X245217Y498117D01*
X244800Y497950D01*
X244425Y497908D01*
X244050Y497992D01*
X243800Y498117D01*
X243550Y498367D01*
X243383Y498658D01*
X243300Y498950D01*
Y499242D01*
X243383Y499533D01*
X243508Y499783D01*
X243675Y499992D01*
G01X243300Y502050D02*
X245800D01*
X245300Y501550D01*
G01X243300D02*
Y502550D01*
G01Y505150D02*
X245800D01*
X245300Y504650D01*
G01X243300D02*
Y505650D01*
G01X244342Y507458D02*
X244633Y507750D01*
X244800Y508000D01*
X244883Y508333D01*
X244800Y508625D01*
X244633Y508833D01*
X244383Y509000D01*
X244092Y509042D01*
X243842Y509000D01*
X243592Y508833D01*
X243383Y508583D01*
X243300Y508292D01*
X243383Y507958D01*
X243633Y507667D01*
X244008Y507500D01*
X244425Y507458D01*
X244967Y507542D01*
X245258Y507667D01*
X245550Y507875D01*
X245758Y508167D01*
X245800Y508458D01*
X245717Y508750D01*
X245508Y508958D01*
G01X234200Y512067D02*
X236700D01*
Y513108D01*
X236575Y513442D01*
X236408Y513650D01*
X236075Y513733D01*
X235742Y513650D01*
X235533Y513400D01*
X235408Y513108D01*
Y512067D01*
G01Y513108D02*
X234200Y513733D01*
G01Y516000D02*
X236700D01*
X236200Y515500D01*
G01X234200D02*
Y516500D01*
G01X234575Y518183D02*
X234367Y518433D01*
X234242Y518725D01*
X234200Y519100D01*
X234283Y519475D01*
X234450Y519767D01*
X234742Y519975D01*
X235075Y520017D01*
X235408Y519933D01*
X235617Y519725D01*
X235783Y519433D01*
X235825Y519142D01*
X235783Y518850D01*
X235617Y518475D01*
X236700Y518600D01*
Y519725D01*
G01X235242Y521408D02*
X235533Y521700D01*
X235700Y521950D01*
X235783Y522283D01*
X235700Y522575D01*
X235533Y522783D01*
X235283Y522950D01*
X234992Y522992D01*
X234742Y522950D01*
X234492Y522783D01*
X234283Y522533D01*
X234200Y522242D01*
X234283Y521908D01*
X234533Y521617D01*
X234908Y521450D01*
X235325Y521408D01*
X235867Y521492D01*
X236158Y521617D01*
X236450Y521825D01*
X236658Y522117D01*
X236700Y522408D01*
X236617Y522700D01*
X236408Y522908D01*
G01X249284Y512273D02*
X251784D01*
Y513314D01*
X251659Y513648D01*
X251492Y513856D01*
X251159Y513939D01*
X250826Y513856D01*
X250617Y513606D01*
X250492Y513314D01*
Y512273D01*
G01Y513314D02*
X249284Y513939D01*
G01X251367Y515414D02*
X251617Y515664D01*
X251742Y515956D01*
X251784Y516289D01*
X251701Y516706D01*
X251492Y516998D01*
X251242Y517081D01*
X250992Y517039D01*
X250784Y516873D01*
X250367Y516039D01*
X250076Y515664D01*
X249659Y515414D01*
X249284Y515331D01*
Y517081D01*
G01X249576Y518598D02*
X249367Y518889D01*
X249284Y519223D01*
X249367Y519556D01*
X249617Y519848D01*
X249992Y520056D01*
X250367Y520139D01*
X250826D01*
X251201Y520056D01*
X251534Y519848D01*
X251701Y519598D01*
X251784Y519306D01*
X251701Y518973D01*
X251534Y518723D01*
X251284Y518556D01*
X250951Y518473D01*
X250659Y518556D01*
X250367Y518764D01*
X250201Y519014D01*
X250159Y519306D01*
X250242Y519639D01*
X250451Y519889D01*
X250826Y520139D01*
G01X249284Y522406D02*
X251784D01*
X251284Y521906D01*
G01X249284D02*
Y522906D01*
G01X237600Y512167D02*
X240100D01*
Y513208D01*
X239975Y513542D01*
X239808Y513750D01*
X239475Y513833D01*
X239142Y513750D01*
X238933Y513500D01*
X238808Y513208D01*
Y512167D01*
G01Y513208D02*
X237600Y513833D01*
G01Y516100D02*
X240100D01*
X239600Y515600D01*
G01X237600D02*
Y516600D01*
G01Y519700D02*
X240100D01*
X238308Y518158D01*
Y520242D01*
G01X240100Y522300D02*
X240017Y521967D01*
X239808Y521717D01*
X239558Y521550D01*
X239225Y521425D01*
X238850Y521383D01*
X238475Y521425D01*
X238142Y521550D01*
X237892Y521717D01*
X237683Y521967D01*
X237600Y522300D01*
X237683Y522633D01*
X237892Y522883D01*
X238142Y523050D01*
X238475Y523175D01*
X238850Y523217D01*
X239225Y523175D01*
X239558Y523050D01*
X239808Y522883D01*
X240017Y522633D01*
X240100Y522300D01*
G01X244300Y511217D02*
X246800D01*
Y512258D01*
X246675Y512592D01*
X246508Y512800D01*
X246175Y512883D01*
X245842Y512800D01*
X245633Y512550D01*
X245508Y512258D01*
Y511217D01*
G01Y512258D02*
X244300Y512883D01*
G01Y515150D02*
X246800D01*
X246300Y514650D01*
G01X244300D02*
Y515650D01*
G01Y518750D02*
X246800D01*
X245008Y517208D01*
Y519292D01*
G01X246383Y520558D02*
X246633Y520808D01*
X246758Y521100D01*
X246800Y521433D01*
X246717Y521850D01*
X246508Y522142D01*
X246258Y522225D01*
X246008Y522183D01*
X245800Y522017D01*
X245383Y521183D01*
X245092Y520808D01*
X244675Y520558D01*
X244300Y520475D01*
Y522225D01*
G01X230000Y511467D02*
X232500D01*
Y512508D01*
X232375Y512842D01*
X232208Y513050D01*
X231875Y513133D01*
X231542Y513050D01*
X231333Y512800D01*
X231208Y512508D01*
Y511467D01*
G01Y512508D02*
X230000Y513133D01*
G01Y515400D02*
X232500D01*
X232000Y514900D01*
G01X230000D02*
Y515900D01*
G01X230375Y517583D02*
X230167Y517833D01*
X230042Y518125D01*
X230000Y518500D01*
X230083Y518875D01*
X230250Y519167D01*
X230542Y519375D01*
X230875Y519417D01*
X231208Y519333D01*
X231417Y519125D01*
X231583Y518833D01*
X231625Y518542D01*
X231583Y518250D01*
X231417Y517875D01*
X232500Y518000D01*
Y519125D01*
G01X230000Y522100D02*
X232500D01*
X230708Y520558D01*
Y522642D01*
G01X253484Y511773D02*
X255984D01*
Y512814D01*
X255859Y513148D01*
X255692Y513356D01*
X255359Y513439D01*
X255026Y513356D01*
X254817Y513106D01*
X254692Y512814D01*
Y511773D01*
G01Y512814D02*
X253484Y513439D01*
G01Y515706D02*
X255984D01*
X255484Y515206D01*
G01X253484D02*
Y516206D01*
G01X254526Y518014D02*
X254817Y518306D01*
X254984Y518556D01*
X255067Y518889D01*
X254984Y519181D01*
X254817Y519389D01*
X254567Y519556D01*
X254276Y519598D01*
X254026Y519556D01*
X253776Y519389D01*
X253567Y519139D01*
X253484Y518848D01*
X253567Y518514D01*
X253817Y518223D01*
X254192Y518056D01*
X254609Y518014D01*
X255151Y518098D01*
X255442Y518223D01*
X255734Y518431D01*
X255942Y518723D01*
X255984Y519014D01*
X255901Y519306D01*
X255692Y519514D01*
G01X253484Y521823D02*
X254026Y521906D01*
X254484Y522031D01*
X254901Y522198D01*
X255359Y522406D01*
X255984Y522739D01*
Y521073D01*
G01X270437Y512317D02*
X272937D01*
Y513358D01*
X272812Y513692D01*
X272645Y513900D01*
X272312Y513983D01*
X271979Y513900D01*
X271770Y513650D01*
X271645Y513358D01*
Y512317D01*
G01Y513358D02*
X270437Y513983D01*
G01X270937Y515333D02*
X270645Y515583D01*
X270479Y515917D01*
X270437Y516292D01*
X270479Y516625D01*
X270687Y516958D01*
X270937Y517167D01*
X271187Y517208D01*
X271479Y517125D01*
X271687Y516833D01*
X271770Y516542D01*
Y516167D01*
G01Y516542D02*
X271895Y516792D01*
X272104Y517000D01*
X272354Y517083D01*
X272604Y517000D01*
X272812Y516792D01*
X272937Y516417D01*
X272895Y516042D01*
X272729Y515667D01*
G01X270812Y518433D02*
X270604Y518683D01*
X270479Y518975D01*
X270437Y519350D01*
X270520Y519725D01*
X270687Y520017D01*
X270979Y520225D01*
X271312Y520267D01*
X271645Y520183D01*
X271854Y519975D01*
X272020Y519683D01*
X272062Y519392D01*
X272020Y519100D01*
X271854Y518725D01*
X272937Y518850D01*
Y519975D01*
G01X270937Y521533D02*
X270645Y521783D01*
X270479Y522117D01*
X270437Y522492D01*
X270479Y522825D01*
X270687Y523158D01*
X270937Y523367D01*
X271187Y523408D01*
X271479Y523325D01*
X271687Y523033D01*
X271770Y522742D01*
Y522367D01*
G01Y522742D02*
X271895Y522992D01*
X272104Y523200D01*
X272354Y523283D01*
X272604Y523200D01*
X272812Y522992D01*
X272937Y522617D01*
X272895Y522242D01*
X272729Y521867D01*
G01X261184Y511673D02*
X263684D01*
Y512714D01*
X263559Y513048D01*
X263392Y513256D01*
X263059Y513339D01*
X262726Y513256D01*
X262517Y513006D01*
X262392Y512714D01*
Y511673D01*
G01Y512714D02*
X261184Y513339D01*
G01X261684Y514689D02*
X261392Y514939D01*
X261226Y515273D01*
X261184Y515648D01*
X261226Y515981D01*
X261434Y516314D01*
X261684Y516523D01*
X261934Y516564D01*
X262226Y516481D01*
X262434Y516189D01*
X262517Y515898D01*
Y515523D01*
G01Y515898D02*
X262642Y516148D01*
X262851Y516356D01*
X263101Y516439D01*
X263351Y516356D01*
X263559Y516148D01*
X263684Y515773D01*
X263642Y515398D01*
X263476Y515023D01*
G01X261559Y517789D02*
X261351Y518039D01*
X261226Y518331D01*
X261184Y518706D01*
X261267Y519081D01*
X261434Y519373D01*
X261726Y519581D01*
X262059Y519623D01*
X262392Y519539D01*
X262601Y519331D01*
X262767Y519039D01*
X262809Y518748D01*
X262767Y518456D01*
X262601Y518081D01*
X263684Y518206D01*
Y519331D01*
G01X261559Y520889D02*
X261351Y521139D01*
X261226Y521431D01*
X261184Y521806D01*
X261267Y522181D01*
X261434Y522473D01*
X261726Y522681D01*
X262059Y522723D01*
X262392Y522639D01*
X262601Y522431D01*
X262767Y522139D01*
X262809Y521848D01*
X262767Y521556D01*
X262601Y521181D01*
X263684Y521306D01*
Y522431D01*
G01X226000Y511267D02*
X228500D01*
Y512308D01*
X228375Y512642D01*
X228208Y512850D01*
X227875Y512933D01*
X227542Y512850D01*
X227333Y512600D01*
X227208Y512308D01*
Y511267D01*
G01Y512308D02*
X226000Y512933D01*
G01X226500Y514283D02*
X226208Y514533D01*
X226042Y514867D01*
X226000Y515242D01*
X226042Y515575D01*
X226250Y515908D01*
X226500Y516117D01*
X226750Y516158D01*
X227042Y516075D01*
X227250Y515783D01*
X227333Y515492D01*
Y515117D01*
G01Y515492D02*
X227458Y515742D01*
X227667Y515950D01*
X227917Y516033D01*
X228167Y515950D01*
X228375Y515742D01*
X228500Y515367D01*
X228458Y514992D01*
X228292Y514617D01*
G01X226000Y518217D02*
X226542Y518300D01*
X227000Y518425D01*
X227417Y518592D01*
X227875Y518800D01*
X228500Y519133D01*
Y517467D01*
G01X228083Y520608D02*
X228333Y520858D01*
X228458Y521150D01*
X228500Y521483D01*
X228417Y521900D01*
X228208Y522192D01*
X227958Y522275D01*
X227708Y522233D01*
X227500Y522067D01*
X227083Y521233D01*
X226792Y520858D01*
X226375Y520608D01*
X226000Y520525D01*
Y522275D01*
G01X274437Y512017D02*
X276937D01*
Y513058D01*
X276812Y513392D01*
X276645Y513600D01*
X276312Y513683D01*
X275979Y513600D01*
X275770Y513350D01*
X275645Y513058D01*
Y512017D01*
G01Y513058D02*
X274437Y513683D01*
G01X276520Y515158D02*
X276770Y515408D01*
X276895Y515700D01*
X276937Y516033D01*
X276854Y516450D01*
X276645Y516742D01*
X276395Y516825D01*
X276145Y516783D01*
X275937Y516617D01*
X275520Y515783D01*
X275229Y515408D01*
X274812Y515158D01*
X274437Y515075D01*
Y516825D01*
G01X274729Y518342D02*
X274520Y518633D01*
X274437Y518967D01*
X274520Y519300D01*
X274770Y519592D01*
X275145Y519800D01*
X275520Y519883D01*
X275979D01*
X276354Y519800D01*
X276687Y519592D01*
X276854Y519342D01*
X276937Y519050D01*
X276854Y518717D01*
X276687Y518467D01*
X276437Y518300D01*
X276104Y518217D01*
X275812Y518300D01*
X275520Y518508D01*
X275354Y518758D01*
X275312Y519050D01*
X275395Y519383D01*
X275604Y519633D01*
X275979Y519883D01*
G01X274812Y521233D02*
X274604Y521483D01*
X274479Y521775D01*
X274437Y522150D01*
X274520Y522525D01*
X274687Y522817D01*
X274979Y523025D01*
X275312Y523067D01*
X275645Y522983D01*
X275854Y522775D01*
X276020Y522483D01*
X276062Y522192D01*
X276020Y521900D01*
X275854Y521525D01*
X276937Y521650D01*
Y522775D01*
G01X257384Y511973D02*
X259884D01*
Y513014D01*
X259759Y513348D01*
X259592Y513556D01*
X259259Y513639D01*
X258926Y513556D01*
X258717Y513306D01*
X258592Y513014D01*
Y511973D01*
G01Y513014D02*
X257384Y513639D01*
G01X258426Y515114D02*
X258717Y515406D01*
X258884Y515656D01*
X258967Y515989D01*
X258884Y516281D01*
X258717Y516489D01*
X258467Y516656D01*
X258176Y516698D01*
X257926Y516656D01*
X257676Y516489D01*
X257467Y516239D01*
X257384Y515948D01*
X257467Y515614D01*
X257717Y515323D01*
X258092Y515156D01*
X258509Y515114D01*
X259051Y515198D01*
X259342Y515323D01*
X259634Y515531D01*
X259842Y515823D01*
X259884Y516114D01*
X259801Y516406D01*
X259592Y516614D01*
G01X259884Y519006D02*
X259801Y518673D01*
X259592Y518423D01*
X259342Y518256D01*
X259009Y518131D01*
X258634Y518089D01*
X258259Y518131D01*
X257926Y518256D01*
X257676Y518423D01*
X257467Y518673D01*
X257384Y519006D01*
X257467Y519339D01*
X257676Y519589D01*
X257926Y519756D01*
X258259Y519881D01*
X258634Y519923D01*
X259009Y519881D01*
X259342Y519756D01*
X259592Y519589D01*
X259801Y519339D01*
X259884Y519006D01*
G01X257384Y522023D02*
X257926Y522106D01*
X258384Y522231D01*
X258801Y522398D01*
X259259Y522606D01*
X259884Y522939D01*
Y521273D01*
G01X234500Y523800D02*
X230500D01*
Y531200D01*
G01X234183Y493000D02*
Y495500D01*
X233142D01*
X232808Y495375D01*
X232600Y495208D01*
X232517Y494875D01*
X232600Y494542D01*
X232850Y494333D01*
X233142Y494208D01*
X234183D01*
G01X233142D02*
X232517Y493000D01*
G01X230333D02*
X230250Y493542D01*
X230125Y494000D01*
X229958Y494417D01*
X229750Y494875D01*
X229417Y495500D01*
X231083D01*
G01X227150D02*
X227483Y495417D01*
X227733Y495208D01*
X227900Y494958D01*
X228025Y494625D01*
X228067Y494250D01*
X228025Y493875D01*
X227900Y493542D01*
X227733Y493292D01*
X227483Y493083D01*
X227150Y493000D01*
X226817Y493083D01*
X226567Y493292D01*
X226400Y493542D01*
X226275Y493875D01*
X226233Y494250D01*
X226275Y494625D01*
X226400Y494958D01*
X226567Y495208D01*
X226817Y495417D01*
X227150Y495500D01*
G01X224842Y495083D02*
X224592Y495333D01*
X224300Y495458D01*
X223967Y495500D01*
X223550Y495417D01*
X223258Y495208D01*
X223175Y494958D01*
X223217Y494708D01*
X223383Y494500D01*
X224217Y494083D01*
X224592Y493792D01*
X224842Y493375D01*
X224925Y493000D01*
X223175D01*
G01X209820Y489100D02*
Y493100D01*
X217220D01*
G01X216303Y469411D02*
X218803D01*
Y470452D01*
X218678Y470786D01*
X218511Y470994D01*
X218178Y471077D01*
X217845Y470994D01*
X217636Y470744D01*
X217511Y470452D01*
Y469411D01*
G01Y470452D02*
X216303Y471077D01*
G01X216803Y472427D02*
X216511Y472677D01*
X216345Y473011D01*
X216303Y473386D01*
X216345Y473719D01*
X216553Y474052D01*
X216803Y474261D01*
X217053Y474302D01*
X217345Y474219D01*
X217553Y473927D01*
X217636Y473636D01*
Y473261D01*
G01Y473636D02*
X217761Y473886D01*
X217970Y474094D01*
X218220Y474177D01*
X218470Y474094D01*
X218678Y473886D01*
X218803Y473511D01*
X218761Y473136D01*
X218595Y472761D01*
G01X216303Y476944D02*
X218803D01*
X217011Y475402D01*
Y477486D01*
G01X216678Y478627D02*
X216470Y478877D01*
X216345Y479169D01*
X216303Y479544D01*
X216386Y479919D01*
X216553Y480211D01*
X216845Y480419D01*
X217178Y480461D01*
X217511Y480377D01*
X217720Y480169D01*
X217886Y479877D01*
X217928Y479586D01*
X217886Y479294D01*
X217720Y478919D01*
X218803Y479044D01*
Y480169D01*
G01X213658Y488933D02*
X217658D01*
Y481533D01*
G01X260200Y528300D02*
Y525800D01*
G01X261158Y528300D02*
X259242D01*
G01X257933Y525800D02*
Y528300D01*
X256933D01*
X256600Y528175D01*
X256350Y527883D01*
X256267Y527550D01*
X256350Y527217D01*
X256558Y526967D01*
X256933Y526842D01*
X257933D01*
G01X254000Y525800D02*
Y528300D01*
X254500Y527800D01*
G01Y525800D02*
X253500D01*
G01X251608Y526092D02*
X251317Y525883D01*
X250983Y525800D01*
X250650Y525883D01*
X250358Y526133D01*
X250150Y526508D01*
X250067Y526883D01*
Y527342D01*
X250150Y527717D01*
X250358Y528050D01*
X250608Y528217D01*
X250900Y528300D01*
X251233Y528217D01*
X251483Y528050D01*
X251650Y527800D01*
X251733Y527467D01*
X251650Y527175D01*
X251442Y526883D01*
X251192Y526717D01*
X250900Y526675D01*
X250567Y526758D01*
X250317Y526967D01*
X250067Y527342D01*
G01X248592Y527883D02*
X248342Y528133D01*
X248050Y528258D01*
X247717Y528300D01*
X247300Y528217D01*
X247008Y528008D01*
X246925Y527758D01*
X246967Y527508D01*
X247133Y527300D01*
X247967Y526883D01*
X248342Y526592D01*
X248592Y526175D01*
X248675Y525800D01*
X246925D01*
G01X220477Y512104D02*
Y510312D01*
X220310Y509937D01*
X219977Y509687D01*
X219560Y509604D01*
X219143Y509687D01*
X218810Y509937D01*
X218643Y510312D01*
Y512104D01*
G01X217377Y510104D02*
X217127Y509812D01*
X216793Y509646D01*
X216418Y509604D01*
X216085Y509646D01*
X215752Y509854D01*
X215543Y510104D01*
X215502Y510354D01*
X215585Y510646D01*
X215877Y510854D01*
X216168Y510937D01*
X216543D01*
G01X216168D02*
X215918Y511062D01*
X215710Y511271D01*
X215627Y511521D01*
X215710Y511771D01*
X215918Y511979D01*
X216293Y512104D01*
X216668Y512062D01*
X217043Y511896D01*
G01X213443Y509604D02*
X213360Y510146D01*
X213235Y510604D01*
X213068Y511021D01*
X212860Y511479D01*
X212527Y512104D01*
X214193D01*
G01X221600Y494280D02*
Y507680D01*
G01X211600Y494280D02*
X221600D01*
G01X211600Y507680D02*
Y494280D01*
G01X221600Y507680D02*
X211600D01*
G01X233959Y500067D02*
X234084Y499817D01*
X234167Y499525D01*
Y499192D01*
X234042Y498817D01*
X233834Y498525D01*
X233584Y498317D01*
X233167Y498150D01*
X232792Y498108D01*
X232417Y498192D01*
X232167Y498317D01*
X231917Y498567D01*
X231750Y498858D01*
X231667Y499150D01*
Y499442D01*
X231750Y499733D01*
X231875Y499983D01*
X232042Y500192D01*
G01X231667Y502250D02*
X234167D01*
X233667Y501750D01*
G01X231667D02*
Y502750D01*
G01X234167Y505350D02*
X234084Y505017D01*
X233875Y504767D01*
X233625Y504600D01*
X233292Y504475D01*
X232917Y504433D01*
X232542Y504475D01*
X232209Y504600D01*
X231959Y504767D01*
X231750Y505017D01*
X231667Y505350D01*
X231750Y505683D01*
X231959Y505933D01*
X232209Y506100D01*
X232542Y506225D01*
X232917Y506267D01*
X233292Y506225D01*
X233625Y506100D01*
X233875Y505933D01*
X234084Y505683D01*
X234167Y505350D01*
G01X231959Y507742D02*
X231750Y508033D01*
X231667Y508367D01*
X231750Y508700D01*
X232000Y508992D01*
X232375Y509200D01*
X232750Y509283D01*
X233209D01*
X233584Y509200D01*
X233917Y508992D01*
X234084Y508742D01*
X234167Y508450D01*
X234084Y508117D01*
X233917Y507867D01*
X233667Y507700D01*
X233334Y507617D01*
X233042Y507700D01*
X232750Y507908D01*
X232584Y508158D01*
X232542Y508450D01*
X232625Y508783D01*
X232834Y509033D01*
X233209Y509283D01*
G01X225659Y499967D02*
X225784Y499717D01*
X225867Y499425D01*
Y499092D01*
X225742Y498717D01*
X225534Y498425D01*
X225284Y498217D01*
X224867Y498050D01*
X224492Y498008D01*
X224117Y498092D01*
X223867Y498217D01*
X223617Y498467D01*
X223450Y498758D01*
X223367Y499050D01*
Y499342D01*
X223450Y499633D01*
X223575Y499883D01*
X223742Y500092D01*
G01X223367Y502150D02*
X225867D01*
X225367Y501650D01*
G01X223367D02*
Y502650D01*
G01Y505250D02*
X225867D01*
X225367Y504750D01*
G01X223367D02*
Y505750D01*
G01X225867Y508350D02*
X225784Y508017D01*
X225575Y507767D01*
X225325Y507600D01*
X224992Y507475D01*
X224617Y507433D01*
X224242Y507475D01*
X223909Y507600D01*
X223659Y507767D01*
X223450Y508017D01*
X223367Y508350D01*
X223450Y508683D01*
X223659Y508933D01*
X223909Y509100D01*
X224242Y509225D01*
X224617Y509267D01*
X224992Y509225D01*
X225325Y509100D01*
X225575Y508933D01*
X225784Y508683D01*
X225867Y508350D01*
G01X229959Y499667D02*
X230084Y499417D01*
X230167Y499125D01*
Y498792D01*
X230042Y498417D01*
X229834Y498125D01*
X229584Y497917D01*
X229167Y497750D01*
X228792Y497708D01*
X228417Y497792D01*
X228167Y497917D01*
X227917Y498167D01*
X227750Y498458D01*
X227667Y498750D01*
Y499042D01*
X227750Y499333D01*
X227875Y499583D01*
X228042Y499792D01*
G01X227667Y501850D02*
X230167D01*
X229667Y501350D01*
G01X227667D02*
Y502350D01*
G01Y504950D02*
X230167D01*
X229667Y504450D01*
G01X227667D02*
Y505450D01*
G01X228167Y507133D02*
X227875Y507383D01*
X227709Y507717D01*
X227667Y508092D01*
X227709Y508425D01*
X227917Y508758D01*
X228167Y508967D01*
X228417Y509008D01*
X228709Y508925D01*
X228917Y508633D01*
X229000Y508342D01*
Y507967D01*
G01Y508342D02*
X229125Y508592D01*
X229334Y508800D01*
X229584Y508883D01*
X229834Y508800D01*
X230042Y508592D01*
X230167Y508217D01*
X230125Y507842D01*
X229959Y507467D01*
G01X241892Y499867D02*
X242017Y499617D01*
X242100Y499325D01*
Y498992D01*
X241975Y498617D01*
X241767Y498325D01*
X241517Y498117D01*
X241100Y497950D01*
X240725Y497908D01*
X240350Y497992D01*
X240100Y498117D01*
X239850Y498367D01*
X239683Y498658D01*
X239600Y498950D01*
Y499242D01*
X239683Y499533D01*
X239808Y499783D01*
X239975Y499992D01*
G01X239600Y502050D02*
X242100D01*
X241600Y501550D01*
G01X239600D02*
Y502550D01*
G01Y505150D02*
X242100D01*
X241600Y504650D01*
G01X239600D02*
Y505650D01*
G01Y508750D02*
X242100D01*
X240308Y507208D01*
Y509292D01*
G01X238059Y499867D02*
X238184Y499617D01*
X238267Y499325D01*
Y498992D01*
X238142Y498617D01*
X237934Y498325D01*
X237684Y498117D01*
X237267Y497950D01*
X236892Y497908D01*
X236517Y497992D01*
X236267Y498117D01*
X236017Y498367D01*
X235850Y498658D01*
X235767Y498950D01*
Y499242D01*
X235850Y499533D01*
X235975Y499783D01*
X236142Y499992D01*
G01X235767Y502050D02*
X238267D01*
X237767Y501550D01*
G01X235767D02*
Y502550D01*
G01Y505150D02*
X238267D01*
X237767Y504650D01*
G01X235767D02*
Y505650D01*
G01X236142Y507333D02*
X235934Y507583D01*
X235809Y507875D01*
X235767Y508250D01*
X235850Y508625D01*
X236017Y508917D01*
X236309Y509125D01*
X236642Y509167D01*
X236975Y509083D01*
X237184Y508875D01*
X237350Y508583D01*
X237392Y508292D01*
X237350Y508000D01*
X237184Y507625D01*
X238267Y507750D01*
Y508875D01*
G01X234900Y549500D02*
Y558000D01*
G01X235000Y563000D02*
Y565000D01*
X231000D01*
Y568000D01*
G01X223000Y569000D02*
X217200D01*
Y540300D01*
X235900D01*
Y535300D01*
X278100D01*
Y528100D01*
X302100D01*
Y567900D01*
X285700D01*
Y558100D01*
X272000D01*
Y547000D01*
X242500D01*
G01X267383Y555092D02*
X267633Y555217D01*
X267925Y555300D01*
X268258D01*
X268633Y555175D01*
X268925Y554967D01*
X269133Y554717D01*
X269300Y554300D01*
X269342Y553925D01*
X269258Y553550D01*
X269133Y553300D01*
X268883Y553050D01*
X268592Y552883D01*
X268300Y552800D01*
X268008D01*
X267717Y552883D01*
X267467Y553008D01*
X267258Y553175D01*
G01X265992Y554883D02*
X265742Y555133D01*
X265450Y555258D01*
X265117Y555300D01*
X264700Y555217D01*
X264408Y555008D01*
X264325Y554758D01*
X264367Y554508D01*
X264533Y554300D01*
X265367Y553883D01*
X265742Y553592D01*
X265992Y553175D01*
X266075Y552800D01*
X264325D01*
G01X262183D02*
X262100Y553342D01*
X261975Y553800D01*
X261808Y554217D01*
X261600Y554675D01*
X261267Y555300D01*
X262933D01*
G01X268800Y569700D02*
X264800D01*
Y577100D01*
G01X253600Y558417D02*
X256100D01*
Y559458D01*
X255975Y559792D01*
X255808Y560000D01*
X255475Y560083D01*
X255142Y560000D01*
X254933Y559750D01*
X254808Y559458D01*
Y558417D01*
G01Y559458D02*
X253600Y560083D01*
G01Y562350D02*
X256100D01*
X255600Y561850D01*
G01X253600D02*
Y562850D01*
G01X254642Y564658D02*
X254933Y564950D01*
X255100Y565200D01*
X255183Y565533D01*
X255100Y565825D01*
X254933Y566033D01*
X254683Y566200D01*
X254392Y566242D01*
X254142Y566200D01*
X253892Y566033D01*
X253683Y565783D01*
X253600Y565492D01*
X253683Y565158D01*
X253933Y564867D01*
X254308Y564700D01*
X254725Y564658D01*
X255267Y564742D01*
X255558Y564867D01*
X255850Y565075D01*
X256058Y565367D01*
X256100Y565658D01*
X256017Y565950D01*
X255808Y566158D01*
G01X253600Y568550D02*
X256100D01*
X255600Y568050D01*
G01X253600D02*
Y569050D01*
G01X264816Y566537D02*
X268816D01*
Y559137D01*
G01X236600Y573100D02*
Y577100D01*
X244000D01*
G01X229809Y560053D02*
Y556053D01*
X222409D01*
G01X236500Y556500D02*
Y560500D01*
X243900D01*
G01X272947Y571004D02*
X268947D01*
Y578404D01*
G01X257300Y558417D02*
X259800D01*
Y559458D01*
X259675Y559792D01*
X259508Y560000D01*
X259175Y560083D01*
X258842Y560000D01*
X258633Y559750D01*
X258508Y559458D01*
Y558417D01*
G01Y559458D02*
X257300Y560083D01*
G01Y562350D02*
X259800D01*
X259300Y561850D01*
G01X257300D02*
Y562850D01*
G01X257592Y564742D02*
X257383Y565033D01*
X257300Y565367D01*
X257383Y565700D01*
X257633Y565992D01*
X258008Y566200D01*
X258383Y566283D01*
X258842D01*
X259217Y566200D01*
X259550Y565992D01*
X259717Y565742D01*
X259800Y565450D01*
X259717Y565117D01*
X259550Y564867D01*
X259300Y564700D01*
X258967Y564617D01*
X258675Y564700D01*
X258383Y564908D01*
X258217Y565158D01*
X258175Y565450D01*
X258258Y565783D01*
X258467Y566033D01*
X258842Y566283D01*
G01X257300Y569050D02*
X259800D01*
X258008Y567508D01*
Y569592D01*
G01X268836Y566519D02*
X272836D01*
Y559119D01*
G01X244145Y563318D02*
X248145D01*
Y555918D01*
G01X244300Y563900D02*
Y567900D01*
X251700D01*
G01X236500Y548400D02*
Y552400D01*
X243900D01*
G01X244317Y567957D02*
Y571957D01*
X251717D01*
G01X263909Y585813D02*
Y589813D01*
X271309D01*
G01X269183Y592600D02*
Y595100D01*
X268142D01*
X267808Y594975D01*
X267600Y594808D01*
X267517Y594475D01*
X267600Y594142D01*
X267850Y593933D01*
X268142Y593808D01*
X269183D01*
G01X268142D02*
X267517Y592600D01*
G01X266167Y593100D02*
X265917Y592808D01*
X265583Y592642D01*
X265208Y592600D01*
X264875Y592642D01*
X264542Y592850D01*
X264333Y593100D01*
X264292Y593350D01*
X264375Y593642D01*
X264667Y593850D01*
X264958Y593933D01*
X265333D01*
G01X264958D02*
X264708Y594058D01*
X264500Y594267D01*
X264417Y594517D01*
X264500Y594767D01*
X264708Y594975D01*
X265083Y595100D01*
X265458Y595058D01*
X265833Y594892D01*
G01X262858Y592892D02*
X262567Y592683D01*
X262233Y592600D01*
X261900Y592683D01*
X261608Y592933D01*
X261400Y593308D01*
X261317Y593683D01*
Y594142D01*
X261400Y594517D01*
X261608Y594850D01*
X261858Y595017D01*
X262150Y595100D01*
X262483Y595017D01*
X262733Y594850D01*
X262900Y594600D01*
X262983Y594267D01*
X262900Y593975D01*
X262692Y593683D01*
X262442Y593517D01*
X262150Y593475D01*
X261817Y593558D01*
X261567Y593767D01*
X261317Y594142D01*
G01X259967Y593100D02*
X259717Y592808D01*
X259383Y592642D01*
X259008Y592600D01*
X258675Y592642D01*
X258342Y592850D01*
X258133Y593100D01*
X258092Y593350D01*
X258175Y593642D01*
X258467Y593850D01*
X258758Y593933D01*
X259133D01*
G01X258758D02*
X258508Y594058D01*
X258300Y594267D01*
X258217Y594517D01*
X258300Y594767D01*
X258508Y594975D01*
X258883Y595100D01*
X259258Y595058D01*
X259633Y594892D01*
G01X251765Y596250D02*
Y592250D01*
X244365D01*
G01X230400Y562350D02*
X226400D01*
Y569750D01*
G01X271490Y589802D02*
X275490D01*
Y582402D01*
G01X240100Y581000D02*
X236100D01*
Y588400D01*
G01X253900Y588917D02*
X256400D01*
Y589958D01*
X256275Y590292D01*
X256108Y590500D01*
X255775Y590583D01*
X255442Y590500D01*
X255233Y590250D01*
X255108Y589958D01*
Y588917D01*
G01Y589958D02*
X253900Y590583D01*
G01X254400Y591933D02*
X254108Y592183D01*
X253942Y592517D01*
X253900Y592892D01*
X253942Y593225D01*
X254150Y593558D01*
X254400Y593767D01*
X254650Y593808D01*
X254942Y593725D01*
X255150Y593433D01*
X255233Y593142D01*
Y592767D01*
G01Y593142D02*
X255358Y593392D01*
X255567Y593600D01*
X255817Y593683D01*
X256067Y593600D01*
X256275Y593392D01*
X256400Y593017D01*
X256358Y592642D01*
X256192Y592267D01*
G01X254192Y595242D02*
X253983Y595533D01*
X253900Y595867D01*
X253983Y596200D01*
X254233Y596492D01*
X254608Y596700D01*
X254983Y596783D01*
X255442D01*
X255817Y596700D01*
X256150Y596492D01*
X256317Y596242D01*
X256400Y595950D01*
X256317Y595617D01*
X256150Y595367D01*
X255900Y595200D01*
X255567Y595117D01*
X255275Y595200D01*
X254983Y595408D01*
X254817Y595658D01*
X254775Y595950D01*
X254858Y596283D01*
X255067Y596533D01*
X255442Y596783D01*
G01X253900Y599050D02*
X253942Y599342D01*
X254067Y599675D01*
X254275Y599883D01*
X254567Y599967D01*
X254858Y599883D01*
X255108Y599633D01*
X255233Y599258D01*
Y598842D01*
X255317Y598592D01*
X255525Y598383D01*
X255817Y598300D01*
X256108Y598425D01*
X256317Y598717D01*
X256400Y599050D01*
X256317Y599383D01*
X256108Y599675D01*
X255817Y599800D01*
X255525Y599717D01*
X255317Y599508D01*
X255233Y599258D01*
Y598842D01*
X255108Y598467D01*
X254858Y598217D01*
X254567Y598133D01*
X254275Y598217D01*
X254067Y598425D01*
X253942Y598758D01*
X253900Y599050D01*
G01X244000Y588800D02*
X240000D01*
Y596200D01*
G01X236500Y552400D02*
Y556400D01*
X243900D01*
G01X236300Y560600D02*
Y564600D01*
X243700D01*
G01X236300Y564700D02*
Y568700D01*
X243700D01*
G01X236600Y569000D02*
Y573000D01*
X244000D01*
G01X226102Y534842D02*
X230102D01*
Y527442D01*
G01X244332Y577067D02*
Y581067D01*
X251732D01*
G01X271312Y585809D02*
Y581809D01*
X263912D01*
G01X217100Y530600D02*
X213100D01*
Y538000D01*
G01X229700Y587900D02*
Y583900D01*
X222300D01*
G01X229775Y578816D02*
Y574816D01*
X222375D01*
G01X229400Y573900D02*
Y569900D01*
X222000D01*
G01X222148Y579666D02*
Y583666D01*
X229548D01*
G01X228600Y595200D02*
Y591200D01*
X221200D01*
G01X244100Y581000D02*
X240100D01*
Y588400D01*
G01X221200Y531100D02*
X217200D01*
Y538500D01*
G01X269083Y530300D02*
Y532800D01*
X268042D01*
X267708Y532675D01*
X267500Y532508D01*
X267417Y532175D01*
X267500Y531842D01*
X267750Y531633D01*
X268042Y531508D01*
X269083D01*
G01X268042D02*
X267417Y530300D01*
G01X266067Y530800D02*
X265817Y530508D01*
X265483Y530342D01*
X265108Y530300D01*
X264775Y530342D01*
X264442Y530550D01*
X264233Y530800D01*
X264192Y531050D01*
X264275Y531342D01*
X264567Y531550D01*
X264858Y531633D01*
X265233D01*
G01X264858D02*
X264608Y531758D01*
X264400Y531967D01*
X264317Y532217D01*
X264400Y532467D01*
X264608Y532675D01*
X264983Y532800D01*
X265358Y532758D01*
X265733Y532592D01*
G01X261550Y530300D02*
Y532800D01*
X263092Y531008D01*
X261008D01*
G01X259867Y530800D02*
X259617Y530508D01*
X259283Y530342D01*
X258908Y530300D01*
X258575Y530342D01*
X258242Y530550D01*
X258033Y530800D01*
X257992Y531050D01*
X258075Y531342D01*
X258367Y531550D01*
X258658Y531633D01*
X259033D01*
G01X258658D02*
X258408Y531758D01*
X258200Y531967D01*
X258117Y532217D01*
X258200Y532467D01*
X258408Y532675D01*
X258783Y532800D01*
X259158Y532758D01*
X259533Y532592D01*
G01X248800Y533240D02*
Y529240D01*
X241400D01*
G01X212800Y548617D02*
X215300D01*
Y549658D01*
X215175Y549992D01*
X215008Y550200D01*
X214675Y550283D01*
X214342Y550200D01*
X214133Y549950D01*
X214008Y549658D01*
Y548617D01*
G01Y549658D02*
X212800Y550283D01*
G01X213300Y551633D02*
X213008Y551883D01*
X212842Y552217D01*
X212800Y552592D01*
X212842Y552925D01*
X213050Y553258D01*
X213300Y553467D01*
X213550Y553508D01*
X213842Y553425D01*
X214050Y553133D01*
X214133Y552842D01*
Y552467D01*
G01Y552842D02*
X214258Y553092D01*
X214467Y553300D01*
X214717Y553383D01*
X214967Y553300D01*
X215175Y553092D01*
X215300Y552717D01*
X215258Y552342D01*
X215092Y551967D01*
G01X213175Y554733D02*
X212967Y554983D01*
X212842Y555275D01*
X212800Y555650D01*
X212883Y556025D01*
X213050Y556317D01*
X213342Y556525D01*
X213675Y556567D01*
X214008Y556483D01*
X214217Y556275D01*
X214383Y555983D01*
X214425Y555692D01*
X214383Y555400D01*
X214217Y555025D01*
X215300Y555150D01*
Y556275D01*
G01X212800Y558667D02*
X213342Y558750D01*
X213800Y558875D01*
X214217Y559042D01*
X214675Y559250D01*
X215300Y559583D01*
Y557917D01*
G01X247600Y545100D02*
Y541100D01*
X240200D01*
G01X238200Y537000D02*
Y541000D01*
X245600D01*
G01X283650Y545300D02*
Y542800D01*
G01X284608Y545300D02*
X282692D01*
G01X281383Y542800D02*
Y545300D01*
X280383D01*
X280050Y545175D01*
X279800Y544883D01*
X279717Y544550D01*
X279800Y544217D01*
X280008Y543967D01*
X280383Y543842D01*
X281383D01*
G01X278242D02*
X277950Y544133D01*
X277700Y544300D01*
X277367Y544383D01*
X277075Y544300D01*
X276867Y544133D01*
X276700Y543883D01*
X276658Y543592D01*
X276700Y543342D01*
X276867Y543092D01*
X277117Y542883D01*
X277408Y542800D01*
X277742Y542883D01*
X278033Y543133D01*
X278200Y543508D01*
X278242Y543925D01*
X278158Y544467D01*
X278033Y544758D01*
X277825Y545050D01*
X277533Y545258D01*
X277242Y545300D01*
X276950Y545217D01*
X276742Y545008D01*
G01X274350Y542800D02*
X274058Y542842D01*
X273725Y542967D01*
X273517Y543175D01*
X273433Y543467D01*
X273517Y543758D01*
X273767Y544008D01*
X274142Y544133D01*
X274558D01*
X274808Y544217D01*
X275017Y544425D01*
X275100Y544717D01*
X274975Y545008D01*
X274683Y545217D01*
X274350Y545300D01*
X274017Y545217D01*
X273725Y545008D01*
X273600Y544717D01*
X273683Y544425D01*
X273892Y544217D01*
X274142Y544133D01*
X274558D01*
X274933Y544008D01*
X275183Y543758D01*
X275267Y543467D01*
X275183Y543175D01*
X274975Y542967D01*
X274642Y542842D01*
X274350Y542800D01*
G01X283650Y541600D02*
Y539100D01*
G01X284608Y541600D02*
X282692D01*
G01X281383Y539100D02*
Y541600D01*
X280383D01*
X280050Y541475D01*
X279800Y541183D01*
X279717Y540850D01*
X279800Y540517D01*
X280008Y540267D01*
X280383Y540142D01*
X281383D01*
G01X277533Y539100D02*
X277450Y539642D01*
X277325Y540100D01*
X277158Y540517D01*
X276950Y540975D01*
X276617Y541600D01*
X278283D01*
G01X274350D02*
X274683Y541517D01*
X274933Y541308D01*
X275100Y541058D01*
X275225Y540725D01*
X275267Y540350D01*
X275225Y539975D01*
X275100Y539642D01*
X274933Y539392D01*
X274683Y539183D01*
X274350Y539100D01*
X274017Y539183D01*
X273767Y539392D01*
X273600Y539642D01*
X273475Y539975D01*
X273433Y540350D01*
X273475Y540725D01*
X273600Y541058D01*
X273767Y541308D01*
X274017Y541517D01*
X274350Y541600D01*
G01X283650Y552700D02*
Y550200D01*
G01X284608Y552700D02*
X282692D01*
G01X281383Y550200D02*
Y552700D01*
X280383D01*
X280050Y552575D01*
X279800Y552283D01*
X279717Y551950D01*
X279800Y551617D01*
X280008Y551367D01*
X280383Y551242D01*
X281383D01*
G01X278367Y550575D02*
X278117Y550367D01*
X277825Y550242D01*
X277450Y550200D01*
X277075Y550283D01*
X276783Y550450D01*
X276575Y550742D01*
X276533Y551075D01*
X276617Y551408D01*
X276825Y551617D01*
X277117Y551783D01*
X277408Y551825D01*
X277700Y551783D01*
X278075Y551617D01*
X277950Y552700D01*
X276825D01*
G01X273850Y550200D02*
Y552700D01*
X275392Y550908D01*
X273308D01*
G01X283650Y549000D02*
Y546500D01*
G01X284608Y549000D02*
X282692D01*
G01X281383Y546500D02*
Y549000D01*
X280383D01*
X280050Y548875D01*
X279800Y548583D01*
X279717Y548250D01*
X279800Y547917D01*
X280008Y547667D01*
X280383Y547542D01*
X281383D01*
G01X277533Y546500D02*
X277450Y547042D01*
X277325Y547500D01*
X277158Y547917D01*
X276950Y548375D01*
X276617Y549000D01*
X278283D01*
G01X275267Y547000D02*
X275017Y546708D01*
X274683Y546542D01*
X274308Y546500D01*
X273975Y546542D01*
X273642Y546750D01*
X273433Y547000D01*
X273392Y547250D01*
X273475Y547542D01*
X273767Y547750D01*
X274058Y547833D01*
X274433D01*
G01X274058D02*
X273808Y547958D01*
X273600Y548167D01*
X273517Y548417D01*
X273600Y548667D01*
X273808Y548875D01*
X274183Y549000D01*
X274558Y548958D01*
X274933Y548792D01*
G01X255792Y645317D02*
X255917Y645067D01*
X256000Y644775D01*
Y644442D01*
X255875Y644067D01*
X255667Y643775D01*
X255417Y643567D01*
X255000Y643400D01*
X254625Y643358D01*
X254250Y643442D01*
X254000Y643567D01*
X253750Y643817D01*
X253583Y644108D01*
X253500Y644400D01*
Y644692D01*
X253583Y644983D01*
X253708Y645233D01*
X253875Y645442D01*
G01X253500Y647500D02*
X253542Y647792D01*
X253667Y648125D01*
X253875Y648333D01*
X254167Y648417D01*
X254458Y648333D01*
X254708Y648083D01*
X254833Y647708D01*
Y647292D01*
X254917Y647042D01*
X255125Y646833D01*
X255417Y646750D01*
X255708Y646875D01*
X255917Y647167D01*
X256000Y647500D01*
X255917Y647833D01*
X255708Y648125D01*
X255417Y648250D01*
X255125Y648167D01*
X254917Y647958D01*
X254833Y647708D01*
Y647292D01*
X254708Y646917D01*
X254458Y646667D01*
X254167Y646583D01*
X253875Y646667D01*
X253667Y646875D01*
X253542Y647208D01*
X253500Y647500D01*
G01X256000Y650600D02*
X255917Y650267D01*
X255708Y650017D01*
X255458Y649850D01*
X255125Y649725D01*
X254750Y649683D01*
X254375Y649725D01*
X254042Y649850D01*
X253792Y650017D01*
X253583Y650267D01*
X253500Y650600D01*
X253583Y650933D01*
X253792Y651183D01*
X254042Y651350D01*
X254375Y651475D01*
X254750Y651517D01*
X255125Y651475D01*
X255458Y651350D01*
X255708Y651183D01*
X255917Y650933D01*
X256000Y650600D01*
G01X250883Y633292D02*
X251133Y633417D01*
X251425Y633500D01*
X251758D01*
X252133Y633375D01*
X252425Y633167D01*
X252633Y632917D01*
X252800Y632500D01*
X252842Y632125D01*
X252758Y631750D01*
X252633Y631500D01*
X252383Y631250D01*
X252092Y631083D01*
X251800Y631000D01*
X251508D01*
X251217Y631083D01*
X250967Y631208D01*
X250758Y631375D01*
G01X248700Y631000D02*
X248408Y631042D01*
X248075Y631167D01*
X247867Y631375D01*
X247783Y631667D01*
X247867Y631958D01*
X248117Y632208D01*
X248492Y632333D01*
X248908D01*
X249158Y632417D01*
X249367Y632625D01*
X249450Y632917D01*
X249325Y633208D01*
X249033Y633417D01*
X248700Y633500D01*
X248367Y633417D01*
X248075Y633208D01*
X247950Y632917D01*
X248033Y632625D01*
X248242Y632417D01*
X248492Y632333D01*
X248908D01*
X249283Y632208D01*
X249533Y631958D01*
X249617Y631667D01*
X249533Y631375D01*
X249325Y631167D01*
X248992Y631042D01*
X248700Y631000D01*
G01X245600D02*
X245308Y631042D01*
X244975Y631167D01*
X244767Y631375D01*
X244683Y631667D01*
X244767Y631958D01*
X245017Y632208D01*
X245392Y632333D01*
X245808D01*
X246058Y632417D01*
X246267Y632625D01*
X246350Y632917D01*
X246225Y633208D01*
X245933Y633417D01*
X245600Y633500D01*
X245267Y633417D01*
X244975Y633208D01*
X244850Y632917D01*
X244933Y632625D01*
X245142Y632417D01*
X245392Y632333D01*
X245808D01*
X246183Y632208D01*
X246433Y631958D01*
X246517Y631667D01*
X246433Y631375D01*
X246225Y631167D01*
X245892Y631042D01*
X245600Y631000D01*
G01X237992Y648617D02*
X238117Y648367D01*
X238200Y648075D01*
Y647742D01*
X238075Y647367D01*
X237867Y647075D01*
X237617Y646867D01*
X237200Y646700D01*
X236825Y646658D01*
X236450Y646742D01*
X236200Y646867D01*
X235950Y647117D01*
X235783Y647408D01*
X235700Y647700D01*
Y647992D01*
X235783Y648283D01*
X235908Y648533D01*
X236075Y648742D01*
G01X235992Y650092D02*
X235783Y650383D01*
X235700Y650717D01*
X235783Y651050D01*
X236033Y651342D01*
X236408Y651550D01*
X236783Y651633D01*
X237242D01*
X237617Y651550D01*
X237950Y651342D01*
X238117Y651092D01*
X238200Y650800D01*
X238117Y650467D01*
X237950Y650217D01*
X237700Y650050D01*
X237367Y649967D01*
X237075Y650050D01*
X236783Y650258D01*
X236617Y650508D01*
X236575Y650800D01*
X236658Y651133D01*
X236867Y651383D01*
X237242Y651633D01*
G01X236742Y653108D02*
X237033Y653400D01*
X237200Y653650D01*
X237283Y653983D01*
X237200Y654275D01*
X237033Y654483D01*
X236783Y654650D01*
X236492Y654692D01*
X236242Y654650D01*
X235992Y654483D01*
X235783Y654233D01*
X235700Y653942D01*
X235783Y653608D01*
X236033Y653317D01*
X236408Y653150D01*
X236825Y653108D01*
X237367Y653192D01*
X237658Y653317D01*
X237950Y653525D01*
X238158Y653817D01*
X238200Y654108D01*
X238117Y654400D01*
X237908Y654608D01*
G01X251292Y645917D02*
X251417Y645667D01*
X251500Y645375D01*
Y645042D01*
X251375Y644667D01*
X251167Y644375D01*
X250917Y644167D01*
X250500Y644000D01*
X250125Y643958D01*
X249750Y644042D01*
X249500Y644167D01*
X249250Y644417D01*
X249083Y644708D01*
X249000Y645000D01*
Y645292D01*
X249083Y645583D01*
X249208Y645833D01*
X249375Y646042D01*
G01X249000Y648100D02*
X249042Y648392D01*
X249167Y648725D01*
X249375Y648933D01*
X249667Y649017D01*
X249958Y648933D01*
X250208Y648683D01*
X250333Y648308D01*
Y647892D01*
X250417Y647642D01*
X250625Y647433D01*
X250917Y647350D01*
X251208Y647475D01*
X251417Y647767D01*
X251500Y648100D01*
X251417Y648433D01*
X251208Y648725D01*
X250917Y648850D01*
X250625Y648767D01*
X250417Y648558D01*
X250333Y648308D01*
Y647892D01*
X250208Y647517D01*
X249958Y647267D01*
X249667Y647183D01*
X249375Y647267D01*
X249167Y647475D01*
X249042Y647808D01*
X249000Y648100D01*
G01Y651200D02*
X251500D01*
X251000Y650700D01*
G01X249000D02*
Y651700D01*
G01X282483Y623000D02*
Y625500D01*
X281442D01*
X281108Y625375D01*
X280900Y625208D01*
X280817Y624875D01*
X280900Y624542D01*
X281150Y624333D01*
X281442Y624208D01*
X282483D01*
G01X281442D02*
X280817Y623000D01*
G01X278550D02*
Y625500D01*
X279050Y625000D01*
G01Y623000D02*
X278050D01*
G01X276242Y624042D02*
X275950Y624333D01*
X275700Y624500D01*
X275367Y624583D01*
X275075Y624500D01*
X274867Y624333D01*
X274700Y624083D01*
X274658Y623792D01*
X274700Y623542D01*
X274867Y623292D01*
X275117Y623083D01*
X275408Y623000D01*
X275742Y623083D01*
X276033Y623333D01*
X276200Y623708D01*
X276242Y624125D01*
X276158Y624667D01*
X276033Y624958D01*
X275825Y625250D01*
X275533Y625458D01*
X275242Y625500D01*
X274950Y625417D01*
X274742Y625208D01*
G01X273267Y623500D02*
X273017Y623208D01*
X272683Y623042D01*
X272308Y623000D01*
X271975Y623042D01*
X271642Y623250D01*
X271433Y623500D01*
X271392Y623750D01*
X271475Y624042D01*
X271767Y624250D01*
X272058Y624333D01*
X272433D01*
G01X272058D02*
X271808Y624458D01*
X271600Y624667D01*
X271517Y624917D01*
X271600Y625167D01*
X271808Y625375D01*
X272183Y625500D01*
X272558Y625458D01*
X272933Y625292D01*
G01X282483Y606500D02*
Y609000D01*
X281442D01*
X281108Y608875D01*
X280900Y608708D01*
X280817Y608375D01*
X280900Y608042D01*
X281150Y607833D01*
X281442Y607708D01*
X282483D01*
G01X281442D02*
X280817Y606500D01*
G01X278550D02*
Y609000D01*
X279050Y608500D01*
G01Y606500D02*
X278050D01*
G01X275450D02*
X275158Y606542D01*
X274825Y606667D01*
X274617Y606875D01*
X274533Y607167D01*
X274617Y607458D01*
X274867Y607708D01*
X275242Y607833D01*
X275658D01*
X275908Y607917D01*
X276117Y608125D01*
X276200Y608417D01*
X276075Y608708D01*
X275783Y608917D01*
X275450Y609000D01*
X275117Y608917D01*
X274825Y608708D01*
X274700Y608417D01*
X274783Y608125D01*
X274992Y607917D01*
X275242Y607833D01*
X275658D01*
X276033Y607708D01*
X276283Y607458D01*
X276367Y607167D01*
X276283Y606875D01*
X276075Y606667D01*
X275742Y606542D01*
X275450Y606500D01*
G01X273267Y606875D02*
X273017Y606667D01*
X272725Y606542D01*
X272350Y606500D01*
X271975Y606583D01*
X271683Y606750D01*
X271475Y607042D01*
X271433Y607375D01*
X271517Y607708D01*
X271725Y607917D01*
X272017Y608083D01*
X272308Y608125D01*
X272600Y608083D01*
X272975Y607917D01*
X272850Y609000D01*
X271725D01*
G01X282483Y598500D02*
Y601000D01*
X281442D01*
X281108Y600875D01*
X280900Y600708D01*
X280817Y600375D01*
X280900Y600042D01*
X281150Y599833D01*
X281442Y599708D01*
X282483D01*
G01X281442D02*
X280817Y598500D01*
G01X279342Y600583D02*
X279092Y600833D01*
X278800Y600958D01*
X278467Y601000D01*
X278050Y600917D01*
X277758Y600708D01*
X277675Y600458D01*
X277717Y600208D01*
X277883Y600000D01*
X278717Y599583D01*
X279092Y599292D01*
X279342Y598875D01*
X279425Y598500D01*
X277675D01*
G01X275533D02*
X275450Y599042D01*
X275325Y599500D01*
X275158Y599917D01*
X274950Y600375D01*
X274617Y601000D01*
X276283D01*
G01X273267Y599000D02*
X273017Y598708D01*
X272683Y598542D01*
X272308Y598500D01*
X271975Y598542D01*
X271642Y598750D01*
X271433Y599000D01*
X271392Y599250D01*
X271475Y599542D01*
X271767Y599750D01*
X272058Y599833D01*
X272433D01*
G01X272058D02*
X271808Y599958D01*
X271600Y600167D01*
X271517Y600417D01*
X271600Y600667D01*
X271808Y600875D01*
X272183Y601000D01*
X272558Y600958D01*
X272933Y600792D01*
G01X251200Y608260D02*
Y604260D01*
X243800D01*
G01X285983Y653000D02*
Y655500D01*
X284942D01*
X284608Y655375D01*
X284400Y655208D01*
X284317Y654875D01*
X284400Y654542D01*
X284650Y654333D01*
X284942Y654208D01*
X285983D01*
G01X284942D02*
X284317Y653000D01*
G01X282967Y653500D02*
X282717Y653208D01*
X282383Y653042D01*
X282008Y653000D01*
X281675Y653042D01*
X281342Y653250D01*
X281133Y653500D01*
X281092Y653750D01*
X281175Y654042D01*
X281467Y654250D01*
X281758Y654333D01*
X282133D01*
G01X281758D02*
X281508Y654458D01*
X281300Y654667D01*
X281217Y654917D01*
X281300Y655167D01*
X281508Y655375D01*
X281883Y655500D01*
X282258Y655458D01*
X282633Y655292D01*
G01X278950Y655500D02*
X279283Y655417D01*
X279533Y655208D01*
X279700Y654958D01*
X279825Y654625D01*
X279867Y654250D01*
X279825Y653875D01*
X279700Y653542D01*
X279533Y653292D01*
X279283Y653083D01*
X278950Y653000D01*
X278617Y653083D01*
X278367Y653292D01*
X278200Y653542D01*
X278075Y653875D01*
X278033Y654250D01*
X278075Y654625D01*
X278200Y654958D01*
X278367Y655208D01*
X278617Y655417D01*
X278950Y655500D01*
G01X275350Y653000D02*
Y655500D01*
X276892Y653708D01*
X274808D01*
G01X243550Y612860D02*
Y608860D01*
X236150D01*
G01X217100Y644200D02*
Y640200D01*
X209700D01*
G01X280983Y649000D02*
Y651500D01*
X279942D01*
X279608Y651375D01*
X279400Y651208D01*
X279317Y650875D01*
X279400Y650542D01*
X279650Y650333D01*
X279942Y650208D01*
X280983D01*
G01X279942D02*
X279317Y649000D01*
G01X277967Y649500D02*
X277717Y649208D01*
X277383Y649042D01*
X277008Y649000D01*
X276675Y649042D01*
X276342Y649250D01*
X276133Y649500D01*
X276092Y649750D01*
X276175Y650042D01*
X276467Y650250D01*
X276758Y650333D01*
X277133D01*
G01X276758D02*
X276508Y650458D01*
X276300Y650667D01*
X276217Y650917D01*
X276300Y651167D01*
X276508Y651375D01*
X276883Y651500D01*
X277258Y651458D01*
X277633Y651292D01*
G01X274658Y649292D02*
X274367Y649083D01*
X274033Y649000D01*
X273700Y649083D01*
X273408Y649333D01*
X273200Y649708D01*
X273117Y650083D01*
Y650542D01*
X273200Y650917D01*
X273408Y651250D01*
X273658Y651417D01*
X273950Y651500D01*
X274283Y651417D01*
X274533Y651250D01*
X274700Y651000D01*
X274783Y650667D01*
X274700Y650375D01*
X274492Y650083D01*
X274242Y649917D01*
X273950Y649875D01*
X273617Y649958D01*
X273367Y650167D01*
X273117Y650542D01*
G01X270350Y649000D02*
Y651500D01*
X271892Y649708D01*
X269808D01*
G01X240762Y608422D02*
Y604422D01*
X233362D01*
G01X267983Y641500D02*
Y644000D01*
X266942D01*
X266608Y643875D01*
X266400Y643708D01*
X266317Y643375D01*
X266400Y643042D01*
X266650Y642833D01*
X266942Y642708D01*
X267983D01*
G01X266942D02*
X266317Y641500D01*
G01X264967Y642000D02*
X264717Y641708D01*
X264383Y641542D01*
X264008Y641500D01*
X263675Y641542D01*
X263342Y641750D01*
X263133Y642000D01*
X263092Y642250D01*
X263175Y642542D01*
X263467Y642750D01*
X263758Y642833D01*
X264133D01*
G01X263758D02*
X263508Y642958D01*
X263300Y643167D01*
X263217Y643417D01*
X263300Y643667D01*
X263508Y643875D01*
X263883Y644000D01*
X264258Y643958D01*
X264633Y643792D01*
G01X260950Y641500D02*
X260658Y641542D01*
X260325Y641667D01*
X260117Y641875D01*
X260033Y642167D01*
X260117Y642458D01*
X260367Y642708D01*
X260742Y642833D01*
X261158D01*
X261408Y642917D01*
X261617Y643125D01*
X261700Y643417D01*
X261575Y643708D01*
X261283Y643917D01*
X260950Y644000D01*
X260617Y643917D01*
X260325Y643708D01*
X260200Y643417D01*
X260283Y643125D01*
X260492Y642917D01*
X260742Y642833D01*
X261158D01*
X261533Y642708D01*
X261783Y642458D01*
X261867Y642167D01*
X261783Y641875D01*
X261575Y641667D01*
X261242Y641542D01*
X260950Y641500D01*
G01X258767Y642000D02*
X258517Y641708D01*
X258183Y641542D01*
X257808Y641500D01*
X257475Y641542D01*
X257142Y641750D01*
X256933Y642000D01*
X256892Y642250D01*
X256975Y642542D01*
X257267Y642750D01*
X257558Y642833D01*
X257933D01*
G01X257558D02*
X257308Y642958D01*
X257100Y643167D01*
X257017Y643417D01*
X257100Y643667D01*
X257308Y643875D01*
X257683Y644000D01*
X258058Y643958D01*
X258433Y643792D01*
G01X228600Y599200D02*
Y595200D01*
X221200D01*
G01X279883Y631967D02*
Y634467D01*
X278842D01*
X278508Y634342D01*
X278300Y634175D01*
X278217Y633842D01*
X278300Y633509D01*
X278550Y633300D01*
X278842Y633175D01*
X279883D01*
G01X278842D02*
X278217Y631967D01*
G01X276867Y632467D02*
X276617Y632175D01*
X276283Y632009D01*
X275908Y631967D01*
X275575Y632009D01*
X275242Y632217D01*
X275033Y632467D01*
X274992Y632717D01*
X275075Y633009D01*
X275367Y633217D01*
X275658Y633300D01*
X276033D01*
G01X275658D02*
X275408Y633425D01*
X275200Y633634D01*
X275117Y633884D01*
X275200Y634134D01*
X275408Y634342D01*
X275783Y634467D01*
X276158Y634425D01*
X276533Y634259D01*
G01X272850Y631967D02*
X272558Y632009D01*
X272225Y632134D01*
X272017Y632342D01*
X271933Y632634D01*
X272017Y632925D01*
X272267Y633175D01*
X272642Y633300D01*
X273058D01*
X273308Y633384D01*
X273517Y633592D01*
X273600Y633884D01*
X273475Y634175D01*
X273183Y634384D01*
X272850Y634467D01*
X272517Y634384D01*
X272225Y634175D01*
X272100Y633884D01*
X272183Y633592D01*
X272392Y633384D01*
X272642Y633300D01*
X273058D01*
X273433Y633175D01*
X273683Y632925D01*
X273767Y632634D01*
X273683Y632342D01*
X273475Y632134D01*
X273142Y632009D01*
X272850Y631967D01*
G01X269250D02*
Y634467D01*
X270792Y632675D01*
X268708D01*
G01X238200Y639900D02*
Y635900D01*
X230800D01*
G01X280983Y645000D02*
Y647500D01*
X279942D01*
X279608Y647375D01*
X279400Y647208D01*
X279317Y646875D01*
X279400Y646542D01*
X279650Y646333D01*
X279942Y646208D01*
X280983D01*
G01X279942D02*
X279317Y645000D01*
G01X277967Y645500D02*
X277717Y645208D01*
X277383Y645042D01*
X277008Y645000D01*
X276675Y645042D01*
X276342Y645250D01*
X276133Y645500D01*
X276092Y645750D01*
X276175Y646042D01*
X276467Y646250D01*
X276758Y646333D01*
X277133D01*
G01X276758D02*
X276508Y646458D01*
X276300Y646667D01*
X276217Y646917D01*
X276300Y647167D01*
X276508Y647375D01*
X276883Y647500D01*
X277258Y647458D01*
X277633Y647292D01*
G01X274658Y645292D02*
X274367Y645083D01*
X274033Y645000D01*
X273700Y645083D01*
X273408Y645333D01*
X273200Y645708D01*
X273117Y646083D01*
Y646542D01*
X273200Y646917D01*
X273408Y647250D01*
X273658Y647417D01*
X273950Y647500D01*
X274283Y647417D01*
X274533Y647250D01*
X274700Y647000D01*
X274783Y646667D01*
X274700Y646375D01*
X274492Y646083D01*
X274242Y645917D01*
X273950Y645875D01*
X273617Y645958D01*
X273367Y646167D01*
X273117Y646542D01*
G01X271558Y645292D02*
X271267Y645083D01*
X270933Y645000D01*
X270600Y645083D01*
X270308Y645333D01*
X270100Y645708D01*
X270017Y646083D01*
Y646542D01*
X270100Y646917D01*
X270308Y647250D01*
X270558Y647417D01*
X270850Y647500D01*
X271183Y647417D01*
X271433Y647250D01*
X271600Y647000D01*
X271683Y646667D01*
X271600Y646375D01*
X271392Y646083D01*
X271142Y645917D01*
X270850Y645875D01*
X270517Y645958D01*
X270267Y646167D01*
X270017Y646542D01*
G01X240810Y604160D02*
Y600160D01*
X233410D01*
G01X282483Y602500D02*
Y605000D01*
X281442D01*
X281108Y604875D01*
X280900Y604708D01*
X280817Y604375D01*
X280900Y604042D01*
X281150Y603833D01*
X281442Y603708D01*
X282483D01*
G01X281442D02*
X280817Y602500D01*
G01X279342Y604583D02*
X279092Y604833D01*
X278800Y604958D01*
X278467Y605000D01*
X278050Y604917D01*
X277758Y604708D01*
X277675Y604458D01*
X277717Y604208D01*
X277883Y604000D01*
X278717Y603583D01*
X279092Y603292D01*
X279342Y602875D01*
X279425Y602500D01*
X277675D01*
G01X275533D02*
X275450Y603042D01*
X275325Y603500D01*
X275158Y603917D01*
X274950Y604375D01*
X274617Y605000D01*
X276283D01*
G01X273142Y604583D02*
X272892Y604833D01*
X272600Y604958D01*
X272267Y605000D01*
X271850Y604917D01*
X271558Y604708D01*
X271475Y604458D01*
X271517Y604208D01*
X271683Y604000D01*
X272517Y603583D01*
X272892Y603292D01*
X273142Y602875D01*
X273225Y602500D01*
X271475D01*
G01X282483Y611000D02*
Y613500D01*
X281442D01*
X281108Y613375D01*
X280900Y613208D01*
X280817Y612875D01*
X280900Y612542D01*
X281150Y612333D01*
X281442Y612208D01*
X282483D01*
G01X281442D02*
X280817Y611000D01*
G01X278550D02*
Y613500D01*
X279050Y613000D01*
G01Y611000D02*
X278050D01*
G01X276367Y611375D02*
X276117Y611167D01*
X275825Y611042D01*
X275450Y611000D01*
X275075Y611083D01*
X274783Y611250D01*
X274575Y611542D01*
X274533Y611875D01*
X274617Y612208D01*
X274825Y612417D01*
X275117Y612583D01*
X275408Y612625D01*
X275700Y612583D01*
X276075Y612417D01*
X275950Y613500D01*
X274825D01*
G01X272350Y611000D02*
Y613500D01*
X272850Y613000D01*
G01Y611000D02*
X271850D01*
G01X282483Y615000D02*
Y617500D01*
X281442D01*
X281108Y617375D01*
X280900Y617208D01*
X280817Y616875D01*
X280900Y616542D01*
X281150Y616333D01*
X281442Y616208D01*
X282483D01*
G01X281442D02*
X280817Y615000D01*
G01X278550D02*
Y617500D01*
X279050Y617000D01*
G01Y615000D02*
X278050D01*
G01X276367Y615375D02*
X276117Y615167D01*
X275825Y615042D01*
X275450Y615000D01*
X275075Y615083D01*
X274783Y615250D01*
X274575Y615542D01*
X274533Y615875D01*
X274617Y616208D01*
X274825Y616417D01*
X275117Y616583D01*
X275408Y616625D01*
X275700Y616583D01*
X276075Y616417D01*
X275950Y617500D01*
X274825D01*
G01X273267Y615500D02*
X273017Y615208D01*
X272683Y615042D01*
X272308Y615000D01*
X271975Y615042D01*
X271642Y615250D01*
X271433Y615500D01*
X271392Y615750D01*
X271475Y616042D01*
X271767Y616250D01*
X272058Y616333D01*
X272433D01*
G01X272058D02*
X271808Y616458D01*
X271600Y616667D01*
X271517Y616917D01*
X271600Y617167D01*
X271808Y617375D01*
X272183Y617500D01*
X272558Y617458D01*
X272933Y617292D01*
G01X282483Y619000D02*
Y621500D01*
X281442D01*
X281108Y621375D01*
X280900Y621208D01*
X280817Y620875D01*
X280900Y620542D01*
X281150Y620333D01*
X281442Y620208D01*
X282483D01*
G01X281442D02*
X280817Y619000D01*
G01X278550D02*
Y621500D01*
X279050Y621000D01*
G01Y619000D02*
X278050D01*
G01X276242Y620042D02*
X275950Y620333D01*
X275700Y620500D01*
X275367Y620583D01*
X275075Y620500D01*
X274867Y620333D01*
X274700Y620083D01*
X274658Y619792D01*
X274700Y619542D01*
X274867Y619292D01*
X275117Y619083D01*
X275408Y619000D01*
X275742Y619083D01*
X276033Y619333D01*
X276200Y619708D01*
X276242Y620125D01*
X276158Y620667D01*
X276033Y620958D01*
X275825Y621250D01*
X275533Y621458D01*
X275242Y621500D01*
X274950Y621417D01*
X274742Y621208D01*
G01X273267Y619375D02*
X273017Y619167D01*
X272725Y619042D01*
X272350Y619000D01*
X271975Y619083D01*
X271683Y619250D01*
X271475Y619542D01*
X271433Y619875D01*
X271517Y620208D01*
X271725Y620417D01*
X272017Y620583D01*
X272308Y620625D01*
X272600Y620583D01*
X272975Y620417D01*
X272850Y621500D01*
X271725D01*
G01X267483Y632000D02*
Y634500D01*
X266442D01*
X266108Y634375D01*
X265900Y634208D01*
X265817Y633875D01*
X265900Y633542D01*
X266150Y633333D01*
X266442Y633208D01*
X267483D01*
G01X266442D02*
X265817Y632000D01*
G01X264467Y632500D02*
X264217Y632208D01*
X263883Y632042D01*
X263508Y632000D01*
X263175Y632042D01*
X262842Y632250D01*
X262633Y632500D01*
X262592Y632750D01*
X262675Y633042D01*
X262967Y633250D01*
X263258Y633333D01*
X263633D01*
G01X263258D02*
X263008Y633458D01*
X262800Y633667D01*
X262717Y633917D01*
X262800Y634167D01*
X263008Y634375D01*
X263383Y634500D01*
X263758Y634458D01*
X264133Y634292D01*
G01X261367Y632375D02*
X261117Y632167D01*
X260825Y632042D01*
X260450Y632000D01*
X260075Y632083D01*
X259783Y632250D01*
X259575Y632542D01*
X259533Y632875D01*
X259617Y633208D01*
X259825Y633417D01*
X260117Y633583D01*
X260408Y633625D01*
X260700Y633583D01*
X261075Y633417D01*
X260950Y634500D01*
X259825D01*
G01X258058Y632292D02*
X257767Y632083D01*
X257433Y632000D01*
X257100Y632083D01*
X256808Y632333D01*
X256600Y632708D01*
X256517Y633083D01*
Y633542D01*
X256600Y633917D01*
X256808Y634250D01*
X257058Y634417D01*
X257350Y634500D01*
X257683Y634417D01*
X257933Y634250D01*
X258100Y634000D01*
X258183Y633667D01*
X258100Y633375D01*
X257892Y633083D01*
X257642Y632917D01*
X257350Y632875D01*
X257017Y632958D01*
X256767Y633167D01*
X256517Y633542D01*
G01X267983Y623000D02*
Y625500D01*
X266942D01*
X266608Y625375D01*
X266400Y625208D01*
X266317Y624875D01*
X266400Y624542D01*
X266650Y624333D01*
X266942Y624208D01*
X267983D01*
G01X266942D02*
X266317Y623000D01*
G01X264967Y623500D02*
X264717Y623208D01*
X264383Y623042D01*
X264008Y623000D01*
X263675Y623042D01*
X263342Y623250D01*
X263133Y623500D01*
X263092Y623750D01*
X263175Y624042D01*
X263467Y624250D01*
X263758Y624333D01*
X264133D01*
G01X263758D02*
X263508Y624458D01*
X263300Y624667D01*
X263217Y624917D01*
X263300Y625167D01*
X263508Y625375D01*
X263883Y625500D01*
X264258Y625458D01*
X264633Y625292D01*
G01X261742Y624042D02*
X261450Y624333D01*
X261200Y624500D01*
X260867Y624583D01*
X260575Y624500D01*
X260367Y624333D01*
X260200Y624083D01*
X260158Y623792D01*
X260200Y623542D01*
X260367Y623292D01*
X260617Y623083D01*
X260908Y623000D01*
X261242Y623083D01*
X261533Y623333D01*
X261700Y623708D01*
X261742Y624125D01*
X261658Y624667D01*
X261533Y624958D01*
X261325Y625250D01*
X261033Y625458D01*
X260742Y625500D01*
X260450Y625417D01*
X260242Y625208D01*
G01X257850Y625500D02*
X258183Y625417D01*
X258433Y625208D01*
X258600Y624958D01*
X258725Y624625D01*
X258767Y624250D01*
X258725Y623875D01*
X258600Y623542D01*
X258433Y623292D01*
X258183Y623083D01*
X257850Y623000D01*
X257517Y623083D01*
X257267Y623292D01*
X257100Y623542D01*
X256975Y623875D01*
X256933Y624250D01*
X256975Y624625D01*
X257100Y624958D01*
X257267Y625208D01*
X257517Y625417D01*
X257850Y625500D01*
G01X266983Y618000D02*
Y620500D01*
X265942D01*
X265608Y620375D01*
X265400Y620208D01*
X265317Y619875D01*
X265400Y619542D01*
X265650Y619333D01*
X265942Y619208D01*
X266983D01*
G01X265942D02*
X265317Y618000D01*
G01X263967Y618500D02*
X263717Y618208D01*
X263383Y618042D01*
X263008Y618000D01*
X262675Y618042D01*
X262342Y618250D01*
X262133Y618500D01*
X262092Y618750D01*
X262175Y619042D01*
X262467Y619250D01*
X262758Y619333D01*
X263133D01*
G01X262758D02*
X262508Y619458D01*
X262300Y619667D01*
X262217Y619917D01*
X262300Y620167D01*
X262508Y620375D01*
X262883Y620500D01*
X263258Y620458D01*
X263633Y620292D01*
G01X260742Y619042D02*
X260450Y619333D01*
X260200Y619500D01*
X259867Y619583D01*
X259575Y619500D01*
X259367Y619333D01*
X259200Y619083D01*
X259158Y618792D01*
X259200Y618542D01*
X259367Y618292D01*
X259617Y618083D01*
X259908Y618000D01*
X260242Y618083D01*
X260533Y618333D01*
X260700Y618708D01*
X260742Y619125D01*
X260658Y619667D01*
X260533Y619958D01*
X260325Y620250D01*
X260033Y620458D01*
X259742Y620500D01*
X259450Y620417D01*
X259242Y620208D01*
G01X256850Y618000D02*
Y620500D01*
X257350Y620000D01*
G01Y618000D02*
X256350D01*
G01X267983Y627500D02*
Y630000D01*
X266942D01*
X266608Y629875D01*
X266400Y629708D01*
X266317Y629375D01*
X266400Y629042D01*
X266650Y628833D01*
X266942Y628708D01*
X267983D01*
G01X266942D02*
X266317Y627500D01*
G01X264967Y628000D02*
X264717Y627708D01*
X264383Y627542D01*
X264008Y627500D01*
X263675Y627542D01*
X263342Y627750D01*
X263133Y628000D01*
X263092Y628250D01*
X263175Y628542D01*
X263467Y628750D01*
X263758Y628833D01*
X264133D01*
G01X263758D02*
X263508Y628958D01*
X263300Y629167D01*
X263217Y629417D01*
X263300Y629667D01*
X263508Y629875D01*
X263883Y630000D01*
X264258Y629958D01*
X264633Y629792D01*
G01X261742Y628542D02*
X261450Y628833D01*
X261200Y629000D01*
X260867Y629083D01*
X260575Y629000D01*
X260367Y628833D01*
X260200Y628583D01*
X260158Y628292D01*
X260200Y628042D01*
X260367Y627792D01*
X260617Y627583D01*
X260908Y627500D01*
X261242Y627583D01*
X261533Y627833D01*
X261700Y628208D01*
X261742Y628625D01*
X261658Y629167D01*
X261533Y629458D01*
X261325Y629750D01*
X261033Y629958D01*
X260742Y630000D01*
X260450Y629917D01*
X260242Y629708D01*
G01X258767Y627875D02*
X258517Y627667D01*
X258225Y627542D01*
X257850Y627500D01*
X257475Y627583D01*
X257183Y627750D01*
X256975Y628042D01*
X256933Y628375D01*
X257017Y628708D01*
X257225Y628917D01*
X257517Y629083D01*
X257808Y629125D01*
X258100Y629083D01*
X258475Y628917D01*
X258350Y630000D01*
X257225D01*
G01X267483Y636500D02*
Y639000D01*
X266442D01*
X266108Y638875D01*
X265900Y638708D01*
X265817Y638375D01*
X265900Y638042D01*
X266150Y637833D01*
X266442Y637708D01*
X267483D01*
G01X266442D02*
X265817Y636500D01*
G01X264467Y637000D02*
X264217Y636708D01*
X263883Y636542D01*
X263508Y636500D01*
X263175Y636542D01*
X262842Y636750D01*
X262633Y637000D01*
X262592Y637250D01*
X262675Y637542D01*
X262967Y637750D01*
X263258Y637833D01*
X263633D01*
G01X263258D02*
X263008Y637958D01*
X262800Y638167D01*
X262717Y638417D01*
X262800Y638667D01*
X263008Y638875D01*
X263383Y639000D01*
X263758Y638958D01*
X264133Y638792D01*
G01X260450Y636500D02*
X260158Y636542D01*
X259825Y636667D01*
X259617Y636875D01*
X259533Y637167D01*
X259617Y637458D01*
X259867Y637708D01*
X260242Y637833D01*
X260658D01*
X260908Y637917D01*
X261117Y638125D01*
X261200Y638417D01*
X261075Y638708D01*
X260783Y638917D01*
X260450Y639000D01*
X260117Y638917D01*
X259825Y638708D01*
X259700Y638417D01*
X259783Y638125D01*
X259992Y637917D01*
X260242Y637833D01*
X260658D01*
X261033Y637708D01*
X261283Y637458D01*
X261367Y637167D01*
X261283Y636875D01*
X261075Y636667D01*
X260742Y636542D01*
X260450Y636500D01*
G01X257350D02*
X257058Y636542D01*
X256725Y636667D01*
X256517Y636875D01*
X256433Y637167D01*
X256517Y637458D01*
X256767Y637708D01*
X257142Y637833D01*
X257558D01*
X257808Y637917D01*
X258017Y638125D01*
X258100Y638417D01*
X257975Y638708D01*
X257683Y638917D01*
X257350Y639000D01*
X257017Y638917D01*
X256725Y638708D01*
X256600Y638417D01*
X256683Y638125D01*
X256892Y637917D01*
X257142Y637833D01*
X257558D01*
X257933Y637708D01*
X258183Y637458D01*
X258267Y637167D01*
X258183Y636875D01*
X257975Y636667D01*
X257642Y636542D01*
X257350Y636500D01*
G01X238200Y644300D02*
Y640300D01*
X230800D01*
G01X209800Y632500D02*
Y636500D01*
X217200D01*
G01X227492Y644006D02*
Y640006D01*
X220092D01*
G01X220108Y635894D02*
Y639894D01*
X227508D01*
G01X250883Y637292D02*
X251133Y637417D01*
X251425Y637500D01*
X251758D01*
X252133Y637375D01*
X252425Y637167D01*
X252633Y636917D01*
X252800Y636500D01*
X252842Y636125D01*
X252758Y635750D01*
X252633Y635500D01*
X252383Y635250D01*
X252092Y635083D01*
X251800Y635000D01*
X251508D01*
X251217Y635083D01*
X250967Y635208D01*
X250758Y635375D01*
G01X248700Y635000D02*
X248408Y635042D01*
X248075Y635167D01*
X247867Y635375D01*
X247783Y635667D01*
X247867Y635958D01*
X248117Y636208D01*
X248492Y636333D01*
X248908D01*
X249158Y636417D01*
X249367Y636625D01*
X249450Y636917D01*
X249325Y637208D01*
X249033Y637417D01*
X248700Y637500D01*
X248367Y637417D01*
X248075Y637208D01*
X247950Y636917D01*
X248033Y636625D01*
X248242Y636417D01*
X248492Y636333D01*
X248908D01*
X249283Y636208D01*
X249533Y635958D01*
X249617Y635667D01*
X249533Y635375D01*
X249325Y635167D01*
X248992Y635042D01*
X248700Y635000D01*
G01X245683D02*
X245600Y635542D01*
X245475Y636000D01*
X245308Y636417D01*
X245100Y636875D01*
X244767Y637500D01*
X246433D01*
G01X242492Y648292D02*
X242617Y648042D01*
X242700Y647750D01*
Y647417D01*
X242575Y647042D01*
X242367Y646750D01*
X242117Y646542D01*
X241700Y646375D01*
X241325Y646333D01*
X240950Y646417D01*
X240700Y646542D01*
X240450Y646792D01*
X240283Y647083D01*
X240200Y647375D01*
Y647667D01*
X240283Y647958D01*
X240408Y648208D01*
X240575Y648417D01*
G01X240492Y649767D02*
X240283Y650058D01*
X240200Y650392D01*
X240283Y650725D01*
X240533Y651017D01*
X240908Y651225D01*
X241283Y651308D01*
X241742D01*
X242117Y651225D01*
X242450Y651017D01*
X242617Y650767D01*
X242700Y650475D01*
X242617Y650142D01*
X242450Y649892D01*
X242200Y649725D01*
X241867Y649642D01*
X241575Y649725D01*
X241283Y649933D01*
X241117Y650183D01*
X241075Y650475D01*
X241158Y650808D01*
X241367Y651058D01*
X241742Y651308D01*
G01X240575Y652658D02*
X240367Y652908D01*
X240242Y653200D01*
X240200Y653575D01*
X240283Y653950D01*
X240450Y654242D01*
X240742Y654450D01*
X241075Y654492D01*
X241408Y654408D01*
X241617Y654200D01*
X241783Y653908D01*
X241825Y653617D01*
X241783Y653325D01*
X241617Y652950D01*
X242700Y653075D01*
Y654200D01*
G01X249583Y641500D02*
Y639000D01*
X247917D01*
G01X246442Y641083D02*
X246192Y641333D01*
X245900Y641458D01*
X245567Y641500D01*
X245150Y641417D01*
X244858Y641208D01*
X244775Y640958D01*
X244817Y640708D01*
X244983Y640500D01*
X245817Y640083D01*
X246192Y639792D01*
X246442Y639375D01*
X246525Y639000D01*
X244775D01*
G01X230340Y611820D02*
Y618820D01*
X216940D01*
Y611820D01*
X230340D01*
G01X247367Y646717D02*
X244867D01*
Y648383D01*
G01Y651150D02*
X247367D01*
X245575Y649608D01*
Y651692D01*
G01X235846Y616376D02*
X242846D01*
Y629776D01*
X235846D01*
Y616376D01*
G01X240833Y663092D02*
X241083Y663217D01*
X241375Y663300D01*
X241708D01*
X242083Y663175D01*
X242375Y662967D01*
X242583Y662717D01*
X242750Y662300D01*
X242792Y661925D01*
X242708Y661550D01*
X242583Y661300D01*
X242333Y661050D01*
X242042Y660883D01*
X241750Y660800D01*
X241458D01*
X241167Y660883D01*
X240917Y661008D01*
X240708Y661175D01*
G01X238650Y660800D02*
Y663300D01*
X239150Y662800D01*
G01Y660800D02*
X238150D01*
G01X235550D02*
Y663300D01*
X236050Y662800D01*
G01Y660800D02*
X235050D01*
G01X233158Y661092D02*
X232867Y660883D01*
X232533Y660800D01*
X232200Y660883D01*
X231908Y661133D01*
X231700Y661508D01*
X231617Y661883D01*
Y662342D01*
X231700Y662717D01*
X231908Y663050D01*
X232158Y663217D01*
X232450Y663300D01*
X232783Y663217D01*
X233033Y663050D01*
X233200Y662800D01*
X233283Y662467D01*
X233200Y662175D01*
X232992Y661883D01*
X232742Y661717D01*
X232450Y661675D01*
X232117Y661758D01*
X231867Y661967D01*
X231617Y662342D01*
G01X227533Y663292D02*
X227783Y663417D01*
X228075Y663500D01*
X228408D01*
X228783Y663375D01*
X229075Y663167D01*
X229283Y662917D01*
X229450Y662500D01*
X229492Y662125D01*
X229408Y661750D01*
X229283Y661500D01*
X229033Y661250D01*
X228742Y661083D01*
X228450Y661000D01*
X228158D01*
X227867Y661083D01*
X227617Y661208D01*
X227408Y661375D01*
G01X225350Y661000D02*
Y663500D01*
X225850Y663000D01*
G01Y661000D02*
X224850D01*
G01X223042Y663083D02*
X222792Y663333D01*
X222500Y663458D01*
X222167Y663500D01*
X221750Y663417D01*
X221458Y663208D01*
X221375Y662958D01*
X221417Y662708D01*
X221583Y662500D01*
X222417Y662083D01*
X222792Y661792D01*
X223042Y661375D01*
X223125Y661000D01*
X221375D01*
G01X220067Y661500D02*
X219817Y661208D01*
X219483Y661042D01*
X219108Y661000D01*
X218775Y661042D01*
X218442Y661250D01*
X218233Y661500D01*
X218192Y661750D01*
X218275Y662042D01*
X218567Y662250D01*
X218858Y662333D01*
X219233D01*
G01X218858D02*
X218608Y662458D01*
X218400Y662667D01*
X218317Y662917D01*
X218400Y663167D01*
X218608Y663375D01*
X218983Y663500D01*
X219358Y663458D01*
X219733Y663292D01*
G01X250959Y688817D02*
X251084Y688567D01*
X251167Y688275D01*
Y687942D01*
X251042Y687567D01*
X250834Y687275D01*
X250584Y687067D01*
X250167Y686900D01*
X249792Y686858D01*
X249417Y686942D01*
X249167Y687067D01*
X248917Y687317D01*
X248750Y687608D01*
X248667Y687900D01*
Y688192D01*
X248750Y688483D01*
X248875Y688733D01*
X249042Y688942D01*
G01X249167Y690083D02*
X248875Y690333D01*
X248709Y690667D01*
X248667Y691042D01*
X248709Y691375D01*
X248917Y691708D01*
X249167Y691917D01*
X249417Y691958D01*
X249709Y691875D01*
X249917Y691583D01*
X250000Y691292D01*
Y690917D01*
G01Y691292D02*
X250125Y691542D01*
X250334Y691750D01*
X250584Y691833D01*
X250834Y691750D01*
X251042Y691542D01*
X251167Y691167D01*
X251125Y690792D01*
X250959Y690417D01*
G01X249167Y693183D02*
X248875Y693433D01*
X248709Y693767D01*
X248667Y694142D01*
X248709Y694475D01*
X248917Y694808D01*
X249167Y695017D01*
X249417Y695058D01*
X249709Y694975D01*
X249917Y694683D01*
X250000Y694392D01*
Y694017D01*
G01Y694392D02*
X250125Y694642D01*
X250334Y694850D01*
X250584Y694933D01*
X250834Y694850D01*
X251042Y694642D01*
X251167Y694267D01*
X251125Y693892D01*
X250959Y693517D01*
G01X242583Y664500D02*
Y667000D01*
X241542D01*
X241208Y666875D01*
X241000Y666708D01*
X240917Y666375D01*
X241000Y666042D01*
X241250Y665833D01*
X241542Y665708D01*
X242583D01*
G01X241542D02*
X240917Y664500D01*
G01X238150D02*
Y667000D01*
X239692Y665208D01*
X237608D01*
G01X235550Y667000D02*
X235883Y666917D01*
X236133Y666708D01*
X236300Y666458D01*
X236425Y666125D01*
X236467Y665750D01*
X236425Y665375D01*
X236300Y665042D01*
X236133Y664792D01*
X235883Y664583D01*
X235550Y664500D01*
X235217Y664583D01*
X234967Y664792D01*
X234800Y665042D01*
X234675Y665375D01*
X234633Y665750D01*
X234675Y666125D01*
X234800Y666458D01*
X234967Y666708D01*
X235217Y666917D01*
X235550Y667000D01*
G01X233242Y665542D02*
X232950Y665833D01*
X232700Y666000D01*
X232367Y666083D01*
X232075Y666000D01*
X231867Y665833D01*
X231700Y665583D01*
X231658Y665292D01*
X231700Y665042D01*
X231867Y664792D01*
X232117Y664583D01*
X232408Y664500D01*
X232742Y664583D01*
X233033Y664833D01*
X233200Y665208D01*
X233242Y665625D01*
X233158Y666167D01*
X233033Y666458D01*
X232825Y666750D01*
X232533Y666958D01*
X232242Y667000D01*
X231950Y666917D01*
X231742Y666708D01*
G01X242583Y668200D02*
Y670700D01*
X241542D01*
X241208Y670575D01*
X241000Y670408D01*
X240917Y670075D01*
X241000Y669742D01*
X241250Y669533D01*
X241542Y669408D01*
X242583D01*
G01X241542D02*
X240917Y668200D01*
G01X238150D02*
Y670700D01*
X239692Y668908D01*
X237608D01*
G01X235550Y670700D02*
X235883Y670617D01*
X236133Y670408D01*
X236300Y670158D01*
X236425Y669825D01*
X236467Y669450D01*
X236425Y669075D01*
X236300Y668742D01*
X236133Y668492D01*
X235883Y668283D01*
X235550Y668200D01*
X235217Y668283D01*
X234967Y668492D01*
X234800Y668742D01*
X234675Y669075D01*
X234633Y669450D01*
X234675Y669825D01*
X234800Y670158D01*
X234967Y670408D01*
X235217Y670617D01*
X235550Y670700D01*
G01X233367Y668700D02*
X233117Y668408D01*
X232783Y668242D01*
X232408Y668200D01*
X232075Y668242D01*
X231742Y668450D01*
X231533Y668700D01*
X231492Y668950D01*
X231575Y669242D01*
X231867Y669450D01*
X232158Y669533D01*
X232533D01*
G01X232158D02*
X231908Y669658D01*
X231700Y669867D01*
X231617Y670117D01*
X231700Y670367D01*
X231908Y670575D01*
X232283Y670700D01*
X232658Y670658D01*
X233033Y670492D01*
G01X229283Y668400D02*
Y670900D01*
X228242D01*
X227908Y670775D01*
X227700Y670608D01*
X227617Y670275D01*
X227700Y669942D01*
X227950Y669733D01*
X228242Y669608D01*
X229283D01*
G01X228242D02*
X227617Y668400D01*
G01X224850D02*
Y670900D01*
X226392Y669108D01*
X224308D01*
G01X222250Y668400D02*
Y670900D01*
X222750Y670400D01*
G01Y668400D02*
X221750D01*
G01X220067Y668900D02*
X219817Y668608D01*
X219483Y668442D01*
X219108Y668400D01*
X218775Y668442D01*
X218442Y668650D01*
X218233Y668900D01*
X218192Y669150D01*
X218275Y669442D01*
X218567Y669650D01*
X218858Y669733D01*
X219233D01*
G01X218858D02*
X218608Y669858D01*
X218400Y670067D01*
X218317Y670317D01*
X218400Y670567D01*
X218608Y670775D01*
X218983Y670900D01*
X219358Y670858D01*
X219733Y670692D01*
G01X229283Y664700D02*
Y667200D01*
X228242D01*
X227908Y667075D01*
X227700Y666908D01*
X227617Y666575D01*
X227700Y666242D01*
X227950Y666033D01*
X228242Y665908D01*
X229283D01*
G01X228242D02*
X227617Y664700D01*
G01X224850D02*
Y667200D01*
X226392Y665408D01*
X224308D01*
G01X222250Y664700D02*
Y667200D01*
X222750Y666700D01*
G01Y664700D02*
X221750D01*
G01X220067Y665075D02*
X219817Y664867D01*
X219525Y664742D01*
X219150Y664700D01*
X218775Y664783D01*
X218483Y664950D01*
X218275Y665242D01*
X218233Y665575D01*
X218317Y665908D01*
X218525Y666117D01*
X218817Y666283D01*
X219108Y666325D01*
X219400Y666283D01*
X219775Y666117D01*
X219650Y667200D01*
X218525D01*
G01X329015Y171633D02*
X329265Y171758D01*
X329557Y171841D01*
X329890D01*
X330265Y171716D01*
X330557Y171508D01*
X330765Y171258D01*
X330932Y170841D01*
X330974Y170466D01*
X330890Y170091D01*
X330765Y169841D01*
X330515Y169591D01*
X330224Y169424D01*
X329932Y169341D01*
X329640D01*
X329349Y169424D01*
X329099Y169549D01*
X328890Y169716D01*
G01X327749D02*
X327499Y169508D01*
X327207Y169383D01*
X326832Y169341D01*
X326457Y169424D01*
X326165Y169591D01*
X325957Y169883D01*
X325915Y170216D01*
X325999Y170549D01*
X326207Y170758D01*
X326499Y170924D01*
X326790Y170966D01*
X327082Y170924D01*
X327457Y170758D01*
X327332Y171841D01*
X326207D01*
G01X323732Y169341D02*
Y171841D01*
X324232Y171341D01*
G01Y169341D02*
X323232D01*
G01X320632D02*
Y171841D01*
X321132Y171341D01*
G01Y169341D02*
X320132D01*
G01X326731Y176533D02*
X326981Y176658D01*
X327273Y176741D01*
X327606D01*
X327981Y176616D01*
X328273Y176408D01*
X328481Y176158D01*
X328648Y175741D01*
X328690Y175366D01*
X328606Y174991D01*
X328481Y174741D01*
X328231Y174491D01*
X327940Y174324D01*
X327648Y174241D01*
X327356D01*
X327065Y174324D01*
X326815Y174449D01*
X326606Y174616D01*
G01X325340Y176324D02*
X325090Y176574D01*
X324798Y176699D01*
X324465Y176741D01*
X324048Y176658D01*
X323756Y176449D01*
X323673Y176199D01*
X323715Y175949D01*
X323881Y175741D01*
X324715Y175324D01*
X325090Y175033D01*
X325340Y174616D01*
X325423Y174241D01*
X323673D01*
G01X322365Y174616D02*
X322115Y174408D01*
X321823Y174283D01*
X321448Y174241D01*
X321073Y174324D01*
X320781Y174491D01*
X320573Y174783D01*
X320531Y175116D01*
X320615Y175449D01*
X320823Y175658D01*
X321115Y175824D01*
X321406Y175866D01*
X321698Y175824D01*
X322073Y175658D01*
X321948Y176741D01*
X320823D01*
G01X318158Y215559D02*
X318408Y215684D01*
X318700Y215767D01*
X319033D01*
X319408Y215642D01*
X319700Y215434D01*
X319908Y215184D01*
X320075Y214767D01*
X320117Y214392D01*
X320033Y214017D01*
X319908Y213767D01*
X319658Y213517D01*
X319367Y213350D01*
X319075Y213267D01*
X318783D01*
X318492Y213350D01*
X318242Y213475D01*
X318033Y213642D01*
G01X315975Y213267D02*
Y215767D01*
X316475Y215267D01*
G01Y213267D02*
X315475D01*
G01X312875D02*
X312583Y213309D01*
X312250Y213434D01*
X312042Y213642D01*
X311958Y213934D01*
X312042Y214225D01*
X312292Y214475D01*
X312667Y214600D01*
X313083D01*
X313333Y214684D01*
X313542Y214892D01*
X313625Y215184D01*
X313500Y215475D01*
X313208Y215684D01*
X312875Y215767D01*
X312542Y215684D01*
X312250Y215475D01*
X312125Y215184D01*
X312208Y214892D01*
X312417Y214684D01*
X312667Y214600D01*
X313083D01*
X313458Y214475D01*
X313708Y214225D01*
X313792Y213934D01*
X313708Y213642D01*
X313500Y213434D01*
X313167Y213309D01*
X312875Y213267D01*
G01X309858D02*
X309775Y213809D01*
X309650Y214267D01*
X309483Y214684D01*
X309275Y215142D01*
X308942Y215767D01*
X310608D01*
G01X318158Y235959D02*
X318408Y236084D01*
X318700Y236167D01*
X319033D01*
X319408Y236042D01*
X319700Y235834D01*
X319908Y235584D01*
X320075Y235167D01*
X320117Y234792D01*
X320033Y234417D01*
X319908Y234167D01*
X319658Y233917D01*
X319367Y233750D01*
X319075Y233667D01*
X318783D01*
X318492Y233750D01*
X318242Y233875D01*
X318033Y234042D01*
G01X315975Y233667D02*
Y236167D01*
X316475Y235667D01*
G01Y233667D02*
X315475D01*
G01X312875D02*
X312583Y233709D01*
X312250Y233834D01*
X312042Y234042D01*
X311958Y234334D01*
X312042Y234625D01*
X312292Y234875D01*
X312667Y235000D01*
X313083D01*
X313333Y235084D01*
X313542Y235292D01*
X313625Y235584D01*
X313500Y235875D01*
X313208Y236084D01*
X312875Y236167D01*
X312542Y236084D01*
X312250Y235875D01*
X312125Y235584D01*
X312208Y235292D01*
X312417Y235084D01*
X312667Y235000D01*
X313083D01*
X313458Y234875D01*
X313708Y234625D01*
X313792Y234334D01*
X313708Y234042D01*
X313500Y233834D01*
X313167Y233709D01*
X312875Y233667D01*
G01X309775D02*
X309483Y233709D01*
X309150Y233834D01*
X308942Y234042D01*
X308858Y234334D01*
X308942Y234625D01*
X309192Y234875D01*
X309567Y235000D01*
X309983D01*
X310233Y235084D01*
X310442Y235292D01*
X310525Y235584D01*
X310400Y235875D01*
X310108Y236084D01*
X309775Y236167D01*
X309442Y236084D01*
X309150Y235875D01*
X309025Y235584D01*
X309108Y235292D01*
X309317Y235084D01*
X309567Y235000D01*
X309983D01*
X310358Y234875D01*
X310608Y234625D01*
X310692Y234334D01*
X310608Y234042D01*
X310400Y233834D01*
X310067Y233709D01*
X309775Y233667D01*
G01X339992Y235441D02*
X340117Y235191D01*
X340200Y234899D01*
Y234566D01*
X340075Y234191D01*
X339867Y233899D01*
X339617Y233691D01*
X339200Y233524D01*
X338825Y233482D01*
X338450Y233566D01*
X338200Y233691D01*
X337950Y233941D01*
X337783Y234232D01*
X337700Y234524D01*
Y234816D01*
X337783Y235107D01*
X337908Y235357D01*
X338075Y235566D01*
G01Y236707D02*
X337867Y236957D01*
X337742Y237249D01*
X337700Y237624D01*
X337783Y237999D01*
X337950Y238291D01*
X338242Y238499D01*
X338575Y238541D01*
X338908Y238457D01*
X339117Y238249D01*
X339283Y237957D01*
X339325Y237666D01*
X339283Y237374D01*
X339117Y236999D01*
X340200Y237124D01*
Y238249D01*
G01X337700Y240724D02*
X340200D01*
X339700Y240224D01*
G01X337700D02*
Y241224D01*
G01X339783Y243032D02*
X340033Y243282D01*
X340158Y243574D01*
X340200Y243907D01*
X340117Y244324D01*
X339908Y244616D01*
X339658Y244699D01*
X339408Y244657D01*
X339200Y244491D01*
X338783Y243657D01*
X338492Y243282D01*
X338075Y243032D01*
X337700Y242949D01*
Y244699D01*
G01X339892Y217391D02*
X340017Y217141D01*
X340100Y216849D01*
Y216516D01*
X339975Y216141D01*
X339767Y215849D01*
X339517Y215641D01*
X339100Y215474D01*
X338725Y215432D01*
X338350Y215516D01*
X338100Y215641D01*
X337850Y215891D01*
X337683Y216182D01*
X337600Y216474D01*
Y216766D01*
X337683Y217057D01*
X337808Y217307D01*
X337975Y217516D01*
G01X339683Y218782D02*
X339933Y219032D01*
X340058Y219324D01*
X340100Y219657D01*
X340017Y220074D01*
X339808Y220366D01*
X339558Y220449D01*
X339308Y220407D01*
X339100Y220241D01*
X338683Y219407D01*
X338392Y219032D01*
X337975Y218782D01*
X337600Y218699D01*
Y220449D01*
G01X337892Y221966D02*
X337683Y222257D01*
X337600Y222591D01*
X337683Y222924D01*
X337933Y223216D01*
X338308Y223424D01*
X338683Y223507D01*
X339142D01*
X339517Y223424D01*
X339850Y223216D01*
X340017Y222966D01*
X340100Y222674D01*
X340017Y222341D01*
X339850Y222091D01*
X339600Y221924D01*
X339267Y221841D01*
X338975Y221924D01*
X338683Y222132D01*
X338517Y222382D01*
X338475Y222674D01*
X338558Y223007D01*
X338767Y223257D01*
X339142Y223507D01*
G01X314765Y207932D02*
X315015Y208057D01*
X315307Y208140D01*
X315640D01*
X316015Y208015D01*
X316307Y207807D01*
X316515Y207557D01*
X316682Y207140D01*
X316724Y206765D01*
X316640Y206390D01*
X316515Y206140D01*
X316265Y205890D01*
X315974Y205723D01*
X315682Y205640D01*
X315390D01*
X315099Y205723D01*
X314849Y205848D01*
X314640Y206015D01*
G01X313374Y207723D02*
X313124Y207973D01*
X312832Y208098D01*
X312499Y208140D01*
X312082Y208057D01*
X311790Y207848D01*
X311707Y207598D01*
X311749Y207348D01*
X311915Y207140D01*
X312749Y206723D01*
X313124Y206432D01*
X313374Y206015D01*
X313457Y205640D01*
X311707D01*
G01X309482D02*
X309190Y205682D01*
X308857Y205807D01*
X308649Y206015D01*
X308565Y206307D01*
X308649Y206598D01*
X308899Y206848D01*
X309274Y206973D01*
X309690D01*
X309940Y207057D01*
X310149Y207265D01*
X310232Y207557D01*
X310107Y207848D01*
X309815Y208057D01*
X309482Y208140D01*
X309149Y208057D01*
X308857Y207848D01*
X308732Y207557D01*
X308815Y207265D01*
X309024Y207057D01*
X309274Y206973D01*
X309690D01*
X310065Y206848D01*
X310315Y206598D01*
X310399Y206307D01*
X310315Y206015D01*
X310107Y205807D01*
X309774Y205682D01*
X309482Y205640D01*
G01X321341Y383785D02*
X323841D01*
Y384826D01*
X323716Y385160D01*
X323549Y385368D01*
X323216Y385451D01*
X322883Y385368D01*
X322674Y385118D01*
X322549Y384826D01*
Y383785D01*
G01Y384826D02*
X321341Y385451D01*
G01X322383Y386926D02*
X322674Y387218D01*
X322841Y387468D01*
X322924Y387801D01*
X322841Y388093D01*
X322674Y388301D01*
X322424Y388468D01*
X322133Y388510D01*
X321883Y388468D01*
X321633Y388301D01*
X321424Y388051D01*
X321341Y387760D01*
X321424Y387426D01*
X321674Y387135D01*
X322049Y386968D01*
X322466Y386926D01*
X323008Y387010D01*
X323299Y387135D01*
X323591Y387343D01*
X323799Y387635D01*
X323841Y387926D01*
X323758Y388218D01*
X323549Y388426D01*
G01X321341Y391318D02*
X323841D01*
X322049Y389776D01*
Y391860D01*
G01X329174Y383918D02*
X325174D01*
Y391318D01*
G01X329782Y383243D02*
Y397243D01*
G01X342782Y383243D02*
X329782D01*
G01X341382Y398409D02*
X341715Y398451D01*
X342007Y398617D01*
X342257Y398867D01*
X342424Y399159D01*
X342507Y399492D01*
Y399826D01*
X342424Y400159D01*
X342257Y400451D01*
X342007Y400701D01*
X341715Y400867D01*
X341382Y400909D01*
X341049Y400867D01*
X340757Y400701D01*
X340507Y400451D01*
X340340Y400159D01*
X340257Y399826D01*
Y399492D01*
X340340Y399159D01*
X340507Y398867D01*
X340757Y398617D01*
X341049Y398451D01*
X341382Y398409D01*
G01X341049Y399076D02*
X340549Y398409D01*
G01X339074Y400492D02*
X338824Y400742D01*
X338532Y400867D01*
X338199Y400909D01*
X337782Y400826D01*
X337490Y400617D01*
X337407Y400367D01*
X337449Y400117D01*
X337615Y399909D01*
X338449Y399492D01*
X338824Y399201D01*
X339074Y398784D01*
X339157Y398409D01*
X337407D01*
G01X336099Y398784D02*
X335849Y398576D01*
X335557Y398451D01*
X335182Y398409D01*
X334807Y398492D01*
X334515Y398659D01*
X334307Y398951D01*
X334265Y399284D01*
X334349Y399617D01*
X334557Y399826D01*
X334849Y399992D01*
X335140Y400034D01*
X335432Y399992D01*
X335807Y399826D01*
X335682Y400909D01*
X334557D01*
G01X329782Y397243D02*
X342782D01*
G01X303592Y508767D02*
X303717Y508517D01*
X303800Y508225D01*
Y507892D01*
X303675Y507517D01*
X303467Y507225D01*
X303217Y507017D01*
X302800Y506850D01*
X302425Y506808D01*
X302050Y506892D01*
X301800Y507017D01*
X301550Y507267D01*
X301383Y507558D01*
X301300Y507850D01*
Y508142D01*
X301383Y508433D01*
X301508Y508683D01*
X301675Y508892D01*
G01Y510033D02*
X301467Y510283D01*
X301342Y510575D01*
X301300Y510950D01*
X301383Y511325D01*
X301550Y511617D01*
X301842Y511825D01*
X302175Y511867D01*
X302508Y511783D01*
X302717Y511575D01*
X302883Y511283D01*
X302925Y510992D01*
X302883Y510700D01*
X302717Y510325D01*
X303800Y510450D01*
Y511575D01*
G01Y514050D02*
X303717Y513717D01*
X303508Y513467D01*
X303258Y513300D01*
X302925Y513175D01*
X302550Y513133D01*
X302175Y513175D01*
X301842Y513300D01*
X301592Y513467D01*
X301383Y513717D01*
X301300Y514050D01*
X301383Y514383D01*
X301592Y514633D01*
X301842Y514800D01*
X302175Y514925D01*
X302550Y514967D01*
X302925Y514925D01*
X303258Y514800D01*
X303508Y514633D01*
X303717Y514383D01*
X303800Y514050D01*
G01X303383Y516358D02*
X303633Y516608D01*
X303758Y516900D01*
X303800Y517233D01*
X303717Y517650D01*
X303508Y517942D01*
X303258Y518025D01*
X303008Y517983D01*
X302800Y517817D01*
X302383Y516983D01*
X302092Y516608D01*
X301675Y516358D01*
X301300Y516275D01*
Y518025D01*
G01X278587Y512647D02*
X281087D01*
Y513688D01*
X280962Y514022D01*
X280795Y514230D01*
X280462Y514313D01*
X280129Y514230D01*
X279920Y513980D01*
X279795Y513688D01*
Y512647D01*
G01Y513688D02*
X278587Y514313D01*
G01Y516580D02*
X281087D01*
X280587Y516080D01*
G01X278587D02*
Y517080D01*
G01X279629Y518888D02*
X279920Y519180D01*
X280087Y519430D01*
X280170Y519763D01*
X280087Y520055D01*
X279920Y520263D01*
X279670Y520430D01*
X279379Y520472D01*
X279129Y520430D01*
X278879Y520263D01*
X278670Y520013D01*
X278587Y519722D01*
X278670Y519388D01*
X278920Y519097D01*
X279295Y518930D01*
X279712Y518888D01*
X280254Y518972D01*
X280545Y519097D01*
X280837Y519305D01*
X281045Y519597D01*
X281087Y519888D01*
X281004Y520180D01*
X280795Y520388D01*
G01X278879Y522072D02*
X278670Y522363D01*
X278587Y522697D01*
X278670Y523030D01*
X278920Y523322D01*
X279295Y523530D01*
X279670Y523613D01*
X280129D01*
X280504Y523530D01*
X280837Y523322D01*
X281004Y523072D01*
X281087Y522780D01*
X281004Y522447D01*
X280837Y522197D01*
X280587Y522030D01*
X280254Y521947D01*
X279962Y522030D01*
X279670Y522238D01*
X279504Y522488D01*
X279462Y522780D01*
X279545Y523113D01*
X279754Y523363D01*
X280129Y523613D01*
G01X346383Y515567D02*
Y518067D01*
X345342D01*
X345008Y517942D01*
X344800Y517775D01*
X344717Y517442D01*
X344800Y517109D01*
X345050Y516900D01*
X345342Y516775D01*
X346383D01*
G01X345342D02*
X344717Y515567D01*
G01X342533D02*
X342450Y516109D01*
X342325Y516567D01*
X342158Y516984D01*
X341950Y517442D01*
X341617Y518067D01*
X343283D01*
G01X339350Y515567D02*
Y518067D01*
X339850Y517567D01*
G01Y515567D02*
X338850D01*
G01X336250D02*
X335958Y515609D01*
X335625Y515734D01*
X335417Y515942D01*
X335333Y516234D01*
X335417Y516525D01*
X335667Y516775D01*
X336042Y516900D01*
X336458D01*
X336708Y516984D01*
X336917Y517192D01*
X337000Y517484D01*
X336875Y517775D01*
X336583Y517984D01*
X336250Y518067D01*
X335917Y517984D01*
X335625Y517775D01*
X335500Y517484D01*
X335583Y517192D01*
X335792Y516984D01*
X336042Y516900D01*
X336458D01*
X336833Y516775D01*
X337083Y516525D01*
X337167Y516234D01*
X337083Y515942D01*
X336875Y515734D01*
X336542Y515609D01*
X336250Y515567D01*
G01X329300Y510000D02*
Y514000D01*
X336700D01*
G01X282086Y512447D02*
X284586D01*
Y513488D01*
X284461Y513822D01*
X284294Y514030D01*
X283961Y514113D01*
X283628Y514030D01*
X283419Y513780D01*
X283294Y513488D01*
Y512447D01*
G01Y513488D02*
X282086Y514113D01*
G01Y516297D02*
X282628Y516380D01*
X283086Y516505D01*
X283503Y516672D01*
X283961Y516880D01*
X284586Y517213D01*
Y515547D01*
G01X282086Y519480D02*
X282128Y519772D01*
X282253Y520105D01*
X282461Y520313D01*
X282753Y520397D01*
X283044Y520313D01*
X283294Y520063D01*
X283419Y519688D01*
Y519272D01*
X283503Y519022D01*
X283711Y518813D01*
X284003Y518730D01*
X284294Y518855D01*
X284503Y519147D01*
X284586Y519480D01*
X284503Y519813D01*
X284294Y520105D01*
X284003Y520230D01*
X283711Y520147D01*
X283503Y519938D01*
X283419Y519688D01*
Y519272D01*
X283294Y518897D01*
X283044Y518647D01*
X282753Y518563D01*
X282461Y518647D01*
X282253Y518855D01*
X282128Y519188D01*
X282086Y519480D01*
G01Y523080D02*
X284586D01*
X282794Y521538D01*
Y523622D01*
G01X328567Y524000D02*
Y522208D01*
X328400Y521833D01*
X328067Y521583D01*
X327650Y521500D01*
X327233Y521583D01*
X326900Y521833D01*
X326733Y522208D01*
Y524000D01*
G01X324550Y521500D02*
Y524000D01*
X325050Y523500D01*
G01Y521500D02*
X324050D01*
G01X321450Y524000D02*
X321783Y523917D01*
X322033Y523708D01*
X322200Y523458D01*
X322325Y523125D01*
X322367Y522750D01*
X322325Y522375D01*
X322200Y522042D01*
X322033Y521792D01*
X321783Y521583D01*
X321450Y521500D01*
X321117Y521583D01*
X320867Y521792D01*
X320700Y522042D01*
X320575Y522375D01*
X320533Y522750D01*
X320575Y523125D01*
X320700Y523458D01*
X320867Y523708D01*
X321117Y523917D01*
X321450Y524000D01*
G01X319267Y522000D02*
X319017Y521708D01*
X318683Y521542D01*
X318308Y521500D01*
X317975Y521542D01*
X317642Y521750D01*
X317433Y522000D01*
X317392Y522250D01*
X317475Y522542D01*
X317767Y522750D01*
X318058Y522833D01*
X318433D01*
G01X318058D02*
X317808Y522958D01*
X317600Y523167D01*
X317517Y523417D01*
X317600Y523667D01*
X317808Y523875D01*
X318183Y524000D01*
X318558Y523958D01*
X318933Y523792D01*
G01X310700Y507000D02*
X324100D01*
G01X310700Y517000D02*
Y507000D01*
G01X324100Y517000D02*
X310700D01*
G01X324100Y507000D02*
Y517000D01*
G01X275600Y569017D02*
X278100D01*
Y570058D01*
X277975Y570392D01*
X277808Y570600D01*
X277475Y570683D01*
X277142Y570600D01*
X276933Y570350D01*
X276808Y570058D01*
Y569017D01*
G01Y570058D02*
X275600Y570683D01*
G01Y572950D02*
X278100D01*
X277600Y572450D01*
G01X275600D02*
Y573450D01*
G01X275975Y575133D02*
X275767Y575383D01*
X275642Y575675D01*
X275600Y576050D01*
X275683Y576425D01*
X275850Y576717D01*
X276142Y576925D01*
X276475Y576967D01*
X276808Y576883D01*
X277017Y576675D01*
X277183Y576383D01*
X277225Y576092D01*
X277183Y575800D01*
X277017Y575425D01*
X278100Y575550D01*
Y576675D01*
G01X275892Y578442D02*
X275683Y578733D01*
X275600Y579067D01*
X275683Y579400D01*
X275933Y579692D01*
X276308Y579900D01*
X276683Y579983D01*
X277142D01*
X277517Y579900D01*
X277850Y579692D01*
X278017Y579442D01*
X278100Y579150D01*
X278017Y578817D01*
X277850Y578567D01*
X277600Y578400D01*
X277267Y578317D01*
X276975Y578400D01*
X276683Y578608D01*
X276517Y578858D01*
X276475Y579150D01*
X276558Y579483D01*
X276767Y579733D01*
X277142Y579983D01*
G01X297283Y549200D02*
Y551700D01*
X296242D01*
X295908Y551575D01*
X295700Y551408D01*
X295617Y551075D01*
X295700Y550742D01*
X295950Y550533D01*
X296242Y550408D01*
X297283D01*
G01X296242D02*
X295617Y549200D01*
G01X293350D02*
Y551700D01*
X293850Y551200D01*
G01Y549200D02*
X292850D01*
G01X290333D02*
X290250Y549742D01*
X290125Y550200D01*
X289958Y550617D01*
X289750Y551075D01*
X289417Y551700D01*
X291083D01*
G01X288067Y549575D02*
X287817Y549367D01*
X287525Y549242D01*
X287150Y549200D01*
X286775Y549283D01*
X286483Y549450D01*
X286275Y549742D01*
X286233Y550075D01*
X286317Y550408D01*
X286525Y550617D01*
X286817Y550783D01*
X287108Y550825D01*
X287400Y550783D01*
X287775Y550617D01*
X287650Y551700D01*
X286525D01*
G01X279300Y569017D02*
X281800D01*
Y570058D01*
X281675Y570392D01*
X281508Y570600D01*
X281175Y570683D01*
X280842Y570600D01*
X280633Y570350D01*
X280508Y570058D01*
Y569017D01*
G01Y570058D02*
X279300Y570683D01*
G01Y572950D02*
X281800D01*
X281300Y572450D01*
G01X279300D02*
Y573450D01*
G01X279592Y575342D02*
X279383Y575633D01*
X279300Y575967D01*
X279383Y576300D01*
X279633Y576592D01*
X280008Y576800D01*
X280383Y576883D01*
X280842D01*
X281217Y576800D01*
X281550Y576592D01*
X281717Y576342D01*
X281800Y576050D01*
X281717Y575717D01*
X281550Y575467D01*
X281300Y575300D01*
X280967Y575217D01*
X280675Y575300D01*
X280383Y575508D01*
X280217Y575758D01*
X280175Y576050D01*
X280258Y576383D01*
X280467Y576633D01*
X280842Y576883D01*
G01X279800Y578233D02*
X279508Y578483D01*
X279342Y578817D01*
X279300Y579192D01*
X279342Y579525D01*
X279550Y579858D01*
X279800Y580067D01*
X280050Y580108D01*
X280342Y580025D01*
X280550Y579733D01*
X280633Y579442D01*
Y579067D01*
G01Y579442D02*
X280758Y579692D01*
X280967Y579900D01*
X281217Y579983D01*
X281467Y579900D01*
X281675Y579692D01*
X281800Y579317D01*
X281758Y578942D01*
X281592Y578567D01*
G01X288683Y593467D02*
Y595967D01*
X287642D01*
X287308Y595842D01*
X287100Y595675D01*
X287017Y595342D01*
X287100Y595009D01*
X287350Y594800D01*
X287642Y594675D01*
X288683D01*
G01X287642D02*
X287017Y593467D01*
G01X285667Y593967D02*
X285417Y593675D01*
X285083Y593509D01*
X284708Y593467D01*
X284375Y593509D01*
X284042Y593717D01*
X283833Y593967D01*
X283792Y594217D01*
X283875Y594509D01*
X284167Y594717D01*
X284458Y594800D01*
X284833D01*
G01X284458D02*
X284208Y594925D01*
X284000Y595134D01*
X283917Y595384D01*
X284000Y595634D01*
X284208Y595842D01*
X284583Y595967D01*
X284958Y595925D01*
X285333Y595759D01*
G01X281650Y593467D02*
X281358Y593509D01*
X281025Y593634D01*
X280817Y593842D01*
X280733Y594134D01*
X280817Y594425D01*
X281067Y594675D01*
X281442Y594800D01*
X281858D01*
X282108Y594884D01*
X282317Y595092D01*
X282400Y595384D01*
X282275Y595675D01*
X281983Y595884D01*
X281650Y595967D01*
X281317Y595884D01*
X281025Y595675D01*
X280900Y595384D01*
X280983Y595092D01*
X281192Y594884D01*
X281442Y594800D01*
X281858D01*
X282233Y594675D01*
X282483Y594425D01*
X282567Y594134D01*
X282483Y593842D01*
X282275Y593634D01*
X281942Y593509D01*
X281650Y593467D01*
G01X279342Y594509D02*
X279050Y594800D01*
X278800Y594967D01*
X278467Y595050D01*
X278175Y594967D01*
X277967Y594800D01*
X277800Y594550D01*
X277758Y594259D01*
X277800Y594009D01*
X277967Y593759D01*
X278217Y593550D01*
X278508Y593467D01*
X278842Y593550D01*
X279133Y593800D01*
X279300Y594175D01*
X279342Y594592D01*
X279258Y595134D01*
X279133Y595425D01*
X278925Y595717D01*
X278633Y595925D01*
X278342Y595967D01*
X278050Y595884D01*
X277842Y595675D01*
G01X289500Y554067D02*
X292000D01*
Y555108D01*
X291875Y555442D01*
X291708Y555650D01*
X291375Y555733D01*
X291042Y555650D01*
X290833Y555400D01*
X290708Y555108D01*
Y554067D01*
G01Y555108D02*
X289500Y555733D01*
G01X290000Y557083D02*
X289708Y557333D01*
X289542Y557667D01*
X289500Y558042D01*
X289542Y558375D01*
X289750Y558708D01*
X290000Y558917D01*
X290250Y558958D01*
X290542Y558875D01*
X290750Y558583D01*
X290833Y558292D01*
Y557917D01*
G01Y558292D02*
X290958Y558542D01*
X291167Y558750D01*
X291417Y558833D01*
X291667Y558750D01*
X291875Y558542D01*
X292000Y558167D01*
X291958Y557792D01*
X291792Y557417D01*
G01X289875Y560183D02*
X289667Y560433D01*
X289542Y560725D01*
X289500Y561100D01*
X289583Y561475D01*
X289750Y561767D01*
X290042Y561975D01*
X290375Y562017D01*
X290708Y561933D01*
X290917Y561725D01*
X291083Y561433D01*
X291125Y561142D01*
X291083Y560850D01*
X290917Y560475D01*
X292000Y560600D01*
Y561725D01*
G01X289500Y564200D02*
X289542Y564492D01*
X289667Y564825D01*
X289875Y565033D01*
X290167Y565117D01*
X290458Y565033D01*
X290708Y564783D01*
X290833Y564408D01*
Y563992D01*
X290917Y563742D01*
X291125Y563533D01*
X291417Y563450D01*
X291708Y563575D01*
X291917Y563867D01*
X292000Y564200D01*
X291917Y564533D01*
X291708Y564825D01*
X291417Y564950D01*
X291125Y564867D01*
X290917Y564658D01*
X290833Y564408D01*
Y563992D01*
X290708Y563617D01*
X290458Y563367D01*
X290167Y563283D01*
X289875Y563367D01*
X289667Y563575D01*
X289542Y563908D01*
X289500Y564200D01*
G01X290700Y589317D02*
X293200D01*
Y590358D01*
X293075Y590692D01*
X292908Y590900D01*
X292575Y590983D01*
X292242Y590900D01*
X292033Y590650D01*
X291908Y590358D01*
Y589317D01*
G01Y590358D02*
X290700Y590983D01*
G01X291200Y592333D02*
X290908Y592583D01*
X290742Y592917D01*
X290700Y593292D01*
X290742Y593625D01*
X290950Y593958D01*
X291200Y594167D01*
X291450Y594208D01*
X291742Y594125D01*
X291950Y593833D01*
X292033Y593542D01*
Y593167D01*
G01Y593542D02*
X292158Y593792D01*
X292367Y594000D01*
X292617Y594083D01*
X292867Y594000D01*
X293075Y593792D01*
X293200Y593417D01*
X293158Y593042D01*
X292992Y592667D01*
G01X290700Y596350D02*
X290742Y596642D01*
X290867Y596975D01*
X291075Y597183D01*
X291367Y597267D01*
X291658Y597183D01*
X291908Y596933D01*
X292033Y596558D01*
Y596142D01*
X292117Y595892D01*
X292325Y595683D01*
X292617Y595600D01*
X292908Y595725D01*
X293117Y596017D01*
X293200Y596350D01*
X293117Y596683D01*
X292908Y596975D01*
X292617Y597100D01*
X292325Y597017D01*
X292117Y596808D01*
X292033Y596558D01*
Y596142D01*
X291908Y595767D01*
X291658Y595517D01*
X291367Y595433D01*
X291075Y595517D01*
X290867Y595725D01*
X290742Y596058D01*
X290700Y596350D01*
G01Y599450D02*
X293200D01*
X292700Y598950D01*
G01X290700D02*
Y599950D01*
G01X288583Y588967D02*
Y591467D01*
X287542D01*
X287208Y591342D01*
X287000Y591175D01*
X286917Y590842D01*
X287000Y590509D01*
X287250Y590300D01*
X287542Y590175D01*
X288583D01*
G01X287542D02*
X286917Y588967D01*
G01X285567Y589467D02*
X285317Y589175D01*
X284983Y589009D01*
X284608Y588967D01*
X284275Y589009D01*
X283942Y589217D01*
X283733Y589467D01*
X283692Y589717D01*
X283775Y590009D01*
X284067Y590217D01*
X284358Y590300D01*
X284733D01*
G01X284358D02*
X284108Y590425D01*
X283900Y590634D01*
X283817Y590884D01*
X283900Y591134D01*
X284108Y591342D01*
X284483Y591467D01*
X284858Y591425D01*
X285233Y591259D01*
G01X282467Y589467D02*
X282217Y589175D01*
X281883Y589009D01*
X281508Y588967D01*
X281175Y589009D01*
X280842Y589217D01*
X280633Y589467D01*
X280592Y589717D01*
X280675Y590009D01*
X280967Y590217D01*
X281258Y590300D01*
X281633D01*
G01X281258D02*
X281008Y590425D01*
X280800Y590634D01*
X280717Y590884D01*
X280800Y591134D01*
X281008Y591342D01*
X281383Y591467D01*
X281758Y591425D01*
X282133Y591259D01*
G01X277950Y588967D02*
Y591467D01*
X279492Y589675D01*
X277408D01*
G01X341283Y575167D02*
Y577667D01*
X340242D01*
X339908Y577542D01*
X339700Y577375D01*
X339617Y577042D01*
X339700Y576709D01*
X339950Y576500D01*
X340242Y576375D01*
X341283D01*
G01X340242D02*
X339617Y575167D01*
G01X336850D02*
Y577667D01*
X338392Y575875D01*
X336308D01*
G01X335042Y577250D02*
X334792Y577500D01*
X334500Y577625D01*
X334167Y577667D01*
X333750Y577584D01*
X333458Y577375D01*
X333375Y577125D01*
X333417Y576875D01*
X333583Y576667D01*
X334417Y576250D01*
X334792Y575959D01*
X335042Y575542D01*
X335125Y575167D01*
X333375D01*
G01X330650D02*
Y577667D01*
X332192Y575875D01*
X330108D01*
G01X323683Y543666D02*
Y546166D01*
X322642D01*
X322308Y546041D01*
X322100Y545874D01*
X322017Y545541D01*
X322100Y545208D01*
X322350Y544999D01*
X322642Y544874D01*
X323683D01*
G01X322642D02*
X322017Y543666D01*
G01X319833D02*
X319750Y544208D01*
X319625Y544666D01*
X319458Y545083D01*
X319250Y545541D01*
X318917Y546166D01*
X320583D01*
G01X317442Y545749D02*
X317192Y545999D01*
X316900Y546124D01*
X316567Y546166D01*
X316150Y546083D01*
X315858Y545874D01*
X315775Y545624D01*
X315817Y545374D01*
X315983Y545166D01*
X316817Y544749D01*
X317192Y544458D01*
X317442Y544041D01*
X317525Y543666D01*
X315775D01*
G01X313550Y546166D02*
X313883Y546083D01*
X314133Y545874D01*
X314300Y545624D01*
X314425Y545291D01*
X314467Y544916D01*
X314425Y544541D01*
X314300Y544208D01*
X314133Y543958D01*
X313883Y543749D01*
X313550Y543666D01*
X313217Y543749D01*
X312967Y543958D01*
X312800Y544208D01*
X312675Y544541D01*
X312633Y544916D01*
X312675Y545291D01*
X312800Y545624D01*
X312967Y545874D01*
X313217Y546083D01*
X313550Y546166D01*
G01X322700Y554900D02*
Y550900D01*
X315300D01*
G01X319483Y576000D02*
Y578500D01*
X318442D01*
X318108Y578375D01*
X317900Y578208D01*
X317817Y577875D01*
X317900Y577542D01*
X318150Y577333D01*
X318442Y577208D01*
X319483D01*
G01X318442D02*
X317817Y576000D01*
G01X315550D02*
Y578500D01*
X316050Y578000D01*
G01Y576000D02*
X315050D01*
G01X313242Y578083D02*
X312992Y578333D01*
X312700Y578458D01*
X312367Y578500D01*
X311950Y578417D01*
X311658Y578208D01*
X311575Y577958D01*
X311617Y577708D01*
X311783Y577500D01*
X312617Y577083D01*
X312992Y576792D01*
X313242Y576375D01*
X313325Y576000D01*
X311575D01*
G01X309350D02*
X309058Y576042D01*
X308725Y576167D01*
X308517Y576375D01*
X308433Y576667D01*
X308517Y576958D01*
X308767Y577208D01*
X309142Y577333D01*
X309558D01*
X309808Y577417D01*
X310017Y577625D01*
X310100Y577917D01*
X309975Y578208D01*
X309683Y578417D01*
X309350Y578500D01*
X309017Y578417D01*
X308725Y578208D01*
X308600Y577917D01*
X308683Y577625D01*
X308892Y577417D01*
X309142Y577333D01*
X309558D01*
X309933Y577208D01*
X310183Y576958D01*
X310267Y576667D01*
X310183Y576375D01*
X309975Y576167D01*
X309642Y576042D01*
X309350Y576000D01*
G01X318100Y575000D02*
Y571000D01*
X310700D01*
G01X304100Y557517D02*
X306600D01*
Y558558D01*
X306475Y558892D01*
X306308Y559100D01*
X305975Y559183D01*
X305642Y559100D01*
X305433Y558850D01*
X305308Y558558D01*
Y557517D01*
G01Y558558D02*
X304100Y559183D01*
G01Y561450D02*
X306600D01*
X306100Y560950D01*
G01X304100D02*
Y561950D01*
G01X306183Y563758D02*
X306433Y564008D01*
X306558Y564300D01*
X306600Y564633D01*
X306517Y565050D01*
X306308Y565342D01*
X306058Y565425D01*
X305808Y565383D01*
X305600Y565217D01*
X305183Y564383D01*
X304892Y564008D01*
X304475Y563758D01*
X304100Y563675D01*
Y565425D01*
G01Y567567D02*
X304642Y567650D01*
X305100Y567775D01*
X305517Y567942D01*
X305975Y568150D01*
X306600Y568483D01*
Y566817D01*
G01X312700Y557200D02*
X308700D01*
Y564600D01*
G01X347483Y529166D02*
Y531666D01*
X346442D01*
X346108Y531541D01*
X345900Y531374D01*
X345817Y531041D01*
X345900Y530708D01*
X346150Y530499D01*
X346442Y530374D01*
X347483D01*
G01X346442D02*
X345817Y529166D01*
G01X344342Y530208D02*
X344050Y530499D01*
X343800Y530666D01*
X343467Y530749D01*
X343175Y530666D01*
X342967Y530499D01*
X342800Y530249D01*
X342758Y529958D01*
X342800Y529708D01*
X342967Y529458D01*
X343217Y529249D01*
X343508Y529166D01*
X343842Y529249D01*
X344133Y529499D01*
X344300Y529874D01*
X344342Y530291D01*
X344258Y530833D01*
X344133Y531124D01*
X343925Y531416D01*
X343633Y531624D01*
X343342Y531666D01*
X343050Y531583D01*
X342842Y531374D01*
G01X340450Y529166D02*
X340158Y529208D01*
X339825Y529333D01*
X339617Y529541D01*
X339533Y529833D01*
X339617Y530124D01*
X339867Y530374D01*
X340242Y530499D01*
X340658D01*
X340908Y530583D01*
X341117Y530791D01*
X341200Y531083D01*
X341075Y531374D01*
X340783Y531583D01*
X340450Y531666D01*
X340117Y531583D01*
X339825Y531374D01*
X339700Y531083D01*
X339783Y530791D01*
X339992Y530583D01*
X340242Y530499D01*
X340658D01*
X341033Y530374D01*
X341283Y530124D01*
X341367Y529833D01*
X341283Y529541D01*
X341075Y529333D01*
X340742Y529208D01*
X340450Y529166D01*
G01X337350D02*
X337058Y529208D01*
X336725Y529333D01*
X336517Y529541D01*
X336433Y529833D01*
X336517Y530124D01*
X336767Y530374D01*
X337142Y530499D01*
X337558D01*
X337808Y530583D01*
X338017Y530791D01*
X338100Y531083D01*
X337975Y531374D01*
X337683Y531583D01*
X337350Y531666D01*
X337017Y531583D01*
X336725Y531374D01*
X336600Y531083D01*
X336683Y530791D01*
X336892Y530583D01*
X337142Y530499D01*
X337558D01*
X337933Y530374D01*
X338183Y530124D01*
X338267Y529833D01*
X338183Y529541D01*
X337975Y529333D01*
X337642Y529208D01*
X337350Y529166D01*
G01X300283Y534300D02*
Y536800D01*
X299242D01*
X298908Y536675D01*
X298700Y536508D01*
X298617Y536175D01*
X298700Y535842D01*
X298950Y535633D01*
X299242Y535508D01*
X300283D01*
G01X299242D02*
X298617Y534300D01*
G01X296433D02*
X296350Y534842D01*
X296225Y535300D01*
X296058Y535717D01*
X295850Y536175D01*
X295517Y536800D01*
X297183D01*
G01X293250Y534300D02*
X292958Y534342D01*
X292625Y534467D01*
X292417Y534675D01*
X292333Y534967D01*
X292417Y535258D01*
X292667Y535508D01*
X293042Y535633D01*
X293458D01*
X293708Y535717D01*
X293917Y535925D01*
X294000Y536217D01*
X293875Y536508D01*
X293583Y536717D01*
X293250Y536800D01*
X292917Y536717D01*
X292625Y536508D01*
X292500Y536217D01*
X292583Y535925D01*
X292792Y535717D01*
X293042Y535633D01*
X293458D01*
X293833Y535508D01*
X294083Y535258D01*
X294167Y534967D01*
X294083Y534675D01*
X293875Y534467D01*
X293542Y534342D01*
X293250Y534300D01*
G01X291067Y534675D02*
X290817Y534467D01*
X290525Y534342D01*
X290150Y534300D01*
X289775Y534383D01*
X289483Y534550D01*
X289275Y534842D01*
X289233Y535175D01*
X289317Y535508D01*
X289525Y535717D01*
X289817Y535883D01*
X290108Y535925D01*
X290400Y535883D01*
X290775Y535717D01*
X290650Y536800D01*
X289525D01*
G01X298283Y530200D02*
Y532700D01*
X297242D01*
X296908Y532575D01*
X296700Y532408D01*
X296617Y532075D01*
X296700Y531742D01*
X296950Y531533D01*
X297242Y531408D01*
X298283D01*
G01X297242D02*
X296617Y530200D01*
G01X294433D02*
X294350Y530742D01*
X294225Y531200D01*
X294058Y531617D01*
X293850Y532075D01*
X293517Y532700D01*
X295183D01*
G01X292167Y530700D02*
X291917Y530408D01*
X291583Y530242D01*
X291208Y530200D01*
X290875Y530242D01*
X290542Y530450D01*
X290333Y530700D01*
X290292Y530950D01*
X290375Y531242D01*
X290667Y531450D01*
X290958Y531533D01*
X291333D01*
G01X290958D02*
X290708Y531658D01*
X290500Y531867D01*
X290417Y532117D01*
X290500Y532367D01*
X290708Y532575D01*
X291083Y532700D01*
X291458Y532658D01*
X291833Y532492D01*
G01X288858Y530492D02*
X288567Y530283D01*
X288233Y530200D01*
X287900Y530283D01*
X287608Y530533D01*
X287400Y530908D01*
X287317Y531283D01*
Y531742D01*
X287400Y532117D01*
X287608Y532450D01*
X287858Y532617D01*
X288150Y532700D01*
X288483Y532617D01*
X288733Y532450D01*
X288900Y532200D01*
X288983Y531867D01*
X288900Y531575D01*
X288692Y531283D01*
X288442Y531117D01*
X288150Y531075D01*
X287817Y531158D01*
X287567Y531367D01*
X287317Y531742D01*
G01X297450Y540800D02*
Y538300D01*
G01X298408Y540800D02*
X296492D01*
G01X295183Y538300D02*
Y540800D01*
X294183D01*
X293850Y540675D01*
X293600Y540383D01*
X293517Y540050D01*
X293600Y539717D01*
X293808Y539467D01*
X294183Y539342D01*
X295183D01*
G01X292042D02*
X291750Y539633D01*
X291500Y539800D01*
X291167Y539883D01*
X290875Y539800D01*
X290667Y539633D01*
X290500Y539383D01*
X290458Y539092D01*
X290500Y538842D01*
X290667Y538592D01*
X290917Y538383D01*
X291208Y538300D01*
X291542Y538383D01*
X291833Y538633D01*
X292000Y539008D01*
X292042Y539425D01*
X291958Y539967D01*
X291833Y540258D01*
X291625Y540550D01*
X291333Y540758D01*
X291042Y540800D01*
X290750Y540717D01*
X290542Y540508D01*
G01X288858Y538592D02*
X288567Y538383D01*
X288233Y538300D01*
X287900Y538383D01*
X287608Y538633D01*
X287400Y539008D01*
X287317Y539383D01*
Y539842D01*
X287400Y540217D01*
X287608Y540550D01*
X287858Y540717D01*
X288150Y540800D01*
X288483Y540717D01*
X288733Y540550D01*
X288900Y540300D01*
X288983Y539967D01*
X288900Y539675D01*
X288692Y539383D01*
X288442Y539217D01*
X288150Y539175D01*
X287817Y539258D01*
X287567Y539467D01*
X287317Y539842D01*
G01X285985Y557057D02*
Y554557D01*
G01X286943Y557057D02*
X285027D01*
G01X283718Y554557D02*
Y557057D01*
X282718D01*
X282385Y556932D01*
X282135Y556640D01*
X282052Y556307D01*
X282135Y555974D01*
X282343Y555724D01*
X282718Y555599D01*
X283718D01*
G01X279868Y554557D02*
X279785Y555099D01*
X279660Y555557D01*
X279493Y555974D01*
X279285Y556432D01*
X278952Y557057D01*
X280618D01*
G01X277393Y554849D02*
X277102Y554640D01*
X276768Y554557D01*
X276435Y554640D01*
X276143Y554890D01*
X275935Y555265D01*
X275852Y555640D01*
Y556099D01*
X275935Y556474D01*
X276143Y556807D01*
X276393Y556974D01*
X276685Y557057D01*
X277018Y556974D01*
X277268Y556807D01*
X277435Y556557D01*
X277518Y556224D01*
X277435Y555932D01*
X277227Y555640D01*
X276977Y555474D01*
X276685Y555432D01*
X276352Y555515D01*
X276102Y555724D01*
X275852Y556099D01*
G01X297550Y548500D02*
Y546000D01*
G01X298508Y548500D02*
X296592D01*
G01X295283Y546000D02*
Y548500D01*
X294283D01*
X293950Y548375D01*
X293700Y548083D01*
X293617Y547750D01*
X293700Y547417D01*
X293908Y547167D01*
X294283Y547042D01*
X295283D01*
G01X291350Y546000D02*
Y548500D01*
X291850Y548000D01*
G01Y546000D02*
X290850D01*
G01X289167Y546375D02*
X288917Y546167D01*
X288625Y546042D01*
X288250Y546000D01*
X287875Y546083D01*
X287583Y546250D01*
X287375Y546542D01*
X287333Y546875D01*
X287417Y547208D01*
X287625Y547417D01*
X287917Y547583D01*
X288208Y547625D01*
X288500Y547583D01*
X288875Y547417D01*
X288750Y548500D01*
X287625D01*
G01X297550Y544600D02*
Y542100D01*
G01X298508Y544600D02*
X296592D01*
G01X295283Y542100D02*
Y544600D01*
X294283D01*
X293950Y544475D01*
X293700Y544183D01*
X293617Y543850D01*
X293700Y543517D01*
X293908Y543267D01*
X294283Y543142D01*
X295283D01*
G01X291433Y542100D02*
X291350Y542642D01*
X291225Y543100D01*
X291058Y543517D01*
X290850Y543975D01*
X290517Y544600D01*
X292183D01*
G01X289042Y543142D02*
X288750Y543433D01*
X288500Y543600D01*
X288167Y543683D01*
X287875Y543600D01*
X287667Y543433D01*
X287500Y543183D01*
X287458Y542892D01*
X287500Y542642D01*
X287667Y542392D01*
X287917Y542183D01*
X288208Y542100D01*
X288542Y542183D01*
X288833Y542433D01*
X289000Y542808D01*
X289042Y543225D01*
X288958Y543767D01*
X288833Y544058D01*
X288625Y544350D01*
X288333Y544558D01*
X288042Y544600D01*
X287750Y544517D01*
X287542Y544308D01*
G01X284700Y599017D02*
X287200D01*
Y600058D01*
X287075Y600392D01*
X286908Y600600D01*
X286575Y600683D01*
X286242Y600600D01*
X286033Y600350D01*
X285908Y600058D01*
Y599017D01*
G01Y600058D02*
X284700Y600683D01*
G01Y602950D02*
X287200D01*
X286700Y602450D01*
G01X284700D02*
Y603450D01*
G01X284992Y605342D02*
X284783Y605633D01*
X284700Y605967D01*
X284783Y606300D01*
X285033Y606592D01*
X285408Y606800D01*
X285783Y606883D01*
X286242D01*
X286617Y606800D01*
X286950Y606592D01*
X287117Y606342D01*
X287200Y606050D01*
X287117Y605717D01*
X286950Y605467D01*
X286700Y605300D01*
X286367Y605217D01*
X286075Y605300D01*
X285783Y605508D01*
X285617Y605758D01*
X285575Y606050D01*
X285658Y606383D01*
X285867Y606633D01*
X286242Y606883D01*
G01X285075Y608233D02*
X284867Y608483D01*
X284742Y608775D01*
X284700Y609150D01*
X284783Y609525D01*
X284950Y609817D01*
X285242Y610025D01*
X285575Y610067D01*
X285908Y609983D01*
X286117Y609775D01*
X286283Y609483D01*
X286325Y609192D01*
X286283Y608900D01*
X286117Y608525D01*
X287200Y608650D01*
Y609775D01*
G01X295483Y615000D02*
Y617500D01*
X294442D01*
X294108Y617375D01*
X293900Y617208D01*
X293817Y616875D01*
X293900Y616542D01*
X294150Y616333D01*
X294442Y616208D01*
X295483D01*
G01X294442D02*
X293817Y615000D01*
G01X291550D02*
Y617500D01*
X292050Y617000D01*
G01Y615000D02*
X291050D01*
G01X289158Y615292D02*
X288867Y615083D01*
X288533Y615000D01*
X288200Y615083D01*
X287908Y615333D01*
X287700Y615708D01*
X287617Y616083D01*
Y616542D01*
X287700Y616917D01*
X287908Y617250D01*
X288158Y617417D01*
X288450Y617500D01*
X288783Y617417D01*
X289033Y617250D01*
X289200Y617000D01*
X289283Y616667D01*
X289200Y616375D01*
X288992Y616083D01*
X288742Y615917D01*
X288450Y615875D01*
X288117Y615958D01*
X287867Y616167D01*
X287617Y616542D01*
G01X286142Y616042D02*
X285850Y616333D01*
X285600Y616500D01*
X285267Y616583D01*
X284975Y616500D01*
X284767Y616333D01*
X284600Y616083D01*
X284558Y615792D01*
X284600Y615542D01*
X284767Y615292D01*
X285017Y615083D01*
X285308Y615000D01*
X285642Y615083D01*
X285933Y615333D01*
X286100Y615708D01*
X286142Y616125D01*
X286058Y616667D01*
X285933Y616958D01*
X285725Y617250D01*
X285433Y617458D01*
X285142Y617500D01*
X284850Y617417D01*
X284642Y617208D01*
G01X294483Y645000D02*
Y647500D01*
X293442D01*
X293108Y647375D01*
X292900Y647208D01*
X292817Y646875D01*
X292900Y646542D01*
X293150Y646333D01*
X293442Y646208D01*
X294483D01*
G01X293442D02*
X292817Y645000D01*
G01X291467Y645500D02*
X291217Y645208D01*
X290883Y645042D01*
X290508Y645000D01*
X290175Y645042D01*
X289842Y645250D01*
X289633Y645500D01*
X289592Y645750D01*
X289675Y646042D01*
X289967Y646250D01*
X290258Y646333D01*
X290633D01*
G01X290258D02*
X290008Y646458D01*
X289800Y646667D01*
X289717Y646917D01*
X289800Y647167D01*
X290008Y647375D01*
X290383Y647500D01*
X290758Y647458D01*
X291133Y647292D01*
G01X287450Y647500D02*
X287783Y647417D01*
X288033Y647208D01*
X288200Y646958D01*
X288325Y646625D01*
X288367Y646250D01*
X288325Y645875D01*
X288200Y645542D01*
X288033Y645292D01*
X287783Y645083D01*
X287450Y645000D01*
X287117Y645083D01*
X286867Y645292D01*
X286700Y645542D01*
X286575Y645875D01*
X286533Y646250D01*
X286575Y646625D01*
X286700Y646958D01*
X286867Y647208D01*
X287117Y647417D01*
X287450Y647500D01*
G01X285267Y645500D02*
X285017Y645208D01*
X284683Y645042D01*
X284308Y645000D01*
X283975Y645042D01*
X283642Y645250D01*
X283433Y645500D01*
X283392Y645750D01*
X283475Y646042D01*
X283767Y646250D01*
X284058Y646333D01*
X284433D01*
G01X284058D02*
X283808Y646458D01*
X283600Y646667D01*
X283517Y646917D01*
X283600Y647167D01*
X283808Y647375D01*
X284183Y647500D01*
X284558Y647458D01*
X284933Y647292D01*
G01X294983Y619000D02*
Y621500D01*
X293942D01*
X293608Y621375D01*
X293400Y621208D01*
X293317Y620875D01*
X293400Y620542D01*
X293650Y620333D01*
X293942Y620208D01*
X294983D01*
G01X293942D02*
X293317Y619000D01*
G01X291842Y621083D02*
X291592Y621333D01*
X291300Y621458D01*
X290967Y621500D01*
X290550Y621417D01*
X290258Y621208D01*
X290175Y620958D01*
X290217Y620708D01*
X290383Y620500D01*
X291217Y620083D01*
X291592Y619792D01*
X291842Y619375D01*
X291925Y619000D01*
X290175D01*
G01X287950Y621500D02*
X288283Y621417D01*
X288533Y621208D01*
X288700Y620958D01*
X288825Y620625D01*
X288867Y620250D01*
X288825Y619875D01*
X288700Y619542D01*
X288533Y619292D01*
X288283Y619083D01*
X287950Y619000D01*
X287617Y619083D01*
X287367Y619292D01*
X287200Y619542D01*
X287075Y619875D01*
X287033Y620250D01*
X287075Y620625D01*
X287200Y620958D01*
X287367Y621208D01*
X287617Y621417D01*
X287950Y621500D01*
G01X285642Y621083D02*
X285392Y621333D01*
X285100Y621458D01*
X284767Y621500D01*
X284350Y621417D01*
X284058Y621208D01*
X283975Y620958D01*
X284017Y620708D01*
X284183Y620500D01*
X285017Y620083D01*
X285392Y619792D01*
X285642Y619375D01*
X285725Y619000D01*
X283975D01*
G01X292983Y629100D02*
Y631600D01*
X291942D01*
X291608Y631475D01*
X291400Y631308D01*
X291317Y630975D01*
X291400Y630642D01*
X291650Y630433D01*
X291942Y630308D01*
X292983D01*
G01X291942D02*
X291317Y629100D01*
G01X289842Y631183D02*
X289592Y631433D01*
X289300Y631558D01*
X288967Y631600D01*
X288550Y631517D01*
X288258Y631308D01*
X288175Y631058D01*
X288217Y630808D01*
X288383Y630600D01*
X289217Y630183D01*
X289592Y629892D01*
X289842Y629475D01*
X289925Y629100D01*
X288175D01*
G01X285950Y631600D02*
X286283Y631517D01*
X286533Y631308D01*
X286700Y631058D01*
X286825Y630725D01*
X286867Y630350D01*
X286825Y629975D01*
X286700Y629642D01*
X286533Y629392D01*
X286283Y629183D01*
X285950Y629100D01*
X285617Y629183D01*
X285367Y629392D01*
X285200Y629642D01*
X285075Y629975D01*
X285033Y630350D01*
X285075Y630725D01*
X285200Y631058D01*
X285367Y631308D01*
X285617Y631517D01*
X285950Y631600D01*
G01X282850Y629100D02*
Y631600D01*
X283350Y631100D01*
G01Y629100D02*
X282350D01*
G01X293483Y633000D02*
Y635500D01*
X292442D01*
X292108Y635375D01*
X291900Y635208D01*
X291817Y634875D01*
X291900Y634542D01*
X292150Y634333D01*
X292442Y634208D01*
X293483D01*
G01X292442D02*
X291817Y633000D01*
G01X290467Y633500D02*
X290217Y633208D01*
X289883Y633042D01*
X289508Y633000D01*
X289175Y633042D01*
X288842Y633250D01*
X288633Y633500D01*
X288592Y633750D01*
X288675Y634042D01*
X288967Y634250D01*
X289258Y634333D01*
X289633D01*
G01X289258D02*
X289008Y634458D01*
X288800Y634667D01*
X288717Y634917D01*
X288800Y635167D01*
X289008Y635375D01*
X289383Y635500D01*
X289758Y635458D01*
X290133Y635292D01*
G01X286450Y633000D02*
X286158Y633042D01*
X285825Y633167D01*
X285617Y633375D01*
X285533Y633667D01*
X285617Y633958D01*
X285867Y634208D01*
X286242Y634333D01*
X286658D01*
X286908Y634417D01*
X287117Y634625D01*
X287200Y634917D01*
X287075Y635208D01*
X286783Y635417D01*
X286450Y635500D01*
X286117Y635417D01*
X285825Y635208D01*
X285700Y634917D01*
X285783Y634625D01*
X285992Y634417D01*
X286242Y634333D01*
X286658D01*
X287033Y634208D01*
X287283Y633958D01*
X287367Y633667D01*
X287283Y633375D01*
X287075Y633167D01*
X286742Y633042D01*
X286450Y633000D01*
G01X284058Y633292D02*
X283767Y633083D01*
X283433Y633000D01*
X283100Y633083D01*
X282808Y633333D01*
X282600Y633708D01*
X282517Y634083D01*
Y634542D01*
X282600Y634917D01*
X282808Y635250D01*
X283058Y635417D01*
X283350Y635500D01*
X283683Y635417D01*
X283933Y635250D01*
X284100Y635000D01*
X284183Y634667D01*
X284100Y634375D01*
X283892Y634083D01*
X283642Y633917D01*
X283350Y633875D01*
X283017Y633958D01*
X282767Y634167D01*
X282517Y634542D01*
G01X308383Y647817D02*
Y650317D01*
X307342D01*
X307008Y650192D01*
X306800Y650025D01*
X306717Y649692D01*
X306800Y649359D01*
X307050Y649150D01*
X307342Y649025D01*
X308383D01*
G01X307342D02*
X306717Y647817D01*
G01X305242Y648859D02*
X304950Y649150D01*
X304700Y649317D01*
X304367Y649400D01*
X304075Y649317D01*
X303867Y649150D01*
X303700Y648900D01*
X303658Y648609D01*
X303700Y648359D01*
X303867Y648109D01*
X304117Y647900D01*
X304408Y647817D01*
X304742Y647900D01*
X305033Y648150D01*
X305200Y648525D01*
X305242Y648942D01*
X305158Y649484D01*
X305033Y649775D01*
X304825Y650067D01*
X304533Y650275D01*
X304242Y650317D01*
X303950Y650234D01*
X303742Y650025D01*
G01X302267Y648192D02*
X302017Y647984D01*
X301725Y647859D01*
X301350Y647817D01*
X300975Y647900D01*
X300683Y648067D01*
X300475Y648359D01*
X300433Y648692D01*
X300517Y649025D01*
X300725Y649234D01*
X301017Y649400D01*
X301308Y649442D01*
X301600Y649400D01*
X301975Y649234D01*
X301850Y650317D01*
X300725D01*
G01X298250Y647817D02*
Y650317D01*
X298750Y649817D01*
G01Y647817D02*
X297750D01*
G01X314350Y660050D02*
Y656050D01*
X306950D01*
G01X322133Y647817D02*
Y650317D01*
X321092D01*
X320758Y650192D01*
X320550Y650025D01*
X320467Y649692D01*
X320550Y649359D01*
X320800Y649150D01*
X321092Y649025D01*
X322133D01*
G01X321092D02*
X320467Y647817D01*
G01X317700D02*
Y650317D01*
X319242Y648525D01*
X317158D01*
G01X316017Y648192D02*
X315767Y647984D01*
X315475Y647859D01*
X315100Y647817D01*
X314725Y647900D01*
X314433Y648067D01*
X314225Y648359D01*
X314183Y648692D01*
X314267Y649025D01*
X314475Y649234D01*
X314767Y649400D01*
X315058Y649442D01*
X315350Y649400D01*
X315725Y649234D01*
X315600Y650317D01*
X314475D01*
G01X312792Y649900D02*
X312542Y650150D01*
X312250Y650275D01*
X311917Y650317D01*
X311500Y650234D01*
X311208Y650025D01*
X311125Y649775D01*
X311167Y649525D01*
X311333Y649317D01*
X312167Y648900D01*
X312542Y648609D01*
X312792Y648192D01*
X312875Y647817D01*
X311125D01*
G01X321900Y660100D02*
Y656100D01*
X314500D01*
G01X317383Y690008D02*
X317633Y690133D01*
X317925Y690216D01*
X318258D01*
X318633Y690091D01*
X318925Y689883D01*
X319133Y689633D01*
X319300Y689216D01*
X319342Y688841D01*
X319258Y688466D01*
X319133Y688216D01*
X318883Y687966D01*
X318592Y687799D01*
X318300Y687716D01*
X318008D01*
X317717Y687799D01*
X317467Y687924D01*
X317258Y688091D01*
G01X315200Y687716D02*
Y690216D01*
X315700Y689716D01*
G01Y687716D02*
X314700D01*
G01X312892Y689799D02*
X312642Y690049D01*
X312350Y690174D01*
X312017Y690216D01*
X311600Y690133D01*
X311308Y689924D01*
X311225Y689674D01*
X311267Y689424D01*
X311433Y689216D01*
X312267Y688799D01*
X312642Y688508D01*
X312892Y688091D01*
X312975Y687716D01*
X311225D01*
G01X309917Y688091D02*
X309667Y687883D01*
X309375Y687758D01*
X309000Y687716D01*
X308625Y687799D01*
X308333Y687966D01*
X308125Y688258D01*
X308083Y688591D01*
X308167Y688924D01*
X308375Y689133D01*
X308667Y689299D01*
X308958Y689341D01*
X309250Y689299D01*
X309625Y689133D01*
X309500Y690216D01*
X308375D01*
G01X332583Y685800D02*
Y688300D01*
X331542D01*
X331208Y688175D01*
X331000Y688008D01*
X330917Y687675D01*
X331000Y687342D01*
X331250Y687133D01*
X331542Y687008D01*
X332583D01*
G01X331542D02*
X330917Y685800D01*
G01X328150D02*
Y688300D01*
X329692Y686508D01*
X327608D01*
G01X325550Y685800D02*
Y688300D01*
X326050Y687800D01*
G01Y685800D02*
X325050D01*
G01X322450D02*
X322158Y685842D01*
X321825Y685967D01*
X321617Y686175D01*
X321533Y686467D01*
X321617Y686758D01*
X321867Y687008D01*
X322242Y687133D01*
X322658D01*
X322908Y687217D01*
X323117Y687425D01*
X323200Y687717D01*
X323075Y688008D01*
X322783Y688217D01*
X322450Y688300D01*
X322117Y688217D01*
X321825Y688008D01*
X321700Y687717D01*
X321783Y687425D01*
X321992Y687217D01*
X322242Y687133D01*
X322658D01*
X323033Y687008D01*
X323283Y686758D01*
X323367Y686467D01*
X323283Y686175D01*
X323075Y685967D01*
X322742Y685842D01*
X322450Y685800D01*
G01X308917Y674517D02*
X311417D01*
Y675558D01*
X311292Y675892D01*
X311125Y676100D01*
X310792Y676183D01*
X310459Y676100D01*
X310250Y675850D01*
X310125Y675558D01*
Y674517D01*
G01Y675558D02*
X308917Y676183D01*
G01Y678950D02*
X311417D01*
X309625Y677408D01*
Y679492D01*
G01X309292Y680633D02*
X309084Y680883D01*
X308959Y681175D01*
X308917Y681550D01*
X309000Y681925D01*
X309167Y682217D01*
X309459Y682425D01*
X309792Y682467D01*
X310125Y682383D01*
X310334Y682175D01*
X310500Y681883D01*
X310542Y681592D01*
X310500Y681300D01*
X310334Y680925D01*
X311417Y681050D01*
Y682175D01*
G01X308917Y684650D02*
X311417D01*
X310917Y684150D01*
G01X308917D02*
Y685150D01*
G01X317290Y676470D02*
X313290D01*
Y683870D01*
G01X334700Y709967D02*
X337200D01*
Y711008D01*
X337075Y711342D01*
X336908Y711550D01*
X336575Y711633D01*
X336242Y711550D01*
X336033Y711300D01*
X335908Y711008D01*
Y709967D01*
G01Y711008D02*
X334700Y711633D01*
G01X334992Y713192D02*
X334783Y713483D01*
X334700Y713817D01*
X334783Y714150D01*
X335033Y714442D01*
X335408Y714650D01*
X335783Y714733D01*
X336242D01*
X336617Y714650D01*
X336950Y714442D01*
X337117Y714192D01*
X337200Y713900D01*
X337117Y713567D01*
X336950Y713317D01*
X336700Y713150D01*
X336367Y713067D01*
X336075Y713150D01*
X335783Y713358D01*
X335617Y713608D01*
X335575Y713900D01*
X335658Y714233D01*
X335867Y714483D01*
X336242Y714733D01*
G01X335742Y716208D02*
X336033Y716500D01*
X336200Y716750D01*
X336283Y717083D01*
X336200Y717375D01*
X336033Y717583D01*
X335783Y717750D01*
X335492Y717792D01*
X335242Y717750D01*
X334992Y717583D01*
X334783Y717333D01*
X334700Y717042D01*
X334783Y716708D01*
X335033Y716417D01*
X335408Y716250D01*
X335825Y716208D01*
X336367Y716292D01*
X336658Y716417D01*
X336950Y716625D01*
X337158Y716917D01*
X337200Y717208D01*
X337117Y717500D01*
X336908Y717708D01*
G01X333962Y707596D02*
X337962D01*
Y700196D01*
G01X328700Y691167D02*
X331200D01*
Y692208D01*
X331075Y692542D01*
X330908Y692750D01*
X330575Y692833D01*
X330242Y692750D01*
X330033Y692500D01*
X329908Y692208D01*
Y691167D01*
G01Y692208D02*
X328700Y692833D01*
G01X328992Y694392D02*
X328783Y694683D01*
X328700Y695017D01*
X328783Y695350D01*
X329033Y695642D01*
X329408Y695850D01*
X329783Y695933D01*
X330242D01*
X330617Y695850D01*
X330950Y695642D01*
X331117Y695392D01*
X331200Y695100D01*
X331117Y694767D01*
X330950Y694517D01*
X330700Y694350D01*
X330367Y694267D01*
X330075Y694350D01*
X329783Y694558D01*
X329617Y694808D01*
X329575Y695100D01*
X329658Y695433D01*
X329867Y695683D01*
X330242Y695933D01*
G01X329200Y697283D02*
X328908Y697533D01*
X328742Y697867D01*
X328700Y698242D01*
X328742Y698575D01*
X328950Y698908D01*
X329200Y699117D01*
X329450Y699158D01*
X329742Y699075D01*
X329950Y698783D01*
X330033Y698492D01*
Y698117D01*
G01Y698492D02*
X330158Y698742D01*
X330367Y698950D01*
X330617Y699033D01*
X330867Y698950D01*
X331075Y698742D01*
X331200Y698367D01*
X331158Y697992D01*
X330992Y697617D01*
G01X325433Y695400D02*
Y697900D01*
X324392D01*
X324058Y697775D01*
X323850Y697608D01*
X323767Y697275D01*
X323850Y696942D01*
X324100Y696733D01*
X324392Y696608D01*
X325433D01*
G01X324392D02*
X323767Y695400D01*
G01X322208Y695692D02*
X321917Y695483D01*
X321583Y695400D01*
X321250Y695483D01*
X320958Y695733D01*
X320750Y696108D01*
X320667Y696483D01*
Y696942D01*
X320750Y697317D01*
X320958Y697650D01*
X321208Y697817D01*
X321500Y697900D01*
X321833Y697817D01*
X322083Y697650D01*
X322250Y697400D01*
X322333Y697067D01*
X322250Y696775D01*
X322042Y696483D01*
X321792Y696317D01*
X321500Y696275D01*
X321167Y696358D01*
X320917Y696567D01*
X320667Y696942D01*
G01X319192Y697483D02*
X318942Y697733D01*
X318650Y697858D01*
X318317Y697900D01*
X317900Y697817D01*
X317608Y697608D01*
X317525Y697358D01*
X317567Y697108D01*
X317733Y696900D01*
X318567Y696483D01*
X318942Y696192D01*
X319192Y695775D01*
X319275Y695400D01*
X317525D01*
G01X343600Y698100D02*
Y694100D01*
X336200D01*
G01X369092Y30394D02*
Y32894D01*
X368051D01*
X367717Y32769D01*
X367509Y32602D01*
X367426Y32269D01*
X367509Y31936D01*
X367759Y31727D01*
X368051Y31602D01*
X369092D01*
G01X368051D02*
X367426Y30394D01*
G01X366076Y30894D02*
X365826Y30602D01*
X365492Y30436D01*
X365117Y30394D01*
X364784Y30436D01*
X364451Y30644D01*
X364242Y30894D01*
X364201Y31144D01*
X364284Y31436D01*
X364576Y31644D01*
X364867Y31727D01*
X365242D01*
G01X364867D02*
X364617Y31852D01*
X364409Y32061D01*
X364326Y32311D01*
X364409Y32561D01*
X364617Y32769D01*
X364992Y32894D01*
X365367Y32852D01*
X365742Y32686D01*
G01X362142Y30394D02*
X362059Y30936D01*
X361934Y31394D01*
X361767Y31811D01*
X361559Y32269D01*
X361226Y32894D01*
X362892D01*
G01X371800Y29000D02*
Y33000D01*
X379200D01*
G01X362271Y26994D02*
X362521Y27119D01*
X362813Y27202D01*
X363146D01*
X363521Y27077D01*
X363813Y26869D01*
X364021Y26619D01*
X364188Y26202D01*
X364230Y25827D01*
X364146Y25452D01*
X364021Y25202D01*
X363771Y24952D01*
X363480Y24785D01*
X363188Y24702D01*
X362896D01*
X362605Y24785D01*
X362355Y24910D01*
X362146Y25077D01*
G01X361005D02*
X360755Y24869D01*
X360463Y24744D01*
X360088Y24702D01*
X359713Y24785D01*
X359421Y24952D01*
X359213Y25244D01*
X359171Y25577D01*
X359255Y25910D01*
X359463Y26119D01*
X359755Y26285D01*
X360046Y26327D01*
X360338Y26285D01*
X360713Y26119D01*
X360588Y27202D01*
X359463D01*
G01X357780Y26785D02*
X357530Y27035D01*
X357238Y27160D01*
X356905Y27202D01*
X356488Y27119D01*
X356196Y26910D01*
X356113Y26660D01*
X356155Y26410D01*
X356321Y26202D01*
X357155Y25785D01*
X357530Y25494D01*
X357780Y25077D01*
X357863Y24702D01*
X356113D01*
G01X354805Y25077D02*
X354555Y24869D01*
X354263Y24744D01*
X353888Y24702D01*
X353513Y24785D01*
X353221Y24952D01*
X353013Y25244D01*
X352971Y25577D01*
X353055Y25910D01*
X353263Y26119D01*
X353555Y26285D01*
X353846Y26327D01*
X354138Y26285D01*
X354513Y26119D01*
X354388Y27202D01*
X353263D01*
G01X378300Y20500D02*
X383800D01*
Y28500D01*
X378200D01*
G01X366200Y20500D02*
X371700D01*
G01X366200D02*
Y28500D01*
X371700D01*
G01X352548Y375991D02*
X355048D01*
Y377032D01*
X354923Y377366D01*
X354756Y377574D01*
X354423Y377657D01*
X354090Y377574D01*
X353881Y377324D01*
X353756Y377032D01*
Y375991D01*
G01Y377032D02*
X352548Y377657D01*
G01Y379841D02*
X353090Y379924D01*
X353548Y380049D01*
X353965Y380216D01*
X354423Y380424D01*
X355048Y380757D01*
Y379091D01*
G01X354631Y382232D02*
X354881Y382482D01*
X355006Y382774D01*
X355048Y383107D01*
X354965Y383524D01*
X354756Y383816D01*
X354506Y383899D01*
X354256Y383857D01*
X354048Y383691D01*
X353631Y382857D01*
X353340Y382482D01*
X352923Y382232D01*
X352548Y382149D01*
Y383899D01*
G01Y386124D02*
X352590Y386416D01*
X352715Y386749D01*
X352923Y386957D01*
X353215Y387041D01*
X353506Y386957D01*
X353756Y386707D01*
X353881Y386332D01*
Y385916D01*
X353965Y385666D01*
X354173Y385457D01*
X354465Y385374D01*
X354756Y385499D01*
X354965Y385791D01*
X355048Y386124D01*
X354965Y386457D01*
X354756Y386749D01*
X354465Y386874D01*
X354173Y386791D01*
X353965Y386582D01*
X353881Y386332D01*
Y385916D01*
X353756Y385541D01*
X353506Y385291D01*
X353215Y385207D01*
X352923Y385291D01*
X352715Y385499D01*
X352590Y385832D01*
X352548Y386124D01*
G01X351182Y375874D02*
X347182D01*
Y383274D01*
G01X342782Y397243D02*
Y383243D01*
G01X363592Y495867D02*
X363717Y495617D01*
X363800Y495325D01*
Y494992D01*
X363675Y494617D01*
X363467Y494325D01*
X363217Y494117D01*
X362800Y493950D01*
X362425Y493908D01*
X362050Y493992D01*
X361800Y494117D01*
X361550Y494367D01*
X361383Y494658D01*
X361300Y494950D01*
Y495242D01*
X361383Y495533D01*
X361508Y495783D01*
X361675Y495992D01*
G01X361300Y498050D02*
X363800D01*
X363300Y497550D01*
G01X361300D02*
Y498550D01*
G01X363383Y500358D02*
X363633Y500608D01*
X363758Y500900D01*
X363800Y501233D01*
X363717Y501650D01*
X363508Y501942D01*
X363258Y502025D01*
X363008Y501983D01*
X362800Y501817D01*
X362383Y500983D01*
X362092Y500608D01*
X361675Y500358D01*
X361300Y500275D01*
Y502025D01*
G01X362342Y503458D02*
X362633Y503750D01*
X362800Y504000D01*
X362883Y504333D01*
X362800Y504625D01*
X362633Y504833D01*
X362383Y505000D01*
X362092Y505042D01*
X361842Y505000D01*
X361592Y504833D01*
X361383Y504583D01*
X361300Y504292D01*
X361383Y503958D01*
X361633Y503667D01*
X362008Y503500D01*
X362425Y503458D01*
X362967Y503542D01*
X363258Y503667D01*
X363550Y503875D01*
X363758Y504167D01*
X363800Y504458D01*
X363717Y504750D01*
X363508Y504958D01*
G01X350233Y523958D02*
X350483Y524083D01*
X350775Y524166D01*
X351108D01*
X351483Y524041D01*
X351775Y523833D01*
X351983Y523583D01*
X352150Y523166D01*
X352192Y522791D01*
X352108Y522416D01*
X351983Y522166D01*
X351733Y521916D01*
X351442Y521749D01*
X351150Y521666D01*
X350858D01*
X350567Y521749D01*
X350317Y521874D01*
X350108Y522041D01*
G01X348967D02*
X348717Y521833D01*
X348425Y521708D01*
X348050Y521666D01*
X347675Y521749D01*
X347383Y521916D01*
X347175Y522208D01*
X347133Y522541D01*
X347217Y522874D01*
X347425Y523083D01*
X347717Y523249D01*
X348008Y523291D01*
X348300Y523249D01*
X348675Y523083D01*
X348550Y524166D01*
X347425D01*
G01X344950D02*
X345283Y524083D01*
X345533Y523874D01*
X345700Y523624D01*
X345825Y523291D01*
X345867Y522916D01*
X345825Y522541D01*
X345700Y522208D01*
X345533Y521958D01*
X345283Y521749D01*
X344950Y521666D01*
X344617Y521749D01*
X344367Y521958D01*
X344200Y522208D01*
X344075Y522541D01*
X344033Y522916D01*
X344075Y523291D01*
X344200Y523624D01*
X344367Y523874D01*
X344617Y524083D01*
X344950Y524166D01*
G01X342767Y522166D02*
X342517Y521874D01*
X342183Y521708D01*
X341808Y521666D01*
X341475Y521708D01*
X341142Y521916D01*
X340933Y522166D01*
X340892Y522416D01*
X340975Y522708D01*
X341267Y522916D01*
X341558Y522999D01*
X341933D01*
G01X341558D02*
X341308Y523124D01*
X341100Y523333D01*
X341017Y523583D01*
X341100Y523833D01*
X341308Y524041D01*
X341683Y524166D01*
X342058Y524124D01*
X342433Y523958D01*
G01X353900Y526900D02*
X349900D01*
Y534300D01*
G01X386067Y521667D02*
Y519875D01*
X385900Y519500D01*
X385567Y519250D01*
X385150Y519167D01*
X384733Y519250D01*
X384400Y519500D01*
X384233Y519875D01*
Y521667D01*
G01X382050Y519167D02*
Y521667D01*
X382550Y521167D01*
G01Y519167D02*
X381550D01*
G01X378950Y521667D02*
X379283Y521584D01*
X379533Y521375D01*
X379700Y521125D01*
X379825Y520792D01*
X379867Y520417D01*
X379825Y520042D01*
X379700Y519709D01*
X379533Y519459D01*
X379283Y519250D01*
X378950Y519167D01*
X378617Y519250D01*
X378367Y519459D01*
X378200Y519709D01*
X378075Y520042D01*
X378033Y520417D01*
X378075Y520792D01*
X378200Y521125D01*
X378367Y521375D01*
X378617Y521584D01*
X378950Y521667D01*
G01X375850D02*
X376183Y521584D01*
X376433Y521375D01*
X376600Y521125D01*
X376725Y520792D01*
X376767Y520417D01*
X376725Y520042D01*
X376600Y519709D01*
X376433Y519459D01*
X376183Y519250D01*
X375850Y519167D01*
X375517Y519250D01*
X375267Y519459D01*
X375100Y519709D01*
X374975Y520042D01*
X374933Y520417D01*
X374975Y520792D01*
X375100Y521125D01*
X375267Y521375D01*
X375517Y521584D01*
X375850Y521667D01*
G01X359400Y514900D02*
X372800D01*
G01X359400Y524900D02*
Y514900D01*
G01X372800Y524900D02*
X359400D01*
G01X372800Y514900D02*
Y524900D01*
G01X358492Y576817D02*
X358617Y576567D01*
X358700Y576275D01*
Y575942D01*
X358575Y575567D01*
X358367Y575275D01*
X358117Y575067D01*
X357700Y574900D01*
X357325Y574858D01*
X356950Y574942D01*
X356700Y575067D01*
X356450Y575317D01*
X356283Y575608D01*
X356200Y575900D01*
Y576192D01*
X356283Y576483D01*
X356408Y576733D01*
X356575Y576942D01*
G01X356200Y579000D02*
X358700D01*
X358200Y578500D01*
G01X356200D02*
Y579500D01*
G01Y582600D02*
X358700D01*
X356908Y581058D01*
Y583142D01*
G01X384192Y573067D02*
X384317Y572817D01*
X384400Y572525D01*
Y572192D01*
X384275Y571817D01*
X384067Y571525D01*
X383817Y571317D01*
X383400Y571150D01*
X383025Y571108D01*
X382650Y571192D01*
X382400Y571317D01*
X382150Y571567D01*
X381983Y571858D01*
X381900Y572150D01*
Y572442D01*
X381983Y572733D01*
X382108Y572983D01*
X382275Y573192D01*
G01X381900Y575250D02*
X384400D01*
X383900Y574750D01*
G01X381900D02*
Y575750D01*
G01X383983Y577558D02*
X384233Y577808D01*
X384358Y578100D01*
X384400Y578433D01*
X384317Y578850D01*
X384108Y579142D01*
X383858Y579225D01*
X383608Y579183D01*
X383400Y579017D01*
X382983Y578183D01*
X382692Y577808D01*
X382275Y577558D01*
X381900Y577475D01*
Y579225D01*
G01Y581367D02*
X382442Y581450D01*
X382900Y581575D01*
X383317Y581742D01*
X383775Y581950D01*
X384400Y582283D01*
Y580617D01*
G01X351044Y542671D02*
X351294Y542796D01*
X351586Y542879D01*
X351919D01*
X352294Y542754D01*
X352586Y542546D01*
X352794Y542296D01*
X352961Y541879D01*
X353003Y541504D01*
X352919Y541129D01*
X352794Y540879D01*
X352544Y540629D01*
X352253Y540462D01*
X351961Y540379D01*
X351669D01*
X351378Y540462D01*
X351128Y540587D01*
X350919Y540754D01*
G01X349778D02*
X349528Y540546D01*
X349236Y540421D01*
X348861Y540379D01*
X348486Y540462D01*
X348194Y540629D01*
X347986Y540921D01*
X347944Y541254D01*
X348028Y541587D01*
X348236Y541796D01*
X348528Y541962D01*
X348819Y542004D01*
X349111Y541962D01*
X349486Y541796D01*
X349361Y542879D01*
X348236D01*
G01X345761D02*
X346094Y542796D01*
X346344Y542587D01*
X346511Y542337D01*
X346636Y542004D01*
X346678Y541629D01*
X346636Y541254D01*
X346511Y540921D01*
X346344Y540671D01*
X346094Y540462D01*
X345761Y540379D01*
X345428Y540462D01*
X345178Y540671D01*
X345011Y540921D01*
X344886Y541254D01*
X344844Y541629D01*
X344886Y542004D01*
X345011Y542337D01*
X345178Y542587D01*
X345428Y542796D01*
X345761Y542879D01*
G01X342161Y540379D02*
Y542879D01*
X343703Y541087D01*
X341619D01*
G01X356933Y555492D02*
X357183Y555617D01*
X357475Y555700D01*
X357808D01*
X358183Y555575D01*
X358475Y555367D01*
X358683Y555117D01*
X358850Y554700D01*
X358892Y554325D01*
X358808Y553950D01*
X358683Y553700D01*
X358433Y553450D01*
X358142Y553283D01*
X357850Y553200D01*
X357558D01*
X357267Y553283D01*
X357017Y553408D01*
X356808Y553575D01*
G01X354750Y553200D02*
Y555700D01*
X355250Y555200D01*
G01Y553200D02*
X354250D01*
G01X352567Y553700D02*
X352317Y553408D01*
X351983Y553242D01*
X351608Y553200D01*
X351275Y553242D01*
X350942Y553450D01*
X350733Y553700D01*
X350692Y553950D01*
X350775Y554242D01*
X351067Y554450D01*
X351358Y554533D01*
X351733D01*
G01X351358D02*
X351108Y554658D01*
X350900Y554867D01*
X350817Y555117D01*
X350900Y555367D01*
X351108Y555575D01*
X351483Y555700D01*
X351858Y555658D01*
X352233Y555492D01*
G01X348633Y553200D02*
X348550Y553742D01*
X348425Y554200D01*
X348258Y554617D01*
X348050Y555075D01*
X347717Y555700D01*
X349383D01*
G01X351500Y575067D02*
X354000D01*
Y576108D01*
X353875Y576442D01*
X353708Y576650D01*
X353375Y576733D01*
X353042Y576650D01*
X352833Y576400D01*
X352708Y576108D01*
Y575067D01*
G01Y576108D02*
X351500Y576733D01*
G01Y579500D02*
X354000D01*
X352208Y577958D01*
Y580042D01*
G01X354000Y582100D02*
X353917Y581767D01*
X353708Y581517D01*
X353458Y581350D01*
X353125Y581225D01*
X352750Y581183D01*
X352375Y581225D01*
X352042Y581350D01*
X351792Y581517D01*
X351583Y581767D01*
X351500Y582100D01*
X351583Y582433D01*
X351792Y582683D01*
X352042Y582850D01*
X352375Y582975D01*
X352750Y583017D01*
X353125Y582975D01*
X353458Y582850D01*
X353708Y582683D01*
X353917Y582433D01*
X354000Y582100D01*
G01X350480Y591564D02*
X354480D01*
Y584164D01*
G01X383267Y585567D02*
X385767D01*
Y586608D01*
X385642Y586942D01*
X385475Y587150D01*
X385142Y587233D01*
X384809Y587150D01*
X384600Y586900D01*
X384475Y586608D01*
Y585567D01*
G01Y586608D02*
X383267Y587233D01*
G01Y590000D02*
X385767D01*
X383975Y588458D01*
Y590542D01*
G01X385350Y591808D02*
X385600Y592058D01*
X385725Y592350D01*
X385767Y592683D01*
X385684Y593100D01*
X385475Y593392D01*
X385225Y593475D01*
X384975Y593433D01*
X384767Y593267D01*
X384350Y592433D01*
X384059Y592058D01*
X383642Y591808D01*
X383267Y591725D01*
Y593475D01*
G01X349517Y577841D02*
Y573841D01*
X342117D01*
G01X367000Y579517D02*
X369500D01*
Y580558D01*
X369375Y580892D01*
X369208Y581100D01*
X368875Y581183D01*
X368542Y581100D01*
X368333Y580850D01*
X368208Y580558D01*
Y579517D01*
G01Y580558D02*
X367000Y581183D01*
G01Y583950D02*
X369500D01*
X367708Y582408D01*
Y584492D01*
G01X369083Y585758D02*
X369333Y586008D01*
X369458Y586300D01*
X369500Y586633D01*
X369417Y587050D01*
X369208Y587342D01*
X368958Y587425D01*
X368708Y587383D01*
X368500Y587217D01*
X368083Y586383D01*
X367792Y586008D01*
X367375Y585758D01*
X367000Y585675D01*
Y587425D01*
G01X367375Y588733D02*
X367167Y588983D01*
X367042Y589275D01*
X367000Y589650D01*
X367083Y590025D01*
X367250Y590317D01*
X367542Y590525D01*
X367875Y590567D01*
X368208Y590483D01*
X368417Y590275D01*
X368583Y589983D01*
X368625Y589692D01*
X368583Y589400D01*
X368417Y589025D01*
X369500Y589150D01*
Y590275D01*
G01X363400Y578100D02*
X367400D01*
Y570700D01*
G01X347244Y581860D02*
X343244D01*
Y589260D01*
G01X370700Y579517D02*
X373200D01*
Y580558D01*
X373075Y580892D01*
X372908Y581100D01*
X372575Y581183D01*
X372242Y581100D01*
X372033Y580850D01*
X371908Y580558D01*
Y579517D01*
G01Y580558D02*
X370700Y581183D01*
G01Y583950D02*
X373200D01*
X371408Y582408D01*
Y584492D01*
G01X371200Y585633D02*
X370908Y585883D01*
X370742Y586217D01*
X370700Y586592D01*
X370742Y586925D01*
X370950Y587258D01*
X371200Y587467D01*
X371450Y587508D01*
X371742Y587425D01*
X371950Y587133D01*
X372033Y586842D01*
Y586467D01*
G01Y586842D02*
X372158Y587092D01*
X372367Y587300D01*
X372617Y587383D01*
X372867Y587300D01*
X373075Y587092D01*
X373200Y586717D01*
X373158Y586342D01*
X372992Y585967D01*
G01X373200Y589650D02*
X373117Y589317D01*
X372908Y589067D01*
X372658Y588900D01*
X372325Y588775D01*
X371950Y588733D01*
X371575Y588775D01*
X371242Y588900D01*
X370992Y589067D01*
X370783Y589317D01*
X370700Y589650D01*
X370783Y589983D01*
X370992Y590233D01*
X371242Y590400D01*
X371575Y590525D01*
X371950Y590567D01*
X372325Y590525D01*
X372658Y590400D01*
X372908Y590233D01*
X373117Y589983D01*
X373200Y589650D01*
G01X371500Y570700D02*
X367500D01*
Y578100D01*
G01X353600Y557617D02*
X356100D01*
Y558658D01*
X355975Y558992D01*
X355808Y559200D01*
X355475Y559283D01*
X355142Y559200D01*
X354933Y558950D01*
X354808Y558658D01*
Y557617D01*
G01Y558658D02*
X353600Y559283D01*
G01Y561467D02*
X354142Y561550D01*
X354600Y561675D01*
X355017Y561842D01*
X355475Y562050D01*
X356100Y562383D01*
Y560717D01*
G01X355683Y563858D02*
X355933Y564108D01*
X356058Y564400D01*
X356100Y564733D01*
X356017Y565150D01*
X355808Y565442D01*
X355558Y565525D01*
X355308Y565483D01*
X355100Y565317D01*
X354683Y564483D01*
X354392Y564108D01*
X353975Y563858D01*
X353600Y563775D01*
Y565525D01*
G01X355683Y566958D02*
X355933Y567208D01*
X356058Y567500D01*
X356100Y567833D01*
X356017Y568250D01*
X355808Y568542D01*
X355558Y568625D01*
X355308Y568583D01*
X355100Y568417D01*
X354683Y567583D01*
X354392Y567208D01*
X353975Y566958D01*
X353600Y566875D01*
Y568625D01*
G01X358300Y563800D02*
X362300D01*
Y556400D01*
G01X352283Y544367D02*
Y546867D01*
X351242D01*
X350908Y546742D01*
X350700Y546575D01*
X350617Y546242D01*
X350700Y545909D01*
X350950Y545700D01*
X351242Y545575D01*
X352283D01*
G01X351242D02*
X350617Y544367D01*
G01X348433D02*
X348350Y544909D01*
X348225Y545367D01*
X348058Y545784D01*
X347850Y546242D01*
X347517Y546867D01*
X349183D01*
G01X346042Y546450D02*
X345792Y546700D01*
X345500Y546825D01*
X345167Y546867D01*
X344750Y546784D01*
X344458Y546575D01*
X344375Y546325D01*
X344417Y546075D01*
X344583Y545867D01*
X345417Y545450D01*
X345792Y545159D01*
X346042Y544742D01*
X346125Y544367D01*
X344375D01*
G01X342150D02*
Y546867D01*
X342650Y546367D01*
G01Y544367D02*
X341650D01*
G01X361496Y547220D02*
Y543220D01*
X354096D01*
G01X381583Y538567D02*
Y541067D01*
X380542D01*
X380208Y540942D01*
X380000Y540775D01*
X379917Y540442D01*
X380000Y540109D01*
X380250Y539900D01*
X380542Y539775D01*
X381583D01*
G01X380542D02*
X379917Y538567D01*
G01X378442Y540650D02*
X378192Y540900D01*
X377900Y541025D01*
X377567Y541067D01*
X377150Y540984D01*
X376858Y540775D01*
X376775Y540525D01*
X376817Y540275D01*
X376983Y540067D01*
X377817Y539650D01*
X378192Y539359D01*
X378442Y538942D01*
X378525Y538567D01*
X376775D01*
G01X374633D02*
X374550Y539109D01*
X374425Y539567D01*
X374258Y539984D01*
X374050Y540442D01*
X373717Y541067D01*
X375383D01*
G01X372367Y538942D02*
X372117Y538734D01*
X371825Y538609D01*
X371450Y538567D01*
X371075Y538650D01*
X370783Y538817D01*
X370575Y539109D01*
X370533Y539442D01*
X370617Y539775D01*
X370825Y539984D01*
X371117Y540150D01*
X371408Y540192D01*
X371700Y540150D01*
X372075Y539984D01*
X371950Y541067D01*
X370825D01*
G01X369000Y542600D02*
Y538600D01*
X361600D01*
G01X380867Y532667D02*
Y530875D01*
X380700Y530500D01*
X380367Y530250D01*
X379950Y530167D01*
X379533Y530250D01*
X379200Y530500D01*
X379033Y530875D01*
Y532667D01*
G01X376850Y530167D02*
Y532667D01*
X377350Y532167D01*
G01Y530167D02*
X376350D01*
G01X373750Y532667D02*
X374083Y532584D01*
X374333Y532375D01*
X374500Y532125D01*
X374625Y531792D01*
X374667Y531417D01*
X374625Y531042D01*
X374500Y530709D01*
X374333Y530459D01*
X374083Y530250D01*
X373750Y530167D01*
X373417Y530250D01*
X373167Y530459D01*
X373000Y530709D01*
X372875Y531042D01*
X372833Y531417D01*
X372875Y531792D01*
X373000Y532125D01*
X373167Y532375D01*
X373417Y532584D01*
X373750Y532667D01*
G01X370650Y530167D02*
Y532667D01*
X371150Y532167D01*
G01Y530167D02*
X370150D01*
G01X354980Y527400D02*
X368380D01*
G01X354980Y537400D02*
Y527400D01*
G01X368380Y537400D02*
X354980D01*
G01X368380Y527400D02*
Y537400D01*
G01X378700Y559400D02*
X378742Y559067D01*
X378908Y558775D01*
X379158Y558525D01*
X379450Y558358D01*
X379783Y558275D01*
X380117D01*
X380450Y558358D01*
X380742Y558525D01*
X380992Y558775D01*
X381158Y559067D01*
X381200Y559400D01*
X381158Y559733D01*
X380992Y560025D01*
X380742Y560275D01*
X380450Y560442D01*
X380117Y560525D01*
X379783D01*
X379450Y560442D01*
X379158Y560275D01*
X378908Y560025D01*
X378742Y559733D01*
X378700Y559400D01*
G01X379367Y559733D02*
X378700Y560233D01*
G01X380783Y561708D02*
X381033Y561958D01*
X381158Y562250D01*
X381200Y562583D01*
X381117Y563000D01*
X380908Y563292D01*
X380658Y563375D01*
X380408Y563333D01*
X380200Y563167D01*
X379783Y562333D01*
X379492Y561958D01*
X379075Y561708D01*
X378700Y561625D01*
Y563375D01*
G01X379742Y564808D02*
X380033Y565100D01*
X380200Y565350D01*
X380283Y565683D01*
X380200Y565975D01*
X380033Y566183D01*
X379783Y566350D01*
X379492Y566392D01*
X379242Y566350D01*
X378992Y566183D01*
X378783Y565933D01*
X378700Y565642D01*
X378783Y565308D01*
X379033Y565017D01*
X379408Y564850D01*
X379825Y564808D01*
X380367Y564892D01*
X380658Y565017D01*
X380950Y565225D01*
X381158Y565517D01*
X381200Y565808D01*
X381117Y566100D01*
X380908Y566308D01*
G01X377100Y556838D02*
X363100D01*
G01X377100Y569838D02*
Y556838D01*
G01X363100Y569838D02*
X377100D01*
G01X363100Y556838D02*
Y569838D01*
G01X377192Y588417D02*
X377317Y588167D01*
X377400Y587875D01*
Y587542D01*
X377275Y587167D01*
X377067Y586875D01*
X376817Y586667D01*
X376400Y586500D01*
X376025Y586458D01*
X375650Y586542D01*
X375400Y586667D01*
X375150Y586917D01*
X374983Y587208D01*
X374900Y587500D01*
Y587792D01*
X374983Y588083D01*
X375108Y588333D01*
X375275Y588542D01*
G01X374900Y590600D02*
X377400D01*
X376900Y590100D01*
G01X374900D02*
Y591100D01*
G01X375400Y592783D02*
X375108Y593033D01*
X374942Y593367D01*
X374900Y593742D01*
X374942Y594075D01*
X375150Y594408D01*
X375400Y594617D01*
X375650Y594658D01*
X375942Y594575D01*
X376150Y594283D01*
X376233Y593992D01*
Y593617D01*
G01Y593992D02*
X376358Y594242D01*
X376567Y594450D01*
X376817Y594533D01*
X377067Y594450D01*
X377275Y594242D01*
X377400Y593867D01*
X377358Y593492D01*
X377192Y593117D01*
G01X377448Y633017D02*
Y635517D01*
X376407D01*
X376073Y635392D01*
X375865Y635225D01*
X375782Y634892D01*
X375865Y634559D01*
X376115Y634350D01*
X376407Y634225D01*
X377448D01*
G01X376407D02*
X375782Y633017D01*
G01X374307Y635100D02*
X374057Y635350D01*
X373765Y635475D01*
X373432Y635517D01*
X373015Y635434D01*
X372723Y635225D01*
X372640Y634975D01*
X372682Y634725D01*
X372848Y634517D01*
X373682Y634100D01*
X374057Y633809D01*
X374307Y633392D01*
X374390Y633017D01*
X372640D01*
G01X370415D02*
Y635517D01*
X370915Y635017D01*
G01Y633017D02*
X369915D01*
G01X369084Y624032D02*
Y628032D01*
X376484D01*
G01X382133Y611600D02*
Y614100D01*
X381092D01*
X380758Y613975D01*
X380550Y613808D01*
X380467Y613475D01*
X380550Y613142D01*
X380800Y612933D01*
X381092Y612808D01*
X382133D01*
G01X381092D02*
X380467Y611600D01*
G01X378992Y613683D02*
X378742Y613933D01*
X378450Y614058D01*
X378117Y614100D01*
X377700Y614017D01*
X377408Y613808D01*
X377325Y613558D01*
X377367Y613308D01*
X377533Y613100D01*
X378367Y612683D01*
X378742Y612392D01*
X378992Y611975D01*
X379075Y611600D01*
X377325D01*
G01X375892Y613683D02*
X375642Y613933D01*
X375350Y614058D01*
X375017Y614100D01*
X374600Y614017D01*
X374308Y613808D01*
X374225Y613558D01*
X374267Y613308D01*
X374433Y613100D01*
X375267Y612683D01*
X375642Y612392D01*
X375892Y611975D01*
X375975Y611600D01*
X374225D01*
G01X381116Y622503D02*
Y618503D01*
X373716D01*
G01X382000Y596400D02*
X378000D01*
Y603800D01*
G01X345200Y593817D02*
X347700D01*
Y594858D01*
X347575Y595192D01*
X347408Y595400D01*
X347075Y595483D01*
X346742Y595400D01*
X346533Y595150D01*
X346408Y594858D01*
Y593817D01*
G01Y594858D02*
X345200Y595483D01*
G01Y598250D02*
X347700D01*
X345908Y596708D01*
Y598792D01*
G01X347283Y600058D02*
X347533Y600308D01*
X347658Y600600D01*
X347700Y600933D01*
X347617Y601350D01*
X347408Y601642D01*
X347158Y601725D01*
X346908Y601683D01*
X346700Y601517D01*
X346283Y600683D01*
X345992Y600308D01*
X345575Y600058D01*
X345200Y599975D01*
Y601725D01*
G01X345492Y603242D02*
X345283Y603533D01*
X345200Y603867D01*
X345283Y604200D01*
X345533Y604492D01*
X345908Y604700D01*
X346283Y604783D01*
X346742D01*
X347117Y604700D01*
X347450Y604492D01*
X347617Y604242D01*
X347700Y603950D01*
X347617Y603617D01*
X347450Y603367D01*
X347200Y603200D01*
X346867Y603117D01*
X346575Y603200D01*
X346283Y603408D01*
X346117Y603658D01*
X346075Y603950D01*
X346158Y604283D01*
X346367Y604533D01*
X346742Y604783D01*
G01X355615Y629301D02*
Y626801D01*
G01X356573Y629301D02*
X354657D01*
G01X353348Y626801D02*
Y629301D01*
X352348D01*
X352015Y629176D01*
X351765Y628884D01*
X351682Y628551D01*
X351765Y628218D01*
X351973Y627968D01*
X352348Y627843D01*
X353348D01*
G01X348915Y626801D02*
Y629301D01*
X350457Y627509D01*
X348373D01*
G01X385767Y595900D02*
X383267D01*
G01X385767Y594942D02*
Y596858D01*
G01X383267Y598167D02*
X385767D01*
Y599167D01*
X385642Y599500D01*
X385350Y599750D01*
X385017Y599833D01*
X384684Y599750D01*
X384434Y599542D01*
X384309Y599167D01*
Y598167D01*
G01Y601308D02*
X384600Y601600D01*
X384767Y601850D01*
X384850Y602183D01*
X384767Y602475D01*
X384600Y602683D01*
X384350Y602850D01*
X384059Y602892D01*
X383809Y602850D01*
X383559Y602683D01*
X383350Y602433D01*
X383267Y602142D01*
X383350Y601808D01*
X383600Y601517D01*
X383975Y601350D01*
X384392Y601308D01*
X384934Y601392D01*
X385225Y601517D01*
X385517Y601725D01*
X385725Y602017D01*
X385767Y602308D01*
X385684Y602600D01*
X385475Y602808D01*
G01X353559Y643517D02*
X353684Y643267D01*
X353767Y642975D01*
Y642642D01*
X353642Y642267D01*
X353434Y641975D01*
X353184Y641767D01*
X352767Y641600D01*
X352392Y641558D01*
X352017Y641642D01*
X351767Y641767D01*
X351517Y642017D01*
X351350Y642308D01*
X351267Y642600D01*
Y642892D01*
X351350Y643183D01*
X351475Y643433D01*
X351642Y643642D01*
G01X351267Y645700D02*
X353767D01*
X353267Y645200D01*
G01X351267D02*
Y646200D01*
G01X351642Y647883D02*
X351434Y648133D01*
X351309Y648425D01*
X351267Y648800D01*
X351350Y649175D01*
X351517Y649467D01*
X351809Y649675D01*
X352142Y649717D01*
X352475Y649633D01*
X352684Y649425D01*
X352850Y649133D01*
X352892Y648842D01*
X352850Y648550D01*
X352684Y648175D01*
X353767Y648300D01*
Y649425D01*
G01X357559Y643517D02*
X357684Y643267D01*
X357767Y642975D01*
Y642642D01*
X357642Y642267D01*
X357434Y641975D01*
X357184Y641767D01*
X356767Y641600D01*
X356392Y641558D01*
X356017Y641642D01*
X355767Y641767D01*
X355517Y642017D01*
X355350Y642308D01*
X355267Y642600D01*
Y642892D01*
X355350Y643183D01*
X355475Y643433D01*
X355642Y643642D01*
G01X355267Y645700D02*
X357767D01*
X357267Y645200D01*
G01X355267D02*
Y646200D01*
G01X356309Y648008D02*
X356600Y648300D01*
X356767Y648550D01*
X356850Y648883D01*
X356767Y649175D01*
X356600Y649383D01*
X356350Y649550D01*
X356059Y649592D01*
X355809Y649550D01*
X355559Y649383D01*
X355350Y649133D01*
X355267Y648842D01*
X355350Y648508D01*
X355600Y648217D01*
X355975Y648050D01*
X356392Y648008D01*
X356934Y648092D01*
X357225Y648217D01*
X357517Y648425D01*
X357725Y648717D01*
X357767Y649008D01*
X357684Y649300D01*
X357475Y649508D01*
G01X382133Y636459D02*
X382383Y636584D01*
X382675Y636667D01*
X383008D01*
X383383Y636542D01*
X383675Y636334D01*
X383883Y636084D01*
X384050Y635667D01*
X384092Y635292D01*
X384008Y634917D01*
X383883Y634667D01*
X383633Y634417D01*
X383342Y634250D01*
X383050Y634167D01*
X382758D01*
X382467Y634250D01*
X382217Y634375D01*
X382008Y634542D01*
G01X379950Y634167D02*
X379658Y634209D01*
X379325Y634334D01*
X379117Y634542D01*
X379033Y634834D01*
X379117Y635125D01*
X379367Y635375D01*
X379742Y635500D01*
X380158D01*
X380408Y635584D01*
X380617Y635792D01*
X380700Y636084D01*
X380575Y636375D01*
X380283Y636584D01*
X379950Y636667D01*
X379617Y636584D01*
X379325Y636375D01*
X379200Y636084D01*
X379283Y635792D01*
X379492Y635584D01*
X379742Y635500D01*
X380158D01*
X380533Y635375D01*
X380783Y635125D01*
X380867Y634834D01*
X380783Y634542D01*
X380575Y634334D01*
X380242Y634209D01*
X379950Y634167D01*
G01X353959Y599817D02*
X354084Y599567D01*
X354167Y599275D01*
Y598942D01*
X354042Y598567D01*
X353834Y598275D01*
X353584Y598067D01*
X353167Y597900D01*
X352792Y597858D01*
X352417Y597942D01*
X352167Y598067D01*
X351917Y598317D01*
X351750Y598608D01*
X351667Y598900D01*
Y599192D01*
X351750Y599483D01*
X351875Y599733D01*
X352042Y599942D01*
G01X351667Y602000D02*
X354167D01*
X353667Y601500D01*
G01X351667D02*
Y602500D01*
G01X354167Y605100D02*
X354084Y604767D01*
X353875Y604517D01*
X353625Y604350D01*
X353292Y604225D01*
X352917Y604183D01*
X352542Y604225D01*
X352209Y604350D01*
X351959Y604517D01*
X351750Y604767D01*
X351667Y605100D01*
X351750Y605433D01*
X351959Y605683D01*
X352209Y605850D01*
X352542Y605975D01*
X352917Y606017D01*
X353292Y605975D01*
X353625Y605850D01*
X353875Y605683D01*
X354084Y605433D01*
X354167Y605100D01*
G01X368459Y631317D02*
X368584Y631067D01*
X368667Y630775D01*
Y630442D01*
X368542Y630067D01*
X368334Y629775D01*
X368084Y629567D01*
X367667Y629400D01*
X367292Y629358D01*
X366917Y629442D01*
X366667Y629567D01*
X366417Y629817D01*
X366250Y630108D01*
X366167Y630400D01*
Y630692D01*
X366250Y630983D01*
X366375Y631233D01*
X366542Y631442D01*
G01X366167Y633500D02*
X368667D01*
X368167Y633000D01*
G01X366167D02*
Y634000D01*
G01Y636600D02*
X368667D01*
X368167Y636100D01*
G01X366167D02*
Y637100D01*
G01X353683Y617459D02*
X353933Y617584D01*
X354225Y617667D01*
X354558D01*
X354933Y617542D01*
X355225Y617334D01*
X355433Y617084D01*
X355600Y616667D01*
X355642Y616292D01*
X355558Y615917D01*
X355433Y615667D01*
X355183Y615417D01*
X354892Y615250D01*
X354600Y615167D01*
X354308D01*
X354017Y615250D01*
X353767Y615375D01*
X353558Y615542D01*
G01X351500Y615167D02*
Y617667D01*
X352000Y617167D01*
G01Y615167D02*
X351000D01*
G01X349192Y617250D02*
X348942Y617500D01*
X348650Y617625D01*
X348317Y617667D01*
X347900Y617584D01*
X347608Y617375D01*
X347525Y617125D01*
X347567Y616875D01*
X347733Y616667D01*
X348567Y616250D01*
X348942Y615959D01*
X349192Y615542D01*
X349275Y615167D01*
X347525D01*
G01X357959Y600367D02*
X358084Y600117D01*
X358167Y599825D01*
Y599492D01*
X358042Y599117D01*
X357834Y598825D01*
X357584Y598617D01*
X357167Y598450D01*
X356792Y598408D01*
X356417Y598492D01*
X356167Y598617D01*
X355917Y598867D01*
X355750Y599158D01*
X355667Y599450D01*
Y599742D01*
X355750Y600033D01*
X355875Y600283D01*
X356042Y600492D01*
G01X355959Y601842D02*
X355750Y602133D01*
X355667Y602467D01*
X355750Y602800D01*
X356000Y603092D01*
X356375Y603300D01*
X356750Y603383D01*
X357209D01*
X357584Y603300D01*
X357917Y603092D01*
X358084Y602842D01*
X358167Y602550D01*
X358084Y602217D01*
X357917Y601967D01*
X357667Y601800D01*
X357334Y601717D01*
X357042Y601800D01*
X356750Y602008D01*
X356584Y602258D01*
X356542Y602550D01*
X356625Y602883D01*
X356834Y603133D01*
X357209Y603383D01*
G01X362217Y656967D02*
Y655175D01*
X362050Y654800D01*
X361717Y654550D01*
X361300Y654467D01*
X360883Y654550D01*
X360550Y654800D01*
X360383Y655175D01*
Y656967D01*
G01X359117Y654967D02*
X358867Y654675D01*
X358533Y654509D01*
X358158Y654467D01*
X357825Y654509D01*
X357492Y654717D01*
X357283Y654967D01*
X357242Y655217D01*
X357325Y655509D01*
X357617Y655717D01*
X357908Y655800D01*
X358283D01*
G01X357908D02*
X357658Y655925D01*
X357450Y656134D01*
X357367Y656384D01*
X357450Y656634D01*
X357658Y656842D01*
X358033Y656967D01*
X358408Y656925D01*
X358783Y656759D01*
G01X355892Y656550D02*
X355642Y656800D01*
X355350Y656925D01*
X355017Y656967D01*
X354600Y656884D01*
X354308Y656675D01*
X354225Y656425D01*
X354267Y656175D01*
X354433Y655967D01*
X355267Y655550D01*
X355642Y655259D01*
X355892Y654842D01*
X355975Y654467D01*
X354225D01*
G01X388733Y698142D02*
X388983Y698267D01*
X389275Y698350D01*
X389608D01*
X389983Y698225D01*
X390275Y698017D01*
X390483Y697767D01*
X390650Y697350D01*
X390692Y696975D01*
X390608Y696600D01*
X390483Y696350D01*
X390233Y696100D01*
X389942Y695933D01*
X389650Y695850D01*
X389358D01*
X389067Y695933D01*
X388817Y696058D01*
X388608Y696225D01*
G01X386050Y695850D02*
Y698350D01*
X387592Y696558D01*
X385508D01*
G01X383450Y695850D02*
Y698350D01*
X383950Y697850D01*
G01Y695850D02*
X382950D01*
G01X372733Y714642D02*
X372983Y714767D01*
X373275Y714850D01*
X373608D01*
X373983Y714725D01*
X374275Y714517D01*
X374483Y714267D01*
X374650Y713850D01*
X374692Y713475D01*
X374608Y713100D01*
X374483Y712850D01*
X374233Y712600D01*
X373942Y712433D01*
X373650Y712350D01*
X373358D01*
X373067Y712433D01*
X372817Y712558D01*
X372608Y712725D01*
G01X371467Y712850D02*
X371217Y712558D01*
X370883Y712392D01*
X370508Y712350D01*
X370175Y712392D01*
X369842Y712600D01*
X369633Y712850D01*
X369592Y713100D01*
X369675Y713392D01*
X369967Y713600D01*
X370258Y713683D01*
X370633D01*
G01X370258D02*
X370008Y713808D01*
X369800Y714017D01*
X369717Y714267D01*
X369800Y714517D01*
X370008Y714725D01*
X370383Y714850D01*
X370758Y714808D01*
X371133Y714642D01*
G01X368158Y712642D02*
X367867Y712433D01*
X367533Y712350D01*
X367200Y712433D01*
X366908Y712683D01*
X366700Y713058D01*
X366617Y713433D01*
Y713892D01*
X366700Y714267D01*
X366908Y714600D01*
X367158Y714767D01*
X367450Y714850D01*
X367783Y714767D01*
X368033Y714600D01*
X368200Y714350D01*
X368283Y714017D01*
X368200Y713725D01*
X367992Y713433D01*
X367742Y713267D01*
X367450Y713225D01*
X367117Y713308D01*
X366867Y713517D01*
X366617Y713892D01*
G01X375583Y685592D02*
X375833Y685717D01*
X376125Y685800D01*
X376458D01*
X376833Y685675D01*
X377125Y685467D01*
X377333Y685217D01*
X377500Y684800D01*
X377542Y684425D01*
X377458Y684050D01*
X377333Y683800D01*
X377083Y683550D01*
X376792Y683383D01*
X376500Y683300D01*
X376208D01*
X375917Y683383D01*
X375667Y683508D01*
X375458Y683675D01*
G01X374317Y683800D02*
X374067Y683508D01*
X373733Y683342D01*
X373358Y683300D01*
X373025Y683342D01*
X372692Y683550D01*
X372483Y683800D01*
X372442Y684050D01*
X372525Y684342D01*
X372817Y684550D01*
X373108Y684633D01*
X373483D01*
G01X373108D02*
X372858Y684758D01*
X372650Y684967D01*
X372567Y685217D01*
X372650Y685467D01*
X372858Y685675D01*
X373233Y685800D01*
X373608Y685758D01*
X373983Y685592D01*
G01X370383Y683300D02*
X370300Y683842D01*
X370175Y684300D01*
X370008Y684717D01*
X369800Y685175D01*
X369467Y685800D01*
X371133D01*
G01X366783Y674567D02*
Y677067D01*
X365742D01*
X365408Y676942D01*
X365200Y676775D01*
X365117Y676442D01*
X365200Y676109D01*
X365450Y675900D01*
X365742Y675775D01*
X366783D01*
G01X365742D02*
X365117Y674567D01*
G01X362350D02*
Y677067D01*
X363892Y675275D01*
X361808D01*
G01X359750Y674567D02*
Y677067D01*
X360250Y676567D01*
G01Y674567D02*
X359250D01*
G01X356733D02*
X356650Y675109D01*
X356525Y675567D01*
X356358Y675984D01*
X356150Y676442D01*
X355817Y677067D01*
X357483D01*
G01X351600Y681400D02*
Y685400D01*
X359000D01*
G01X342100Y685500D02*
Y689500D01*
X349500D01*
G01X380083Y662600D02*
Y665100D01*
X379042D01*
X378708Y664975D01*
X378500Y664808D01*
X378417Y664475D01*
X378500Y664142D01*
X378750Y663933D01*
X379042Y663808D01*
X380083D01*
G01X379042D02*
X378417Y662600D01*
G01X375650D02*
Y665100D01*
X377192Y663308D01*
X375108D01*
G01X373050Y662600D02*
Y665100D01*
X373550Y664600D01*
G01Y662600D02*
X372550D01*
G01X370658Y662892D02*
X370367Y662683D01*
X370033Y662600D01*
X369700Y662683D01*
X369408Y662933D01*
X369200Y663308D01*
X369117Y663683D01*
Y664142D01*
X369200Y664517D01*
X369408Y664850D01*
X369658Y665017D01*
X369950Y665100D01*
X370283Y665017D01*
X370533Y664850D01*
X370700Y664600D01*
X370783Y664267D01*
X370700Y663975D01*
X370492Y663683D01*
X370242Y663517D01*
X369950Y663475D01*
X369617Y663558D01*
X369367Y663767D01*
X369117Y664142D01*
G01X367900Y666200D02*
Y662200D01*
X360500D01*
G01X384383Y669666D02*
Y672166D01*
X383342D01*
X383008Y672041D01*
X382800Y671874D01*
X382717Y671541D01*
X382800Y671208D01*
X383050Y670999D01*
X383342Y670874D01*
X384383D01*
G01X383342D02*
X382717Y669666D01*
G01X380533D02*
X380450Y670208D01*
X380325Y670666D01*
X380158Y671083D01*
X379950Y671541D01*
X379617Y672166D01*
X381283D01*
G01X378058Y669958D02*
X377767Y669749D01*
X377433Y669666D01*
X377100Y669749D01*
X376808Y669999D01*
X376600Y670374D01*
X376517Y670749D01*
Y671208D01*
X376600Y671583D01*
X376808Y671916D01*
X377058Y672083D01*
X377350Y672166D01*
X377683Y672083D01*
X377933Y671916D01*
X378100Y671666D01*
X378183Y671333D01*
X378100Y671041D01*
X377892Y670749D01*
X377642Y670583D01*
X377350Y670541D01*
X377017Y670624D01*
X376767Y670833D01*
X376517Y671208D01*
G01X375167Y670041D02*
X374917Y669833D01*
X374625Y669708D01*
X374250Y669666D01*
X373875Y669749D01*
X373583Y669916D01*
X373375Y670208D01*
X373333Y670541D01*
X373417Y670874D01*
X373625Y671083D01*
X373917Y671249D01*
X374208Y671291D01*
X374500Y671249D01*
X374875Y671083D01*
X374750Y672166D01*
X373625D01*
G01X365100Y669900D02*
Y673900D01*
X372500D01*
G01X342500Y713567D02*
X345000D01*
Y714608D01*
X344875Y714942D01*
X344708Y715150D01*
X344375Y715233D01*
X344042Y715150D01*
X343833Y714900D01*
X343708Y714608D01*
Y713567D01*
G01Y714608D02*
X342500Y715233D01*
G01X342792Y716792D02*
X342583Y717083D01*
X342500Y717417D01*
X342583Y717750D01*
X342833Y718042D01*
X343208Y718250D01*
X343583Y718333D01*
X344042D01*
X344417Y718250D01*
X344750Y718042D01*
X344917Y717792D01*
X345000Y717500D01*
X344917Y717167D01*
X344750Y716917D01*
X344500Y716750D01*
X344167Y716667D01*
X343875Y716750D01*
X343583Y716958D01*
X343417Y717208D01*
X343375Y717500D01*
X343458Y717833D01*
X343667Y718083D01*
X344042Y718333D01*
G01X342500Y720517D02*
X343042Y720600D01*
X343500Y720725D01*
X343917Y720892D01*
X344375Y721100D01*
X345000Y721433D01*
Y719767D01*
G01X345500Y711700D02*
X349500D01*
Y704300D01*
G01X343654Y702015D02*
X347654D01*
Y694615D01*
G01X370524Y700669D02*
X373024D01*
Y701710D01*
X372899Y702044D01*
X372732Y702252D01*
X372399Y702335D01*
X372066Y702252D01*
X371857Y702002D01*
X371732Y701710D01*
Y700669D01*
G01Y701710D02*
X370524Y702335D01*
G01Y704602D02*
X373024D01*
X372524Y704102D01*
G01X370524D02*
Y705102D01*
G01X373024Y707702D02*
X372941Y707369D01*
X372732Y707119D01*
X372482Y706952D01*
X372149Y706827D01*
X371774Y706785D01*
X371399Y706827D01*
X371066Y706952D01*
X370816Y707119D01*
X370607Y707369D01*
X370524Y707702D01*
X370607Y708035D01*
X370816Y708285D01*
X371066Y708452D01*
X371399Y708577D01*
X371774Y708619D01*
X372149Y708577D01*
X372482Y708452D01*
X372732Y708285D01*
X372941Y708035D01*
X373024Y707702D01*
G01X370524Y710802D02*
X373024D01*
X372524Y710302D01*
G01X370524D02*
Y711302D01*
G01X373500Y709700D02*
X377500D01*
Y702300D01*
G01X387183Y688700D02*
Y691200D01*
X386142D01*
X385808Y691075D01*
X385600Y690908D01*
X385517Y690575D01*
X385600Y690242D01*
X385850Y690033D01*
X386142Y689908D01*
X387183D01*
G01X386142D02*
X385517Y688700D01*
G01X383250D02*
Y691200D01*
X383750Y690700D01*
G01Y688700D02*
X382750D01*
G01X380150Y691200D02*
X380483Y691117D01*
X380733Y690908D01*
X380900Y690658D01*
X381025Y690325D01*
X381067Y689950D01*
X381025Y689575D01*
X380900Y689242D01*
X380733Y688992D01*
X380483Y688783D01*
X380150Y688700D01*
X379817Y688783D01*
X379567Y688992D01*
X379400Y689242D01*
X379275Y689575D01*
X379233Y689950D01*
X379275Y690325D01*
X379400Y690658D01*
X379567Y690908D01*
X379817Y691117D01*
X380150Y691200D01*
G01X377050D02*
X377383Y691117D01*
X377633Y690908D01*
X377800Y690658D01*
X377925Y690325D01*
X377967Y689950D01*
X377925Y689575D01*
X377800Y689242D01*
X377633Y688992D01*
X377383Y688783D01*
X377050Y688700D01*
X376717Y688783D01*
X376467Y688992D01*
X376300Y689242D01*
X376175Y689575D01*
X376133Y689950D01*
X376175Y690325D01*
X376300Y690658D01*
X376467Y690908D01*
X376717Y691117D01*
X377050Y691200D01*
G01X381157Y697203D02*
Y693203D01*
X373757D01*
G01X391417Y719680D02*
Y717888D01*
X391250Y717513D01*
X390917Y717263D01*
X390500Y717180D01*
X390083Y717263D01*
X389750Y717513D01*
X389583Y717888D01*
Y719680D01*
G01X387400Y717180D02*
Y719680D01*
X387900Y719180D01*
G01Y717180D02*
X386900D01*
G01X385092Y718222D02*
X384800Y718513D01*
X384550Y718680D01*
X384217Y718763D01*
X383925Y718680D01*
X383717Y718513D01*
X383550Y718263D01*
X383508Y717972D01*
X383550Y717722D01*
X383717Y717472D01*
X383967Y717263D01*
X384258Y717180D01*
X384592Y717263D01*
X384883Y717513D01*
X385050Y717888D01*
X385092Y718305D01*
X385008Y718847D01*
X384883Y719138D01*
X384675Y719430D01*
X384383Y719638D01*
X384092Y719680D01*
X383800Y719597D01*
X383592Y719388D01*
G01X392320Y713700D02*
X378920D01*
G01X392320Y703700D02*
Y713700D01*
G01X378920Y703700D02*
X392320D01*
G01X378920Y713700D02*
Y703700D01*
G01X360617Y715680D02*
Y713888D01*
X360450Y713513D01*
X360117Y713263D01*
X359700Y713180D01*
X359283Y713263D01*
X358950Y713513D01*
X358783Y713888D01*
Y715680D01*
G01X356600Y713180D02*
Y715680D01*
X357100Y715180D01*
G01Y713180D02*
X356100D01*
G01X354417Y713555D02*
X354167Y713347D01*
X353875Y713222D01*
X353500Y713180D01*
X353125Y713263D01*
X352833Y713430D01*
X352625Y713722D01*
X352583Y714055D01*
X352667Y714388D01*
X352875Y714597D01*
X353167Y714763D01*
X353458Y714805D01*
X353750Y714763D01*
X354125Y714597D01*
X354000Y715680D01*
X352875D01*
G01X364520Y709600D02*
X351120D01*
G01X364520Y699600D02*
Y709600D01*
G01X351120Y699600D02*
X364520D01*
G01X351120Y709600D02*
Y699600D01*
G01X367517Y681000D02*
Y679208D01*
X367350Y678833D01*
X367017Y678583D01*
X366600Y678500D01*
X366183Y678583D01*
X365850Y678833D01*
X365683Y679208D01*
Y681000D01*
G01X363500Y678500D02*
Y681000D01*
X364000Y680500D01*
G01Y678500D02*
X363000D01*
G01X361192Y680583D02*
X360942Y680833D01*
X360650Y680958D01*
X360317Y681000D01*
X359900Y680917D01*
X359608Y680708D01*
X359525Y680458D01*
X359567Y680208D01*
X359733Y680000D01*
X360567Y679583D01*
X360942Y679292D01*
X361192Y678875D01*
X361275Y678500D01*
X359525D01*
G01X364420Y697000D02*
X351020D01*
G01X364420Y687000D02*
Y697000D01*
G01X351020Y687000D02*
X364420D01*
G01X351020Y697000D02*
Y687000D01*
G01X462983Y38267D02*
Y40767D01*
X461942D01*
X461608Y40642D01*
X461400Y40475D01*
X461317Y40142D01*
X461400Y39809D01*
X461650Y39600D01*
X461942Y39475D01*
X462983D01*
G01X461942D02*
X461317Y38267D01*
G01X458550D02*
Y40767D01*
X460092Y38975D01*
X458008D01*
G01X456867Y38767D02*
X456617Y38475D01*
X456283Y38309D01*
X455908Y38267D01*
X455575Y38309D01*
X455242Y38517D01*
X455033Y38767D01*
X454992Y39017D01*
X455075Y39309D01*
X455367Y39517D01*
X455658Y39600D01*
X456033D01*
G01X455658D02*
X455408Y39725D01*
X455200Y39934D01*
X455117Y40184D01*
X455200Y40434D01*
X455408Y40642D01*
X455783Y40767D01*
X456158Y40725D01*
X456533Y40559D01*
G01X453642Y39309D02*
X453350Y39600D01*
X453100Y39767D01*
X452767Y39850D01*
X452475Y39767D01*
X452267Y39600D01*
X452100Y39350D01*
X452058Y39059D01*
X452100Y38809D01*
X452267Y38559D01*
X452517Y38350D01*
X452808Y38267D01*
X453142Y38350D01*
X453433Y38600D01*
X453600Y38975D01*
X453642Y39392D01*
X453558Y39934D01*
X453433Y40225D01*
X453225Y40517D01*
X452933Y40725D01*
X452642Y40767D01*
X452350Y40684D01*
X452142Y40475D01*
G01X452000Y31600D02*
Y35600D01*
X459400D01*
G01X461533Y68567D02*
Y71067D01*
X460492D01*
X460158Y70942D01*
X459950Y70775D01*
X459867Y70442D01*
X459950Y70109D01*
X460200Y69900D01*
X460492Y69775D01*
X461533D01*
G01X460492D02*
X459867Y68567D01*
G01X457683D02*
X457600Y69109D01*
X457475Y69567D01*
X457308Y69984D01*
X457100Y70442D01*
X456767Y71067D01*
X458433D01*
G01X454000Y68567D02*
Y71067D01*
X455542Y69275D01*
X453458D01*
G01X450900Y68567D02*
Y71067D01*
X452442Y69275D01*
X450358D01*
G01X454500Y59900D02*
Y63900D01*
X461900D01*
G01X451067Y47117D02*
X453567D01*
Y48158D01*
X453442Y48492D01*
X453275Y48700D01*
X452942Y48783D01*
X452609Y48700D01*
X452400Y48450D01*
X452275Y48158D01*
Y47117D01*
G01Y48158D02*
X451067Y48783D01*
G01Y50967D02*
X451609Y51050D01*
X452067Y51175D01*
X452484Y51342D01*
X452942Y51550D01*
X453567Y51883D01*
Y50217D01*
G01X451067Y54650D02*
X453567D01*
X451775Y53108D01*
Y55192D01*
G01X451067Y57250D02*
X453567D01*
X453067Y56750D01*
G01X451067D02*
Y57750D01*
G01X454400Y59800D02*
X458400D01*
Y52400D01*
G01X463300Y68300D02*
X477300D01*
G01X463300Y55300D02*
Y68300D01*
G01X477300Y55300D02*
X463300D01*
G01X446759Y19167D02*
X446884Y18917D01*
X446967Y18625D01*
Y18292D01*
X446842Y17917D01*
X446634Y17625D01*
X446384Y17417D01*
X445967Y17250D01*
X445592Y17208D01*
X445217Y17292D01*
X444967Y17417D01*
X444717Y17667D01*
X444550Y17958D01*
X444467Y18250D01*
Y18542D01*
X444550Y18833D01*
X444675Y19083D01*
X444842Y19292D01*
G01X444467Y21350D02*
X446967D01*
X446467Y20850D01*
G01X444467D02*
Y21850D01*
G01X444842Y23533D02*
X444634Y23783D01*
X444509Y24075D01*
X444467Y24450D01*
X444550Y24825D01*
X444717Y25117D01*
X445009Y25325D01*
X445342Y25367D01*
X445675Y25283D01*
X445884Y25075D01*
X446050Y24783D01*
X446092Y24492D01*
X446050Y24200D01*
X445884Y23825D01*
X446967Y23950D01*
Y25075D01*
G01Y27550D02*
X446884Y27217D01*
X446675Y26967D01*
X446425Y26800D01*
X446092Y26675D01*
X445717Y26633D01*
X445342Y26675D01*
X445009Y26800D01*
X444759Y26967D01*
X444550Y27217D01*
X444467Y27550D01*
X444550Y27883D01*
X444759Y28133D01*
X445009Y28300D01*
X445342Y28425D01*
X445717Y28467D01*
X446092Y28425D01*
X446425Y28300D01*
X446675Y28133D01*
X446884Y27883D01*
X446967Y27550D01*
G01X440083Y41767D02*
Y44267D01*
X439042D01*
X438708Y44142D01*
X438500Y43975D01*
X438417Y43642D01*
X438500Y43309D01*
X438750Y43100D01*
X439042Y42975D01*
X440083D01*
G01X439042D02*
X438417Y41767D01*
G01X435650D02*
Y44267D01*
X437192Y42475D01*
X435108D01*
G01X433842Y42809D02*
X433550Y43100D01*
X433300Y43267D01*
X432967Y43350D01*
X432675Y43267D01*
X432467Y43100D01*
X432300Y42850D01*
X432258Y42559D01*
X432300Y42309D01*
X432467Y42059D01*
X432717Y41850D01*
X433008Y41767D01*
X433342Y41850D01*
X433633Y42100D01*
X433800Y42475D01*
X433842Y42892D01*
X433758Y43434D01*
X433633Y43725D01*
X433425Y44017D01*
X433133Y44225D01*
X432842Y44267D01*
X432550Y44184D01*
X432342Y43975D01*
G01X429950Y41767D02*
Y44267D01*
X430450Y43767D01*
G01Y41767D02*
X429450D01*
G01X436000Y35800D02*
Y39800D01*
X443400D01*
G01X473059Y41917D02*
X473184Y41667D01*
X473267Y41375D01*
Y41042D01*
X473142Y40667D01*
X472934Y40375D01*
X472684Y40167D01*
X472267Y40000D01*
X471892Y39958D01*
X471517Y40042D01*
X471267Y40167D01*
X471017Y40417D01*
X470850Y40708D01*
X470767Y41000D01*
Y41292D01*
X470850Y41583D01*
X470975Y41833D01*
X471142Y42042D01*
G01X470767Y43058D02*
X473267Y44100D01*
X470767Y45142D01*
G01X471642Y44767D02*
Y43433D01*
G01X470767Y47200D02*
X473267D01*
X472767Y46700D01*
G01X470767D02*
Y47700D01*
G01X474433Y16659D02*
X474683Y16784D01*
X474975Y16867D01*
X475308D01*
X475683Y16742D01*
X475975Y16534D01*
X476183Y16284D01*
X476350Y15867D01*
X476392Y15492D01*
X476308Y15117D01*
X476183Y14867D01*
X475933Y14617D01*
X475642Y14450D01*
X475350Y14367D01*
X475058D01*
X474767Y14450D01*
X474517Y14575D01*
X474308Y14742D01*
G01X472250Y14367D02*
Y16867D01*
X472750Y16367D01*
G01Y14367D02*
X471750D01*
G01X470067Y14867D02*
X469817Y14575D01*
X469483Y14409D01*
X469108Y14367D01*
X468775Y14409D01*
X468442Y14617D01*
X468233Y14867D01*
X468192Y15117D01*
X468275Y15409D01*
X468567Y15617D01*
X468858Y15700D01*
X469233D01*
G01X468858D02*
X468608Y15825D01*
X468400Y16034D01*
X468317Y16284D01*
X468400Y16534D01*
X468608Y16742D01*
X468983Y16867D01*
X469358Y16825D01*
X469733Y16659D01*
G01X466842Y16450D02*
X466592Y16700D01*
X466300Y16825D01*
X465967Y16867D01*
X465550Y16784D01*
X465258Y16575D01*
X465175Y16325D01*
X465217Y16075D01*
X465383Y15867D01*
X466217Y15450D01*
X466592Y15159D01*
X466842Y14742D01*
X466925Y14367D01*
X465175D01*
G01X464200Y21500D02*
X469700D01*
G01X464200D02*
Y29500D01*
X469700D01*
G01X474200Y69667D02*
X474533Y69709D01*
X474825Y69875D01*
X475075Y70125D01*
X475242Y70417D01*
X475325Y70750D01*
Y71084D01*
X475242Y71417D01*
X475075Y71709D01*
X474825Y71959D01*
X474533Y72125D01*
X474200Y72167D01*
X473867Y72125D01*
X473575Y71959D01*
X473325Y71709D01*
X473158Y71417D01*
X473075Y71084D01*
Y70750D01*
X473158Y70417D01*
X473325Y70125D01*
X473575Y69875D01*
X473867Y69709D01*
X474200Y69667D01*
G01X473867Y70334D02*
X473367Y69667D01*
G01X471892Y71750D02*
X471642Y72000D01*
X471350Y72125D01*
X471017Y72167D01*
X470600Y72084D01*
X470308Y71875D01*
X470225Y71625D01*
X470267Y71375D01*
X470433Y71167D01*
X471267Y70750D01*
X471642Y70459D01*
X471892Y70042D01*
X471975Y69667D01*
X470225D01*
G01X468000Y72167D02*
X468333Y72084D01*
X468583Y71875D01*
X468750Y71625D01*
X468875Y71292D01*
X468917Y70917D01*
X468875Y70542D01*
X468750Y70209D01*
X468583Y69959D01*
X468333Y69750D01*
X468000Y69667D01*
X467667Y69750D01*
X467417Y69959D01*
X467250Y70209D01*
X467125Y70542D01*
X467083Y70917D01*
X467125Y71292D01*
X467250Y71625D01*
X467417Y71875D01*
X467667Y72084D01*
X468000Y72167D01*
G01X509477Y29855D02*
Y32355D01*
X508436D01*
X508102Y32230D01*
X507894Y32063D01*
X507811Y31730D01*
X507894Y31397D01*
X508144Y31188D01*
X508436Y31063D01*
X509477D01*
G01X508436D02*
X507811Y29855D01*
G01X505044D02*
Y32355D01*
X506586Y30563D01*
X504502D01*
G01X501944Y29855D02*
Y32355D01*
X503486Y30563D01*
X501402D01*
G01X500052Y30147D02*
X499761Y29938D01*
X499427Y29855D01*
X499094Y29938D01*
X498802Y30188D01*
X498594Y30563D01*
X498511Y30938D01*
Y31397D01*
X498594Y31772D01*
X498802Y32105D01*
X499052Y32272D01*
X499344Y32355D01*
X499677Y32272D01*
X499927Y32105D01*
X500094Y31855D01*
X500177Y31522D01*
X500094Y31230D01*
X499886Y30938D01*
X499636Y30772D01*
X499344Y30730D01*
X499011Y30813D01*
X498761Y31022D01*
X498511Y31397D01*
G01X487794Y32455D02*
Y36455D01*
X495194D01*
G01X522090Y47290D02*
X524590D01*
Y48331D01*
X524465Y48665D01*
X524298Y48873D01*
X523965Y48956D01*
X523632Y48873D01*
X523423Y48623D01*
X523298Y48331D01*
Y47290D01*
G01Y48331D02*
X522090Y48956D01*
G01Y51723D02*
X524590D01*
X522798Y50181D01*
Y52265D01*
G01X522090Y54823D02*
X524590D01*
X522798Y53281D01*
Y55365D01*
G01X522090Y57423D02*
X522132Y57715D01*
X522257Y58048D01*
X522465Y58256D01*
X522757Y58340D01*
X523048Y58256D01*
X523298Y58006D01*
X523423Y57631D01*
Y57215D01*
X523507Y56965D01*
X523715Y56756D01*
X524007Y56673D01*
X524298Y56798D01*
X524507Y57090D01*
X524590Y57423D01*
X524507Y57756D01*
X524298Y58048D01*
X524007Y58173D01*
X523715Y58090D01*
X523507Y57881D01*
X523423Y57631D01*
Y57215D01*
X523298Y56840D01*
X523048Y56590D01*
X522757Y56506D01*
X522465Y56590D01*
X522257Y56798D01*
X522132Y57131D01*
X522090Y57423D01*
G01X510290Y59673D02*
X514290D01*
Y52273D01*
G01X503511Y37982D02*
X506011D01*
Y39023D01*
X505886Y39357D01*
X505719Y39565D01*
X505386Y39648D01*
X505053Y39565D01*
X504844Y39315D01*
X504719Y39023D01*
Y37982D01*
G01Y39023D02*
X503511Y39648D01*
G01Y42415D02*
X506011D01*
X504219Y40873D01*
Y42957D01*
G01X503511Y45515D02*
X506011D01*
X504219Y43973D01*
Y46057D01*
G01X503511Y48032D02*
X504053Y48115D01*
X504511Y48240D01*
X504928Y48407D01*
X505386Y48615D01*
X506011Y48948D01*
Y47282D01*
G01X498411Y57265D02*
X502411D01*
Y49865D01*
G01X509462Y25848D02*
Y28348D01*
X508421D01*
X508087Y28223D01*
X507879Y28056D01*
X507796Y27723D01*
X507879Y27390D01*
X508129Y27181D01*
X508421Y27056D01*
X509462D01*
G01X508421D02*
X507796Y25848D01*
G01X505029D02*
Y28348D01*
X506571Y26556D01*
X504487D01*
G01X503346Y26348D02*
X503096Y26056D01*
X502762Y25890D01*
X502387Y25848D01*
X502054Y25890D01*
X501721Y26098D01*
X501512Y26348D01*
X501471Y26598D01*
X501554Y26890D01*
X501846Y27098D01*
X502137Y27181D01*
X502512D01*
G01X502137D02*
X501887Y27306D01*
X501679Y27515D01*
X501596Y27765D01*
X501679Y28015D01*
X501887Y28223D01*
X502262Y28348D01*
X502637Y28306D01*
X503012Y28140D01*
G01X500246Y26348D02*
X499996Y26056D01*
X499662Y25890D01*
X499287Y25848D01*
X498954Y25890D01*
X498621Y26098D01*
X498412Y26348D01*
X498371Y26598D01*
X498454Y26890D01*
X498746Y27098D01*
X499037Y27181D01*
X499412D01*
G01X499037D02*
X498787Y27306D01*
X498579Y27515D01*
X498496Y27765D01*
X498579Y28015D01*
X498787Y28223D01*
X499162Y28348D01*
X499537Y28306D01*
X499912Y28140D01*
G01X495179Y32448D02*
Y28448D01*
X487779D01*
G01X507583Y67867D02*
Y70367D01*
X506542D01*
X506208Y70242D01*
X506000Y70075D01*
X505917Y69742D01*
X506000Y69409D01*
X506250Y69200D01*
X506542Y69075D01*
X507583D01*
G01X506542D02*
X505917Y67867D01*
G01X503150D02*
Y70367D01*
X504692Y68575D01*
X502608D01*
G01X500050Y67867D02*
Y70367D01*
X501592Y68575D01*
X499508D01*
G01X498242Y68909D02*
X497950Y69200D01*
X497700Y69367D01*
X497367Y69450D01*
X497075Y69367D01*
X496867Y69200D01*
X496700Y68950D01*
X496658Y68659D01*
X496700Y68409D01*
X496867Y68159D01*
X497117Y67950D01*
X497408Y67867D01*
X497742Y67950D01*
X498033Y68200D01*
X498200Y68575D01*
X498242Y68992D01*
X498158Y69534D01*
X498033Y69825D01*
X497825Y70117D01*
X497533Y70325D01*
X497242Y70367D01*
X496950Y70284D01*
X496742Y70075D01*
G01X512700Y67000D02*
Y63000D01*
X505300D01*
G01X488653Y66137D02*
X492653D01*
Y58737D01*
G01X509483Y33900D02*
Y36400D01*
X508442D01*
X508108Y36275D01*
X507900Y36108D01*
X507817Y35775D01*
X507900Y35442D01*
X508150Y35233D01*
X508442Y35108D01*
X509483D01*
G01X508442D02*
X507817Y33900D01*
G01X505050D02*
Y36400D01*
X506592Y34608D01*
X504508D01*
G01X503367Y34400D02*
X503117Y34108D01*
X502783Y33942D01*
X502408Y33900D01*
X502075Y33942D01*
X501742Y34150D01*
X501533Y34400D01*
X501492Y34650D01*
X501575Y34942D01*
X501867Y35150D01*
X502158Y35233D01*
X502533D01*
G01X502158D02*
X501908Y35358D01*
X501700Y35567D01*
X501617Y35817D01*
X501700Y36067D01*
X501908Y36275D01*
X502283Y36400D01*
X502658Y36358D01*
X503033Y36192D01*
G01X499433Y33900D02*
X499350Y34442D01*
X499225Y34900D01*
X499058Y35317D01*
X498850Y35775D01*
X498517Y36400D01*
X500183D01*
G01X495200Y40500D02*
Y36500D01*
X487800D01*
G01X490583Y47500D02*
Y50000D01*
X489542D01*
X489208Y49875D01*
X489000Y49708D01*
X488917Y49375D01*
X489000Y49042D01*
X489250Y48833D01*
X489542Y48708D01*
X490583D01*
G01X489542D02*
X488917Y47500D01*
G01X486733D02*
X486650Y48042D01*
X486525Y48500D01*
X486358Y48917D01*
X486150Y49375D01*
X485817Y50000D01*
X487483D01*
G01X483050Y47500D02*
Y50000D01*
X484592Y48208D01*
X482508D01*
G01X481367Y48000D02*
X481117Y47708D01*
X480783Y47542D01*
X480408Y47500D01*
X480075Y47542D01*
X479742Y47750D01*
X479533Y48000D01*
X479492Y48250D01*
X479575Y48542D01*
X479867Y48750D01*
X480158Y48833D01*
X480533D01*
G01X480158D02*
X479908Y48958D01*
X479700Y49167D01*
X479617Y49417D01*
X479700Y49667D01*
X479908Y49875D01*
X480283Y50000D01*
X480658Y49958D01*
X481033Y49792D01*
G01X485300Y60900D02*
Y56900D01*
X477900D01*
G01X490583Y51500D02*
Y54000D01*
X489542D01*
X489208Y53875D01*
X489000Y53708D01*
X488917Y53375D01*
X489000Y53042D01*
X489250Y52833D01*
X489542Y52708D01*
X490583D01*
G01X489542D02*
X488917Y51500D01*
G01X486733D02*
X486650Y52042D01*
X486525Y52500D01*
X486358Y52917D01*
X486150Y53375D01*
X485817Y54000D01*
X487483D01*
G01X483050Y51500D02*
Y54000D01*
X484592Y52208D01*
X482508D01*
G01X481242Y53583D02*
X480992Y53833D01*
X480700Y53958D01*
X480367Y54000D01*
X479950Y53917D01*
X479658Y53708D01*
X479575Y53458D01*
X479617Y53208D01*
X479783Y53000D01*
X480617Y52583D01*
X480992Y52292D01*
X481242Y51875D01*
X481325Y51500D01*
X479575D01*
G01X485300Y64900D02*
Y60900D01*
X477900D01*
G01X477300Y68300D02*
Y55300D01*
G01X519987Y50664D02*
X520112Y50414D01*
X520195Y50122D01*
Y49789D01*
X520070Y49414D01*
X519862Y49122D01*
X519612Y48914D01*
X519195Y48747D01*
X518820Y48705D01*
X518445Y48789D01*
X518195Y48914D01*
X517945Y49164D01*
X517778Y49455D01*
X517695Y49747D01*
Y50039D01*
X517778Y50330D01*
X517903Y50580D01*
X518070Y50789D01*
G01X517695Y52847D02*
X520195D01*
X519695Y52347D01*
G01X517695D02*
Y53347D01*
G01Y56447D02*
X520195D01*
X518403Y54905D01*
Y56989D01*
G01X518070Y58130D02*
X517862Y58380D01*
X517737Y58672D01*
X517695Y59047D01*
X517778Y59422D01*
X517945Y59714D01*
X518237Y59922D01*
X518570Y59964D01*
X518903Y59880D01*
X519112Y59672D01*
X519278Y59380D01*
X519320Y59089D01*
X519278Y58797D01*
X519112Y58422D01*
X520195Y58547D01*
Y59672D01*
G01X501392Y39582D02*
X501517Y39332D01*
X501600Y39040D01*
Y38707D01*
X501475Y38332D01*
X501267Y38040D01*
X501017Y37832D01*
X500600Y37665D01*
X500225Y37623D01*
X499850Y37707D01*
X499600Y37832D01*
X499350Y38082D01*
X499183Y38373D01*
X499100Y38665D01*
Y38957D01*
X499183Y39248D01*
X499308Y39498D01*
X499475Y39707D01*
G01X499100Y41765D02*
X501600D01*
X501100Y41265D01*
G01X499100D02*
Y42265D01*
G01Y45365D02*
X501600D01*
X499808Y43823D01*
Y45907D01*
G01X499100Y48465D02*
X501600D01*
X499808Y46923D01*
Y49007D01*
G01X476300Y21500D02*
X481800D01*
Y29500D01*
X476200D01*
G01X489067Y68817D02*
X491567D01*
Y69858D01*
X491442Y70192D01*
X491275Y70400D01*
X490942Y70483D01*
X490609Y70400D01*
X490400Y70150D01*
X490275Y69858D01*
Y68817D01*
G01Y69858D02*
X489067Y70483D01*
G01Y73250D02*
X491567D01*
X489775Y71708D01*
Y73792D01*
G01X489067Y76350D02*
X491567D01*
X489775Y74808D01*
Y76892D01*
G01X489442Y78033D02*
X489234Y78283D01*
X489109Y78575D01*
X489067Y78950D01*
X489150Y79325D01*
X489317Y79617D01*
X489609Y79825D01*
X489942Y79867D01*
X490275Y79783D01*
X490484Y79575D01*
X490650Y79283D01*
X490692Y78992D01*
X490650Y78700D01*
X490484Y78325D01*
X491567Y78450D01*
Y79575D01*
G01X542417Y73417D02*
Y71625D01*
X542250Y71250D01*
X541917Y71000D01*
X541500Y70917D01*
X541083Y71000D01*
X540750Y71250D01*
X540583Y71625D01*
Y73417D01*
G01X539317Y71292D02*
X539067Y71084D01*
X538775Y70959D01*
X538400Y70917D01*
X538025Y71000D01*
X537733Y71167D01*
X537525Y71459D01*
X537483Y71792D01*
X537567Y72125D01*
X537775Y72334D01*
X538067Y72500D01*
X538358Y72542D01*
X538650Y72500D01*
X539025Y72334D01*
X538900Y73417D01*
X537775D01*
G01X535300Y70917D02*
Y73417D01*
X535800Y72917D01*
G01Y70917D02*
X534800D01*
G01X562933Y60759D02*
X563183Y60884D01*
X563475Y60967D01*
X563808D01*
X564183Y60842D01*
X564475Y60634D01*
X564683Y60384D01*
X564850Y59967D01*
X564892Y59592D01*
X564808Y59217D01*
X564683Y58967D01*
X564433Y58717D01*
X564142Y58550D01*
X563850Y58467D01*
X563558D01*
X563267Y58550D01*
X563017Y58675D01*
X562808Y58842D01*
G01X561667D02*
X561417Y58634D01*
X561125Y58509D01*
X560750Y58467D01*
X560375Y58550D01*
X560083Y58717D01*
X559875Y59009D01*
X559833Y59342D01*
X559917Y59675D01*
X560125Y59884D01*
X560417Y60050D01*
X560708Y60092D01*
X561000Y60050D01*
X561375Y59884D01*
X561250Y60967D01*
X560125D01*
G01X558442Y60550D02*
X558192Y60800D01*
X557900Y60925D01*
X557567Y60967D01*
X557150Y60884D01*
X556858Y60675D01*
X556775Y60425D01*
X556817Y60175D01*
X556983Y59967D01*
X557817Y59550D01*
X558192Y59259D01*
X558442Y58842D01*
X558525Y58467D01*
X556775D01*
G01X554550D02*
Y60967D01*
X555050Y60467D01*
G01Y58467D02*
X554050D01*
G01X581117Y58217D02*
Y56425D01*
X580950Y56050D01*
X580617Y55800D01*
X580200Y55717D01*
X579783Y55800D01*
X579450Y56050D01*
X579283Y56425D01*
Y58217D01*
G01X578017Y56092D02*
X577767Y55884D01*
X577475Y55759D01*
X577100Y55717D01*
X576725Y55800D01*
X576433Y55967D01*
X576225Y56259D01*
X576183Y56592D01*
X576267Y56925D01*
X576475Y57134D01*
X576767Y57300D01*
X577058Y57342D01*
X577350Y57300D01*
X577725Y57134D01*
X577600Y58217D01*
X576475D01*
G01X574792Y57800D02*
X574542Y58050D01*
X574250Y58175D01*
X573917Y58217D01*
X573500Y58134D01*
X573208Y57925D01*
X573125Y57675D01*
X573167Y57425D01*
X573333Y57217D01*
X574167Y56800D01*
X574542Y56509D01*
X574792Y56092D01*
X574875Y55717D01*
X573125D01*
G01X583700Y62500D02*
Y72500D01*
G01X570300Y62500D02*
X583700D01*
G01X570300Y72500D02*
Y62500D01*
G01X561200Y67500D02*
Y77500D01*
G01X547800Y67500D02*
X561200D01*
G01X547800Y77500D02*
Y67500D01*
G01X596533Y83192D02*
X596783Y83317D01*
X597075Y83400D01*
X597408D01*
X597783Y83275D01*
X598075Y83067D01*
X598283Y82817D01*
X598450Y82400D01*
X598492Y82025D01*
X598408Y81650D01*
X598283Y81400D01*
X598033Y81150D01*
X597742Y80983D01*
X597450Y80900D01*
X597158D01*
X596867Y80983D01*
X596617Y81108D01*
X596408Y81275D01*
G01X595267D02*
X595017Y81067D01*
X594725Y80942D01*
X594350Y80900D01*
X593975Y80983D01*
X593683Y81150D01*
X593475Y81442D01*
X593433Y81775D01*
X593517Y82108D01*
X593725Y82317D01*
X594017Y82483D01*
X594308Y82525D01*
X594600Y82483D01*
X594975Y82317D01*
X594850Y83400D01*
X593725D01*
G01X592042Y82983D02*
X591792Y83233D01*
X591500Y83358D01*
X591167Y83400D01*
X590750Y83317D01*
X590458Y83108D01*
X590375Y82858D01*
X590417Y82608D01*
X590583Y82400D01*
X591417Y81983D01*
X591792Y81692D01*
X592042Y81275D01*
X592125Y80900D01*
X590375D01*
G01X589067Y81400D02*
X588817Y81108D01*
X588483Y80942D01*
X588108Y80900D01*
X587775Y80942D01*
X587442Y81150D01*
X587233Y81400D01*
X587192Y81650D01*
X587275Y81942D01*
X587567Y82150D01*
X587858Y82233D01*
X588233D01*
G01X587858D02*
X587608Y82358D01*
X587400Y82567D01*
X587317Y82817D01*
X587400Y83067D01*
X587608Y83275D01*
X587983Y83400D01*
X588358Y83358D01*
X588733Y83192D01*
G01X583700Y72500D02*
X570300D01*
G01X561200Y77500D02*
X547800D01*
G01X604417Y352600D02*
Y350808D01*
X604250Y350433D01*
X603917Y350183D01*
X603500Y350100D01*
X603083Y350183D01*
X602750Y350433D01*
X602583Y350808D01*
Y352600D01*
G01X599900Y350100D02*
Y352600D01*
X601442Y350808D01*
X599358D01*
G01X597300Y350100D02*
Y352600D01*
X597800Y352100D01*
G01Y350100D02*
X596800D01*
G01X595550Y367550D02*
Y370550D01*
X598550D01*
G01X595550Y359650D02*
Y356650D01*
X598550D01*
G01X601500Y369550D02*
Y371550D01*
G01X644792Y195767D02*
X644917Y195517D01*
X645000Y195225D01*
Y194892D01*
X644875Y194517D01*
X644667Y194225D01*
X644417Y194017D01*
X644000Y193850D01*
X643625Y193808D01*
X643250Y193892D01*
X643000Y194017D01*
X642750Y194267D01*
X642583Y194558D01*
X642500Y194850D01*
Y195142D01*
X642583Y195433D01*
X642708Y195683D01*
X642875Y195892D01*
G01X643000Y197033D02*
X642708Y197283D01*
X642542Y197617D01*
X642500Y197992D01*
X642542Y198325D01*
X642750Y198658D01*
X643000Y198867D01*
X643250Y198908D01*
X643542Y198825D01*
X643750Y198533D01*
X643833Y198242D01*
Y197867D01*
G01Y198242D02*
X643958Y198492D01*
X644167Y198700D01*
X644417Y198783D01*
X644667Y198700D01*
X644875Y198492D01*
X645000Y198117D01*
X644958Y197742D01*
X644792Y197367D01*
G01X644583Y200258D02*
X644833Y200508D01*
X644958Y200800D01*
X645000Y201133D01*
X644917Y201550D01*
X644708Y201842D01*
X644458Y201925D01*
X644208Y201883D01*
X644000Y201717D01*
X643583Y200883D01*
X643292Y200508D01*
X642875Y200258D01*
X642500Y200175D01*
Y201925D01*
G01X642792Y203442D02*
X642583Y203733D01*
X642500Y204067D01*
X642583Y204400D01*
X642833Y204692D01*
X643208Y204900D01*
X643583Y204983D01*
X644042D01*
X644417Y204900D01*
X644750Y204692D01*
X644917Y204442D01*
X645000Y204150D01*
X644917Y203817D01*
X644750Y203567D01*
X644500Y203400D01*
X644167Y203317D01*
X643875Y203400D01*
X643583Y203608D01*
X643417Y203858D01*
X643375Y204150D01*
X643458Y204483D01*
X643667Y204733D01*
X644042Y204983D01*
G01X628000Y175517D02*
X630500D01*
Y176558D01*
X630375Y176892D01*
X630208Y177100D01*
X629875Y177183D01*
X629542Y177100D01*
X629333Y176850D01*
X629208Y176558D01*
Y175517D01*
G01Y176558D02*
X628000Y177183D01*
G01Y179367D02*
X628542Y179450D01*
X629000Y179575D01*
X629417Y179742D01*
X629875Y179950D01*
X630500Y180283D01*
Y178617D01*
G01X628000Y183050D02*
X630500D01*
X628708Y181508D01*
Y183592D01*
G01X628000Y185650D02*
X628042Y185942D01*
X628167Y186275D01*
X628375Y186483D01*
X628667Y186567D01*
X628958Y186483D01*
X629208Y186233D01*
X629333Y185858D01*
Y185442D01*
X629417Y185192D01*
X629625Y184983D01*
X629917Y184900D01*
X630208Y185025D01*
X630417Y185317D01*
X630500Y185650D01*
X630417Y185983D01*
X630208Y186275D01*
X629917Y186400D01*
X629625Y186317D01*
X629417Y186108D01*
X629333Y185858D01*
Y185442D01*
X629208Y185067D01*
X628958Y184817D01*
X628667Y184733D01*
X628375Y184817D01*
X628167Y185025D01*
X628042Y185358D01*
X628000Y185650D01*
G01X627500Y196200D02*
X631500D01*
Y188800D01*
G01X632500Y176017D02*
X635000D01*
Y177058D01*
X634875Y177392D01*
X634708Y177600D01*
X634375Y177683D01*
X634042Y177600D01*
X633833Y177350D01*
X633708Y177058D01*
Y176017D01*
G01Y177058D02*
X632500Y177683D01*
G01Y179867D02*
X633042Y179950D01*
X633500Y180075D01*
X633917Y180242D01*
X634375Y180450D01*
X635000Y180783D01*
Y179117D01*
G01X632500Y183550D02*
X635000D01*
X633208Y182008D01*
Y184092D01*
G01X632500Y186067D02*
X633042Y186150D01*
X633500Y186275D01*
X633917Y186442D01*
X634375Y186650D01*
X635000Y186983D01*
Y185317D01*
G01X636000Y188800D02*
X632000D01*
Y196200D01*
G01X630359Y152567D02*
X630484Y152317D01*
X630567Y152025D01*
Y151692D01*
X630442Y151317D01*
X630234Y151025D01*
X629984Y150817D01*
X629567Y150650D01*
X629192Y150608D01*
X628817Y150692D01*
X628567Y150817D01*
X628317Y151067D01*
X628150Y151358D01*
X628067Y151650D01*
Y151942D01*
X628150Y152233D01*
X628275Y152483D01*
X628442Y152692D01*
G01Y153833D02*
X628234Y154083D01*
X628109Y154375D01*
X628067Y154750D01*
X628150Y155125D01*
X628317Y155417D01*
X628609Y155625D01*
X628942Y155667D01*
X629275Y155583D01*
X629484Y155375D01*
X629650Y155083D01*
X629692Y154792D01*
X629650Y154500D01*
X629484Y154125D01*
X630567Y154250D01*
Y155375D01*
G01Y157850D02*
X630484Y157517D01*
X630275Y157267D01*
X630025Y157100D01*
X629692Y156975D01*
X629317Y156933D01*
X628942Y156975D01*
X628609Y157100D01*
X628359Y157267D01*
X628150Y157517D01*
X628067Y157850D01*
X628150Y158183D01*
X628359Y158433D01*
X628609Y158600D01*
X628942Y158725D01*
X629317Y158767D01*
X629692Y158725D01*
X630025Y158600D01*
X630275Y158433D01*
X630484Y158183D01*
X630567Y157850D01*
G01X628067Y160950D02*
X630567D01*
X630067Y160450D01*
G01X628067D02*
Y161450D01*
G01X625859Y152567D02*
X625984Y152317D01*
X626067Y152025D01*
Y151692D01*
X625942Y151317D01*
X625734Y151025D01*
X625484Y150817D01*
X625067Y150650D01*
X624692Y150608D01*
X624317Y150692D01*
X624067Y150817D01*
X623817Y151067D01*
X623650Y151358D01*
X623567Y151650D01*
Y151942D01*
X623650Y152233D01*
X623775Y152483D01*
X623942Y152692D01*
G01Y153833D02*
X623734Y154083D01*
X623609Y154375D01*
X623567Y154750D01*
X623650Y155125D01*
X623817Y155417D01*
X624109Y155625D01*
X624442Y155667D01*
X624775Y155583D01*
X624984Y155375D01*
X625150Y155083D01*
X625192Y154792D01*
X625150Y154500D01*
X624984Y154125D01*
X626067Y154250D01*
Y155375D01*
G01Y157850D02*
X625984Y157517D01*
X625775Y157267D01*
X625525Y157100D01*
X625192Y156975D01*
X624817Y156933D01*
X624442Y156975D01*
X624109Y157100D01*
X623859Y157267D01*
X623650Y157517D01*
X623567Y157850D01*
X623650Y158183D01*
X623859Y158433D01*
X624109Y158600D01*
X624442Y158725D01*
X624817Y158767D01*
X625192Y158725D01*
X625525Y158600D01*
X625775Y158433D01*
X625984Y158183D01*
X626067Y157850D01*
G01Y160950D02*
X625984Y160617D01*
X625775Y160367D01*
X625525Y160200D01*
X625192Y160075D01*
X624817Y160033D01*
X624442Y160075D01*
X624109Y160200D01*
X623859Y160367D01*
X623650Y160617D01*
X623567Y160950D01*
X623650Y161283D01*
X623859Y161533D01*
X624109Y161700D01*
X624442Y161825D01*
X624817Y161867D01*
X625192Y161825D01*
X625525Y161700D01*
X625775Y161533D01*
X625984Y161283D01*
X626067Y160950D01*
G01X647859Y152067D02*
X647984Y151817D01*
X648067Y151525D01*
Y151192D01*
X647942Y150817D01*
X647734Y150525D01*
X647484Y150317D01*
X647067Y150150D01*
X646692Y150108D01*
X646317Y150192D01*
X646067Y150317D01*
X645817Y150567D01*
X645650Y150858D01*
X645567Y151150D01*
Y151442D01*
X645650Y151733D01*
X645775Y151983D01*
X645942Y152192D01*
G01X645567Y154750D02*
X648067D01*
X646275Y153208D01*
Y155292D01*
G01X645859Y156642D02*
X645650Y156933D01*
X645567Y157267D01*
X645650Y157600D01*
X645900Y157892D01*
X646275Y158100D01*
X646650Y158183D01*
X647109D01*
X647484Y158100D01*
X647817Y157892D01*
X647984Y157642D01*
X648067Y157350D01*
X647984Y157017D01*
X647817Y156767D01*
X647567Y156600D01*
X647234Y156517D01*
X646942Y156600D01*
X646650Y156808D01*
X646484Y157058D01*
X646442Y157350D01*
X646525Y157683D01*
X646734Y157933D01*
X647109Y158183D01*
G01X645567Y160367D02*
X646109Y160450D01*
X646567Y160575D01*
X646984Y160742D01*
X647442Y160950D01*
X648067Y161283D01*
Y159617D01*
G01X639359Y152067D02*
X639484Y151817D01*
X639567Y151525D01*
Y151192D01*
X639442Y150817D01*
X639234Y150525D01*
X638984Y150317D01*
X638567Y150150D01*
X638192Y150108D01*
X637817Y150192D01*
X637567Y150317D01*
X637317Y150567D01*
X637150Y150858D01*
X637067Y151150D01*
Y151442D01*
X637150Y151733D01*
X637275Y151983D01*
X637442Y152192D01*
G01X637067Y154750D02*
X639567D01*
X637775Y153208D01*
Y155292D01*
G01X637359Y156642D02*
X637150Y156933D01*
X637067Y157267D01*
X637150Y157600D01*
X637400Y157892D01*
X637775Y158100D01*
X638150Y158183D01*
X638609D01*
X638984Y158100D01*
X639317Y157892D01*
X639484Y157642D01*
X639567Y157350D01*
X639484Y157017D01*
X639317Y156767D01*
X639067Y156600D01*
X638734Y156517D01*
X638442Y156600D01*
X638150Y156808D01*
X637984Y157058D01*
X637942Y157350D01*
X638025Y157683D01*
X638234Y157933D01*
X638609Y158183D01*
G01X638109Y159658D02*
X638400Y159950D01*
X638567Y160200D01*
X638650Y160533D01*
X638567Y160825D01*
X638400Y161033D01*
X638150Y161200D01*
X637859Y161242D01*
X637609Y161200D01*
X637359Y161033D01*
X637150Y160783D01*
X637067Y160492D01*
X637150Y160158D01*
X637400Y159867D01*
X637775Y159700D01*
X638192Y159658D01*
X638734Y159742D01*
X639025Y159867D01*
X639317Y160075D01*
X639525Y160367D01*
X639567Y160658D01*
X639484Y160950D01*
X639275Y161158D01*
G01X634859Y152067D02*
X634984Y151817D01*
X635067Y151525D01*
Y151192D01*
X634942Y150817D01*
X634734Y150525D01*
X634484Y150317D01*
X634067Y150150D01*
X633692Y150108D01*
X633317Y150192D01*
X633067Y150317D01*
X632817Y150567D01*
X632650Y150858D01*
X632567Y151150D01*
Y151442D01*
X632650Y151733D01*
X632775Y151983D01*
X632942Y152192D01*
G01X632567Y154750D02*
X635067D01*
X633275Y153208D01*
Y155292D01*
G01X632859Y156642D02*
X632650Y156933D01*
X632567Y157267D01*
X632650Y157600D01*
X632900Y157892D01*
X633275Y158100D01*
X633650Y158183D01*
X634109D01*
X634484Y158100D01*
X634817Y157892D01*
X634984Y157642D01*
X635067Y157350D01*
X634984Y157017D01*
X634817Y156767D01*
X634567Y156600D01*
X634234Y156517D01*
X633942Y156600D01*
X633650Y156808D01*
X633484Y157058D01*
X633442Y157350D01*
X633525Y157683D01*
X633734Y157933D01*
X634109Y158183D01*
G01X632942Y159533D02*
X632734Y159783D01*
X632609Y160075D01*
X632567Y160450D01*
X632650Y160825D01*
X632817Y161117D01*
X633109Y161325D01*
X633442Y161367D01*
X633775Y161283D01*
X633984Y161075D01*
X634150Y160783D01*
X634192Y160492D01*
X634150Y160200D01*
X633984Y159825D01*
X635067Y159950D01*
Y161075D01*
G01X643359Y152067D02*
X643484Y151817D01*
X643567Y151525D01*
Y151192D01*
X643442Y150817D01*
X643234Y150525D01*
X642984Y150317D01*
X642567Y150150D01*
X642192Y150108D01*
X641817Y150192D01*
X641567Y150317D01*
X641317Y150567D01*
X641150Y150858D01*
X641067Y151150D01*
Y151442D01*
X641150Y151733D01*
X641275Y151983D01*
X641442Y152192D01*
G01X641067Y154750D02*
X643567D01*
X641775Y153208D01*
Y155292D01*
G01X641359Y156642D02*
X641150Y156933D01*
X641067Y157267D01*
X641150Y157600D01*
X641400Y157892D01*
X641775Y158100D01*
X642150Y158183D01*
X642609D01*
X642984Y158100D01*
X643317Y157892D01*
X643484Y157642D01*
X643567Y157350D01*
X643484Y157017D01*
X643317Y156767D01*
X643067Y156600D01*
X642734Y156517D01*
X642442Y156600D01*
X642150Y156808D01*
X641984Y157058D01*
X641942Y157350D01*
X642025Y157683D01*
X642234Y157933D01*
X642609Y158183D01*
G01X641067Y160950D02*
X643567D01*
X641775Y159408D01*
Y161492D01*
G01X621859Y152567D02*
X621984Y152317D01*
X622067Y152025D01*
Y151692D01*
X621942Y151317D01*
X621734Y151025D01*
X621484Y150817D01*
X621067Y150650D01*
X620692Y150608D01*
X620317Y150692D01*
X620067Y150817D01*
X619817Y151067D01*
X619650Y151358D01*
X619567Y151650D01*
Y151942D01*
X619650Y152233D01*
X619775Y152483D01*
X619942Y152692D01*
G01X619567Y155250D02*
X622067D01*
X620275Y153708D01*
Y155792D01*
G01X619859Y157142D02*
X619650Y157433D01*
X619567Y157767D01*
X619650Y158100D01*
X619900Y158392D01*
X620275Y158600D01*
X620650Y158683D01*
X621109D01*
X621484Y158600D01*
X621817Y158392D01*
X621984Y158142D01*
X622067Y157850D01*
X621984Y157517D01*
X621817Y157267D01*
X621567Y157100D01*
X621234Y157017D01*
X620942Y157100D01*
X620650Y157308D01*
X620484Y157558D01*
X620442Y157850D01*
X620525Y158183D01*
X620734Y158433D01*
X621109Y158683D01*
G01X619859Y160242D02*
X619650Y160533D01*
X619567Y160867D01*
X619650Y161200D01*
X619900Y161492D01*
X620275Y161700D01*
X620650Y161783D01*
X621109D01*
X621484Y161700D01*
X621817Y161492D01*
X621984Y161242D01*
X622067Y160950D01*
X621984Y160617D01*
X621817Y160367D01*
X621567Y160200D01*
X621234Y160117D01*
X620942Y160200D01*
X620650Y160408D01*
X620484Y160658D01*
X620442Y160950D01*
X620525Y161283D01*
X620734Y161533D01*
X621109Y161783D01*
G01X617859Y152567D02*
X617984Y152317D01*
X618067Y152025D01*
Y151692D01*
X617942Y151317D01*
X617734Y151025D01*
X617484Y150817D01*
X617067Y150650D01*
X616692Y150608D01*
X616317Y150692D01*
X616067Y150817D01*
X615817Y151067D01*
X615650Y151358D01*
X615567Y151650D01*
Y151942D01*
X615650Y152233D01*
X615775Y152483D01*
X615942Y152692D01*
G01X615567Y155250D02*
X618067D01*
X616275Y153708D01*
Y155792D01*
G01X615859Y157142D02*
X615650Y157433D01*
X615567Y157767D01*
X615650Y158100D01*
X615900Y158392D01*
X616275Y158600D01*
X616650Y158683D01*
X617109D01*
X617484Y158600D01*
X617817Y158392D01*
X617984Y158142D01*
X618067Y157850D01*
X617984Y157517D01*
X617817Y157267D01*
X617567Y157100D01*
X617234Y157017D01*
X616942Y157100D01*
X616650Y157308D01*
X616484Y157558D01*
X616442Y157850D01*
X616525Y158183D01*
X616734Y158433D01*
X617109Y158683D01*
G01X615567Y160950D02*
X615609Y161242D01*
X615734Y161575D01*
X615942Y161783D01*
X616234Y161867D01*
X616525Y161783D01*
X616775Y161533D01*
X616900Y161158D01*
Y160742D01*
X616984Y160492D01*
X617192Y160283D01*
X617484Y160200D01*
X617775Y160325D01*
X617984Y160617D01*
X618067Y160950D01*
X617984Y161283D01*
X617775Y161575D01*
X617484Y161700D01*
X617192Y161617D01*
X616984Y161408D01*
X616900Y161158D01*
Y160742D01*
X616775Y160367D01*
X616525Y160117D01*
X616234Y160033D01*
X615942Y160117D01*
X615734Y160325D01*
X615609Y160658D01*
X615567Y160950D01*
G01X615500Y233483D02*
X613708D01*
X613333Y233650D01*
X613083Y233983D01*
X613000Y234400D01*
X613083Y234817D01*
X613333Y235150D01*
X613708Y235317D01*
X615500D01*
G01X613000Y238000D02*
X615500D01*
X613708Y236458D01*
Y238542D01*
G01X615083Y239808D02*
X615333Y240058D01*
X615458Y240350D01*
X615500Y240683D01*
X615417Y241100D01*
X615208Y241392D01*
X614958Y241475D01*
X614708Y241433D01*
X614500Y241267D01*
X614083Y240433D01*
X613792Y240058D01*
X613375Y239808D01*
X613000Y239725D01*
Y241475D01*
G01X618900Y215400D02*
Y282800D01*
G01X675500Y215400D02*
X618900D01*
G01Y247400D02*
X620600Y249100D01*
G01D02*
X618900Y250800D01*
G01X642692Y293267D02*
X642817Y293017D01*
X642900Y292725D01*
Y292392D01*
X642775Y292017D01*
X642567Y291725D01*
X642317Y291517D01*
X641900Y291350D01*
X641525Y291308D01*
X641150Y291392D01*
X640900Y291517D01*
X640650Y291767D01*
X640483Y292058D01*
X640400Y292350D01*
Y292642D01*
X640483Y292933D01*
X640608Y293183D01*
X640775Y293392D01*
G01X640900Y294533D02*
X640608Y294783D01*
X640442Y295117D01*
X640400Y295492D01*
X640442Y295825D01*
X640650Y296158D01*
X640900Y296367D01*
X641150Y296408D01*
X641442Y296325D01*
X641650Y296033D01*
X641733Y295742D01*
Y295367D01*
G01Y295742D02*
X641858Y295992D01*
X642067Y296200D01*
X642317Y296283D01*
X642567Y296200D01*
X642775Y295992D01*
X642900Y295617D01*
X642858Y295242D01*
X642692Y294867D01*
G01X642483Y297758D02*
X642733Y298008D01*
X642858Y298300D01*
X642900Y298633D01*
X642817Y299050D01*
X642608Y299342D01*
X642358Y299425D01*
X642108Y299383D01*
X641900Y299217D01*
X641483Y298383D01*
X641192Y298008D01*
X640775Y297758D01*
X640400Y297675D01*
Y299425D01*
G01Y301650D02*
X640442Y301942D01*
X640567Y302275D01*
X640775Y302483D01*
X641067Y302567D01*
X641358Y302483D01*
X641608Y302233D01*
X641733Y301858D01*
Y301442D01*
X641817Y301192D01*
X642025Y300983D01*
X642317Y300900D01*
X642608Y301025D01*
X642817Y301317D01*
X642900Y301650D01*
X642817Y301983D01*
X642608Y302275D01*
X642317Y302400D01*
X642025Y302317D01*
X641817Y302108D01*
X641733Y301858D01*
Y301442D01*
X641608Y301067D01*
X641358Y300817D01*
X641067Y300733D01*
X640775Y300817D01*
X640567Y301025D01*
X640442Y301358D01*
X640400Y301650D01*
G01X675083Y294100D02*
Y296600D01*
X674042D01*
X673708Y296475D01*
X673500Y296308D01*
X673417Y295975D01*
X673500Y295642D01*
X673750Y295433D01*
X674042Y295308D01*
X675083D01*
G01X674042D02*
X673417Y294100D01*
G01X671942Y295142D02*
X671650Y295433D01*
X671400Y295600D01*
X671067Y295683D01*
X670775Y295600D01*
X670567Y295433D01*
X670400Y295183D01*
X670358Y294892D01*
X670400Y294642D01*
X670567Y294392D01*
X670817Y294183D01*
X671108Y294100D01*
X671442Y294183D01*
X671733Y294433D01*
X671900Y294808D01*
X671942Y295225D01*
X671858Y295767D01*
X671733Y296058D01*
X671525Y296350D01*
X671233Y296558D01*
X670942Y296600D01*
X670650Y296517D01*
X670442Y296308D01*
G01X668133Y294100D02*
X668050Y294642D01*
X667925Y295100D01*
X667758Y295517D01*
X667550Y295975D01*
X667217Y296600D01*
X668883D01*
G01X665742Y295142D02*
X665450Y295433D01*
X665200Y295600D01*
X664867Y295683D01*
X664575Y295600D01*
X664367Y295433D01*
X664200Y295183D01*
X664158Y294892D01*
X664200Y294642D01*
X664367Y294392D01*
X664617Y294183D01*
X664908Y294100D01*
X665242Y294183D01*
X665533Y294433D01*
X665700Y294808D01*
X665742Y295225D01*
X665658Y295767D01*
X665533Y296058D01*
X665325Y296350D01*
X665033Y296558D01*
X664742Y296600D01*
X664450Y296517D01*
X664242Y296308D01*
G01X654665Y303866D02*
X658665D01*
Y296466D01*
G01X644000Y293817D02*
X646500D01*
Y294858D01*
X646375Y295192D01*
X646208Y295400D01*
X645875Y295483D01*
X645542Y295400D01*
X645333Y295150D01*
X645208Y294858D01*
Y293817D01*
G01Y294858D02*
X644000Y295483D01*
G01X645042Y296958D02*
X645333Y297250D01*
X645500Y297500D01*
X645583Y297833D01*
X645500Y298125D01*
X645333Y298333D01*
X645083Y298500D01*
X644792Y298542D01*
X644542Y298500D01*
X644292Y298333D01*
X644083Y298083D01*
X644000Y297792D01*
X644083Y297458D01*
X644333Y297167D01*
X644708Y297000D01*
X645125Y296958D01*
X645667Y297042D01*
X645958Y297167D01*
X646250Y297375D01*
X646458Y297667D01*
X646500Y297958D01*
X646417Y298250D01*
X646208Y298458D01*
G01X644000Y300767D02*
X644542Y300850D01*
X645000Y300975D01*
X645417Y301142D01*
X645875Y301350D01*
X646500Y301683D01*
Y300017D01*
G01X644000Y303867D02*
X644542Y303950D01*
X645000Y304075D01*
X645417Y304242D01*
X645875Y304450D01*
X646500Y304783D01*
Y303117D01*
G01X650465Y303966D02*
X654465D01*
Y296566D01*
G01X670483Y311667D02*
Y314167D01*
X669442D01*
X669108Y314042D01*
X668900Y313875D01*
X668817Y313542D01*
X668900Y313209D01*
X669150Y313000D01*
X669442Y312875D01*
X670483D01*
G01X669442D02*
X668817Y311667D01*
G01X667342Y312709D02*
X667050Y313000D01*
X666800Y313167D01*
X666467Y313250D01*
X666175Y313167D01*
X665967Y313000D01*
X665800Y312750D01*
X665758Y312459D01*
X665800Y312209D01*
X665967Y311959D01*
X666217Y311750D01*
X666508Y311667D01*
X666842Y311750D01*
X667133Y312000D01*
X667300Y312375D01*
X667342Y312792D01*
X667258Y313334D01*
X667133Y313625D01*
X666925Y313917D01*
X666633Y314125D01*
X666342Y314167D01*
X666050Y314084D01*
X665842Y313875D01*
G01X663450Y311667D02*
X663158Y311709D01*
X662825Y311834D01*
X662617Y312042D01*
X662533Y312334D01*
X662617Y312625D01*
X662867Y312875D01*
X663242Y313000D01*
X663658D01*
X663908Y313084D01*
X664117Y313292D01*
X664200Y313584D01*
X664075Y313875D01*
X663783Y314084D01*
X663450Y314167D01*
X663117Y314084D01*
X662825Y313875D01*
X662700Y313584D01*
X662783Y313292D01*
X662992Y313084D01*
X663242Y313000D01*
X663658D01*
X664033Y312875D01*
X664283Y312625D01*
X664367Y312334D01*
X664283Y312042D01*
X664075Y311834D01*
X663742Y311709D01*
X663450Y311667D01*
G01X661142Y313750D02*
X660892Y314000D01*
X660600Y314125D01*
X660267Y314167D01*
X659850Y314084D01*
X659558Y313875D01*
X659475Y313625D01*
X659517Y313375D01*
X659683Y313167D01*
X660517Y312750D01*
X660892Y312459D01*
X661142Y312042D01*
X661225Y311667D01*
X659475D01*
G01X668000Y305400D02*
Y309400D01*
X675400D01*
G01X665933Y310167D02*
Y307667D01*
X664267D01*
G01X662000D02*
Y310167D01*
X662500Y309667D01*
G01Y307667D02*
X661500D01*
G01X659692Y308709D02*
X659400Y309000D01*
X659150Y309167D01*
X658817Y309250D01*
X658525Y309167D01*
X658317Y309000D01*
X658150Y308750D01*
X658108Y308459D01*
X658150Y308209D01*
X658317Y307959D01*
X658567Y307750D01*
X658858Y307667D01*
X659192Y307750D01*
X659483Y308000D01*
X659650Y308375D01*
X659692Y308792D01*
X659608Y309334D01*
X659483Y309625D01*
X659275Y309917D01*
X658983Y310125D01*
X658692Y310167D01*
X658400Y310084D01*
X658192Y309875D01*
G01X675100Y297800D02*
Y304800D01*
X661700D01*
Y297800D01*
X675100D01*
G01X618900Y282800D02*
X675500D01*
G01X670233Y397792D02*
X670483Y397917D01*
X670775Y398000D01*
X671108D01*
X671483Y397875D01*
X671775Y397667D01*
X671983Y397417D01*
X672150Y397000D01*
X672192Y396625D01*
X672108Y396250D01*
X671983Y396000D01*
X671733Y395750D01*
X671442Y395583D01*
X671150Y395500D01*
X670858D01*
X670567Y395583D01*
X670317Y395708D01*
X670108Y395875D01*
G01X667550Y395500D02*
Y398000D01*
X669092Y396208D01*
X667008D01*
G01X664450Y395500D02*
Y398000D01*
X665992Y396208D01*
X663908D01*
G01X661850Y395500D02*
X661558Y395542D01*
X661225Y395667D01*
X661017Y395875D01*
X660933Y396167D01*
X661017Y396458D01*
X661267Y396708D01*
X661642Y396833D01*
X662058D01*
X662308Y396917D01*
X662517Y397125D01*
X662600Y397417D01*
X662475Y397708D01*
X662183Y397917D01*
X661850Y398000D01*
X661517Y397917D01*
X661225Y397708D01*
X661100Y397417D01*
X661183Y397125D01*
X661392Y396917D01*
X661642Y396833D01*
X662058D01*
X662433Y396708D01*
X662683Y396458D01*
X662767Y396167D01*
X662683Y395875D01*
X662475Y395667D01*
X662142Y395542D01*
X661850Y395500D01*
G01X670233Y393792D02*
X670483Y393917D01*
X670775Y394000D01*
X671108D01*
X671483Y393875D01*
X671775Y393667D01*
X671983Y393417D01*
X672150Y393000D01*
X672192Y392625D01*
X672108Y392250D01*
X671983Y392000D01*
X671733Y391750D01*
X671442Y391583D01*
X671150Y391500D01*
X670858D01*
X670567Y391583D01*
X670317Y391708D01*
X670108Y391875D01*
G01X667550Y391500D02*
Y394000D01*
X669092Y392208D01*
X667008D01*
G01X664450Y391500D02*
Y394000D01*
X665992Y392208D01*
X663908D01*
G01X662558Y391792D02*
X662267Y391583D01*
X661933Y391500D01*
X661600Y391583D01*
X661308Y391833D01*
X661100Y392208D01*
X661017Y392583D01*
Y393042D01*
X661100Y393417D01*
X661308Y393750D01*
X661558Y393917D01*
X661850Y394000D01*
X662183Y393917D01*
X662433Y393750D01*
X662600Y393500D01*
X662683Y393167D01*
X662600Y392875D01*
X662392Y392583D01*
X662142Y392417D01*
X661850Y392375D01*
X661517Y392458D01*
X661267Y392667D01*
X661017Y393042D01*
G01X621733Y353892D02*
X621983Y354017D01*
X622275Y354100D01*
X622608D01*
X622983Y353975D01*
X623275Y353767D01*
X623483Y353517D01*
X623650Y353100D01*
X623692Y352725D01*
X623608Y352350D01*
X623483Y352100D01*
X623233Y351850D01*
X622942Y351683D01*
X622650Y351600D01*
X622358D01*
X622067Y351683D01*
X621817Y351808D01*
X621608Y351975D01*
G01X620467Y352100D02*
X620217Y351808D01*
X619883Y351642D01*
X619508Y351600D01*
X619175Y351642D01*
X618842Y351850D01*
X618633Y352100D01*
X618592Y352350D01*
X618675Y352642D01*
X618967Y352850D01*
X619258Y352933D01*
X619633D01*
G01X619258D02*
X619008Y353058D01*
X618800Y353267D01*
X618717Y353517D01*
X618800Y353767D01*
X619008Y353975D01*
X619383Y354100D01*
X619758Y354058D01*
X620133Y353892D01*
G01X617242Y353683D02*
X616992Y353933D01*
X616700Y354058D01*
X616367Y354100D01*
X615950Y354017D01*
X615658Y353808D01*
X615575Y353558D01*
X615617Y353308D01*
X615783Y353100D01*
X616617Y352683D01*
X616992Y352392D01*
X617242Y351975D01*
X617325Y351600D01*
X615575D01*
G01X613433D02*
X613350Y352142D01*
X613225Y352600D01*
X613058Y353017D01*
X612850Y353475D01*
X612517Y354100D01*
X614183D01*
G01X626983Y360167D02*
Y362667D01*
X625942D01*
X625608Y362542D01*
X625400Y362375D01*
X625317Y362042D01*
X625400Y361709D01*
X625650Y361500D01*
X625942Y361375D01*
X626983D01*
G01X625942D02*
X625317Y360167D01*
G01X623842Y361209D02*
X623550Y361500D01*
X623300Y361667D01*
X622967Y361750D01*
X622675Y361667D01*
X622467Y361500D01*
X622300Y361250D01*
X622258Y360959D01*
X622300Y360709D01*
X622467Y360459D01*
X622717Y360250D01*
X623008Y360167D01*
X623342Y360250D01*
X623633Y360500D01*
X623800Y360875D01*
X623842Y361292D01*
X623758Y361834D01*
X623633Y362125D01*
X623425Y362417D01*
X623133Y362625D01*
X622842Y362667D01*
X622550Y362584D01*
X622342Y362375D01*
G01X619950Y360167D02*
Y362667D01*
X620450Y362167D01*
G01Y360167D02*
X619450D01*
G01X617642Y361209D02*
X617350Y361500D01*
X617100Y361667D01*
X616767Y361750D01*
X616475Y361667D01*
X616267Y361500D01*
X616100Y361250D01*
X616058Y360959D01*
X616100Y360709D01*
X616267Y360459D01*
X616517Y360250D01*
X616808Y360167D01*
X617142Y360250D01*
X617433Y360500D01*
X617600Y360875D01*
X617642Y361292D01*
X617558Y361834D01*
X617433Y362125D01*
X617225Y362417D01*
X616933Y362625D01*
X616642Y362667D01*
X616350Y362584D01*
X616142Y362375D01*
G01X618686Y369271D02*
Y365271D01*
X611286D01*
G01X607450Y367550D02*
Y370550D01*
X604450D01*
G01X670233Y401792D02*
X670483Y401917D01*
X670775Y402000D01*
X671108D01*
X671483Y401875D01*
X671775Y401667D01*
X671983Y401417D01*
X672150Y401000D01*
X672192Y400625D01*
X672108Y400250D01*
X671983Y400000D01*
X671733Y399750D01*
X671442Y399583D01*
X671150Y399500D01*
X670858D01*
X670567Y399583D01*
X670317Y399708D01*
X670108Y399875D01*
G01X667550Y399500D02*
Y402000D01*
X669092Y400208D01*
X667008D01*
G01X664450Y399500D02*
Y402000D01*
X665992Y400208D01*
X663908D01*
G01X661933Y399500D02*
X661850Y400042D01*
X661725Y400500D01*
X661558Y400917D01*
X661350Y401375D01*
X661017Y402000D01*
X662683D01*
G01X670233Y405792D02*
X670483Y405917D01*
X670775Y406000D01*
X671108D01*
X671483Y405875D01*
X671775Y405667D01*
X671983Y405417D01*
X672150Y405000D01*
X672192Y404625D01*
X672108Y404250D01*
X671983Y404000D01*
X671733Y403750D01*
X671442Y403583D01*
X671150Y403500D01*
X670858D01*
X670567Y403583D01*
X670317Y403708D01*
X670108Y403875D01*
G01X667550Y403500D02*
Y406000D01*
X669092Y404208D01*
X667008D01*
G01X665867Y403875D02*
X665617Y403667D01*
X665325Y403542D01*
X664950Y403500D01*
X664575Y403583D01*
X664283Y403750D01*
X664075Y404042D01*
X664033Y404375D01*
X664117Y404708D01*
X664325Y404917D01*
X664617Y405083D01*
X664908Y405125D01*
X665200Y405083D01*
X665575Y404917D01*
X665450Y406000D01*
X664325D01*
G01X661933Y403500D02*
X661850Y404042D01*
X661725Y404500D01*
X661558Y404917D01*
X661350Y405375D01*
X661017Y406000D01*
X662683D01*
G01X647733Y480792D02*
X647983Y480917D01*
X648275Y481000D01*
X648608D01*
X648983Y480875D01*
X649275Y480667D01*
X649483Y480417D01*
X649650Y480000D01*
X649692Y479625D01*
X649608Y479250D01*
X649483Y479000D01*
X649233Y478750D01*
X648942Y478583D01*
X648650Y478500D01*
X648358D01*
X648067Y478583D01*
X647817Y478708D01*
X647608Y478875D01*
G01X646342Y480583D02*
X646092Y480833D01*
X645800Y480958D01*
X645467Y481000D01*
X645050Y480917D01*
X644758Y480708D01*
X644675Y480458D01*
X644717Y480208D01*
X644883Y480000D01*
X645717Y479583D01*
X646092Y479292D01*
X646342Y478875D01*
X646425Y478500D01*
X644675D01*
G01X642450D02*
Y481000D01*
X642950Y480500D01*
G01Y478500D02*
X641950D01*
G01X640142Y479542D02*
X639850Y479833D01*
X639600Y480000D01*
X639267Y480083D01*
X638975Y480000D01*
X638767Y479833D01*
X638600Y479583D01*
X638558Y479292D01*
X638600Y479042D01*
X638767Y478792D01*
X639017Y478583D01*
X639308Y478500D01*
X639642Y478583D01*
X639933Y478833D01*
X640100Y479208D01*
X640142Y479625D01*
X640058Y480167D01*
X639933Y480458D01*
X639725Y480750D01*
X639433Y480958D01*
X639142Y481000D01*
X638850Y480917D01*
X638642Y480708D01*
G01X647733Y476792D02*
X647983Y476917D01*
X648275Y477000D01*
X648608D01*
X648983Y476875D01*
X649275Y476667D01*
X649483Y476417D01*
X649650Y476000D01*
X649692Y475625D01*
X649608Y475250D01*
X649483Y475000D01*
X649233Y474750D01*
X648942Y474583D01*
X648650Y474500D01*
X648358D01*
X648067Y474583D01*
X647817Y474708D01*
X647608Y474875D01*
G01X646342Y476583D02*
X646092Y476833D01*
X645800Y476958D01*
X645467Y477000D01*
X645050Y476917D01*
X644758Y476708D01*
X644675Y476458D01*
X644717Y476208D01*
X644883Y476000D01*
X645717Y475583D01*
X646092Y475292D01*
X646342Y474875D01*
X646425Y474500D01*
X644675D01*
G01X642450D02*
Y477000D01*
X642950Y476500D01*
G01Y474500D02*
X641950D01*
G01X639350D02*
X639058Y474542D01*
X638725Y474667D01*
X638517Y474875D01*
X638433Y475167D01*
X638517Y475458D01*
X638767Y475708D01*
X639142Y475833D01*
X639558D01*
X639808Y475917D01*
X640017Y476125D01*
X640100Y476417D01*
X639975Y476708D01*
X639683Y476917D01*
X639350Y477000D01*
X639017Y476917D01*
X638725Y476708D01*
X638600Y476417D01*
X638683Y476125D01*
X638892Y475917D01*
X639142Y475833D01*
X639558D01*
X639933Y475708D01*
X640183Y475458D01*
X640267Y475167D01*
X640183Y474875D01*
X639975Y474667D01*
X639642Y474542D01*
X639350Y474500D01*
G01X645958Y539267D02*
X646083Y539017D01*
X646166Y538725D01*
Y538392D01*
X646041Y538017D01*
X645833Y537725D01*
X645583Y537517D01*
X645166Y537350D01*
X644791Y537308D01*
X644416Y537392D01*
X644166Y537517D01*
X643916Y537767D01*
X643749Y538058D01*
X643666Y538350D01*
Y538642D01*
X643749Y538933D01*
X643874Y539183D01*
X644041Y539392D01*
G01X645749Y540658D02*
X645999Y540908D01*
X646124Y541200D01*
X646166Y541533D01*
X646083Y541950D01*
X645874Y542242D01*
X645624Y542325D01*
X645374Y542283D01*
X645166Y542117D01*
X644749Y541283D01*
X644458Y540908D01*
X644041Y540658D01*
X643666Y540575D01*
Y542325D01*
G01Y544550D02*
X646166D01*
X645666Y544050D01*
G01X643666D02*
Y545050D01*
G01X645749Y546858D02*
X645999Y547108D01*
X646124Y547400D01*
X646166Y547733D01*
X646083Y548150D01*
X645874Y548442D01*
X645624Y548525D01*
X645374Y548483D01*
X645166Y548317D01*
X644749Y547483D01*
X644458Y547108D01*
X644041Y546858D01*
X643666Y546775D01*
Y548525D01*
G01X719759Y196667D02*
X719884Y196417D01*
X719967Y196125D01*
Y195792D01*
X719842Y195417D01*
X719634Y195125D01*
X719384Y194917D01*
X718967Y194750D01*
X718592Y194708D01*
X718217Y194792D01*
X717967Y194917D01*
X717717Y195167D01*
X717550Y195458D01*
X717467Y195750D01*
Y196042D01*
X717550Y196333D01*
X717675Y196583D01*
X717842Y196792D01*
G01X717467Y199350D02*
X719967D01*
X718175Y197808D01*
Y199892D01*
G01X717967Y201033D02*
X717675Y201283D01*
X717509Y201617D01*
X717467Y201992D01*
X717509Y202325D01*
X717717Y202658D01*
X717967Y202867D01*
X718217Y202908D01*
X718509Y202825D01*
X718717Y202533D01*
X718800Y202242D01*
Y201867D01*
G01Y202242D02*
X718925Y202492D01*
X719134Y202700D01*
X719384Y202783D01*
X719634Y202700D01*
X719842Y202492D01*
X719967Y202117D01*
X719925Y201742D01*
X719759Y201367D01*
G01X717467Y205550D02*
X719967D01*
X718175Y204008D01*
Y206092D01*
G01X723759Y196367D02*
X723884Y196117D01*
X723967Y195825D01*
Y195492D01*
X723842Y195117D01*
X723634Y194825D01*
X723384Y194617D01*
X722967Y194450D01*
X722592Y194408D01*
X722217Y194492D01*
X721967Y194617D01*
X721717Y194867D01*
X721550Y195158D01*
X721467Y195450D01*
Y195742D01*
X721550Y196033D01*
X721675Y196283D01*
X721842Y196492D01*
G01X721467Y199050D02*
X723967D01*
X722175Y197508D01*
Y199592D01*
G01X721842Y200733D02*
X721634Y200983D01*
X721509Y201275D01*
X721467Y201650D01*
X721550Y202025D01*
X721717Y202317D01*
X722009Y202525D01*
X722342Y202567D01*
X722675Y202483D01*
X722884Y202275D01*
X723050Y201983D01*
X723092Y201692D01*
X723050Y201400D01*
X722884Y201025D01*
X723967Y201150D01*
Y202275D01*
G01X721759Y204042D02*
X721550Y204333D01*
X721467Y204667D01*
X721550Y205000D01*
X721800Y205292D01*
X722175Y205500D01*
X722550Y205583D01*
X723009D01*
X723384Y205500D01*
X723717Y205292D01*
X723884Y205042D01*
X723967Y204750D01*
X723884Y204417D01*
X723717Y204167D01*
X723467Y204000D01*
X723134Y203917D01*
X722842Y204000D01*
X722550Y204208D01*
X722384Y204458D01*
X722342Y204750D01*
X722425Y205083D01*
X722634Y205333D01*
X723009Y205583D01*
G01X714959Y196867D02*
X715084Y196617D01*
X715167Y196325D01*
Y195992D01*
X715042Y195617D01*
X714834Y195325D01*
X714584Y195117D01*
X714167Y194950D01*
X713792Y194908D01*
X713417Y194992D01*
X713167Y195117D01*
X712917Y195367D01*
X712750Y195658D01*
X712667Y195950D01*
Y196242D01*
X712750Y196533D01*
X712875Y196783D01*
X713042Y196992D01*
G01X712667Y199550D02*
X715167D01*
X713375Y198008D01*
Y200092D01*
G01X713709Y201358D02*
X714000Y201650D01*
X714167Y201900D01*
X714250Y202233D01*
X714167Y202525D01*
X714000Y202733D01*
X713750Y202900D01*
X713459Y202942D01*
X713209Y202900D01*
X712959Y202733D01*
X712750Y202483D01*
X712667Y202192D01*
X712750Y201858D01*
X713000Y201567D01*
X713375Y201400D01*
X713792Y201358D01*
X714334Y201442D01*
X714625Y201567D01*
X714917Y201775D01*
X715125Y202067D01*
X715167Y202358D01*
X715084Y202650D01*
X714875Y202858D01*
G01X715167Y205250D02*
X715084Y204917D01*
X714875Y204667D01*
X714625Y204500D01*
X714292Y204375D01*
X713917Y204333D01*
X713542Y204375D01*
X713209Y204500D01*
X712959Y204667D01*
X712750Y204917D01*
X712667Y205250D01*
X712750Y205583D01*
X712959Y205833D01*
X713209Y206000D01*
X713542Y206125D01*
X713917Y206167D01*
X714292Y206125D01*
X714625Y206000D01*
X714875Y205833D01*
X715084Y205583D01*
X715167Y205250D01*
G01X701983Y191567D02*
Y194067D01*
X700942D01*
X700608Y193942D01*
X700400Y193775D01*
X700317Y193442D01*
X700400Y193109D01*
X700650Y192900D01*
X700942Y192775D01*
X701983D01*
G01X700942D02*
X700317Y191567D01*
G01X698842Y192609D02*
X698550Y192900D01*
X698300Y193067D01*
X697967Y193150D01*
X697675Y193067D01*
X697467Y192900D01*
X697300Y192650D01*
X697258Y192359D01*
X697300Y192109D01*
X697467Y191859D01*
X697717Y191650D01*
X698008Y191567D01*
X698342Y191650D01*
X698633Y191900D01*
X698800Y192275D01*
X698842Y192692D01*
X698758Y193234D01*
X698633Y193525D01*
X698425Y193817D01*
X698133Y194025D01*
X697842Y194067D01*
X697550Y193984D01*
X697342Y193775D01*
G01X695742Y192609D02*
X695450Y192900D01*
X695200Y193067D01*
X694867Y193150D01*
X694575Y193067D01*
X694367Y192900D01*
X694200Y192650D01*
X694158Y192359D01*
X694200Y192109D01*
X694367Y191859D01*
X694617Y191650D01*
X694908Y191567D01*
X695242Y191650D01*
X695533Y191900D01*
X695700Y192275D01*
X695742Y192692D01*
X695658Y193234D01*
X695533Y193525D01*
X695325Y193817D01*
X695033Y194025D01*
X694742Y194067D01*
X694450Y193984D01*
X694242Y193775D01*
G01X692642Y192609D02*
X692350Y192900D01*
X692100Y193067D01*
X691767Y193150D01*
X691475Y193067D01*
X691267Y192900D01*
X691100Y192650D01*
X691058Y192359D01*
X691100Y192109D01*
X691267Y191859D01*
X691517Y191650D01*
X691808Y191567D01*
X692142Y191650D01*
X692433Y191900D01*
X692600Y192275D01*
X692642Y192692D01*
X692558Y193234D01*
X692433Y193525D01*
X692225Y193817D01*
X691933Y194025D01*
X691642Y194067D01*
X691350Y193984D01*
X691142Y193775D01*
G01X675667Y193517D02*
X678167D01*
Y194558D01*
X678042Y194892D01*
X677875Y195100D01*
X677542Y195183D01*
X677209Y195100D01*
X677000Y194850D01*
X676875Y194558D01*
Y193517D01*
G01Y194558D02*
X675667Y195183D01*
G01X676709Y196658D02*
X677000Y196950D01*
X677167Y197200D01*
X677250Y197533D01*
X677167Y197825D01*
X677000Y198033D01*
X676750Y198200D01*
X676459Y198242D01*
X676209Y198200D01*
X675959Y198033D01*
X675750Y197783D01*
X675667Y197492D01*
X675750Y197158D01*
X676000Y196867D01*
X676375Y196700D01*
X676792Y196658D01*
X677334Y196742D01*
X677625Y196867D01*
X677917Y197075D01*
X678125Y197367D01*
X678167Y197658D01*
X678084Y197950D01*
X677875Y198158D01*
G01X675667Y200467D02*
X676209Y200550D01*
X676667Y200675D01*
X677084Y200842D01*
X677542Y201050D01*
X678167Y201383D01*
Y199717D01*
G01X675667Y203650D02*
X675709Y203942D01*
X675834Y204275D01*
X676042Y204483D01*
X676334Y204567D01*
X676625Y204483D01*
X676875Y204233D01*
X677000Y203858D01*
Y203442D01*
X677084Y203192D01*
X677292Y202983D01*
X677584Y202900D01*
X677875Y203025D01*
X678084Y203317D01*
X678167Y203650D01*
X678084Y203983D01*
X677875Y204275D01*
X677584Y204400D01*
X677292Y204317D01*
X677084Y204108D01*
X677000Y203858D01*
Y203442D01*
X676875Y203067D01*
X676625Y202817D01*
X676334Y202733D01*
X676042Y202817D01*
X675834Y203025D01*
X675709Y203358D01*
X675667Y203650D01*
G01X672200Y197900D02*
X668200D01*
Y205300D01*
G01X723566Y180217D02*
X726066D01*
Y181258D01*
X725941Y181592D01*
X725774Y181800D01*
X725441Y181883D01*
X725108Y181800D01*
X724899Y181550D01*
X724774Y181258D01*
Y180217D01*
G01Y181258D02*
X723566Y181883D01*
G01Y184067D02*
X724108Y184150D01*
X724566Y184275D01*
X724983Y184442D01*
X725441Y184650D01*
X726066Y184983D01*
Y183317D01*
G01X724608Y186458D02*
X724899Y186750D01*
X725066Y187000D01*
X725149Y187333D01*
X725066Y187625D01*
X724899Y187833D01*
X724649Y188000D01*
X724358Y188042D01*
X724108Y188000D01*
X723858Y187833D01*
X723649Y187583D01*
X723566Y187292D01*
X723649Y186958D01*
X723899Y186667D01*
X724274Y186500D01*
X724691Y186458D01*
X725233Y186542D01*
X725524Y186667D01*
X725816Y186875D01*
X726024Y187167D01*
X726066Y187458D01*
X725983Y187750D01*
X725774Y187958D01*
G01X723566Y190267D02*
X724108Y190350D01*
X724566Y190475D01*
X724983Y190642D01*
X725441Y190850D01*
X726066Y191183D01*
Y189517D01*
G01X732900Y189300D02*
X728900D01*
Y196700D01*
G01X710300Y197867D02*
Y195367D01*
G01X711258Y197867D02*
X709342D01*
G01X708033Y195367D02*
Y197867D01*
X707033D01*
X706700Y197742D01*
X706450Y197450D01*
X706367Y197117D01*
X706450Y196784D01*
X706658Y196534D01*
X707033Y196409D01*
X708033D01*
G01X704100Y195367D02*
Y197867D01*
X704600Y197367D01*
G01Y195367D02*
X703600D01*
G01X701917Y195742D02*
X701667Y195534D01*
X701375Y195409D01*
X701000Y195367D01*
X700625Y195450D01*
X700333Y195617D01*
X700125Y195909D01*
X700083Y196242D01*
X700167Y196575D01*
X700375Y196784D01*
X700667Y196950D01*
X700958Y196992D01*
X701250Y196950D01*
X701625Y196784D01*
X701500Y197867D01*
X700375D01*
G01X697900D02*
X698233Y197784D01*
X698483Y197575D01*
X698650Y197325D01*
X698775Y196992D01*
X698817Y196617D01*
X698775Y196242D01*
X698650Y195909D01*
X698483Y195659D01*
X698233Y195450D01*
X697900Y195367D01*
X697567Y195450D01*
X697317Y195659D01*
X697150Y195909D01*
X697025Y196242D01*
X696983Y196617D01*
X697025Y196992D01*
X697150Y197325D01*
X697317Y197575D01*
X697567Y197784D01*
X697900Y197867D01*
G01X710400Y201967D02*
Y199467D01*
G01X711358Y201967D02*
X709442D01*
G01X708133Y199467D02*
Y201967D01*
X707133D01*
X706800Y201842D01*
X706550Y201550D01*
X706467Y201217D01*
X706550Y200884D01*
X706758Y200634D01*
X707133Y200509D01*
X708133D01*
G01X704200Y199467D02*
Y201967D01*
X704700Y201467D01*
G01Y199467D02*
X703700D01*
G01X702017Y199842D02*
X701767Y199634D01*
X701475Y199509D01*
X701100Y199467D01*
X700725Y199550D01*
X700433Y199717D01*
X700225Y200009D01*
X700183Y200342D01*
X700267Y200675D01*
X700475Y200884D01*
X700767Y201050D01*
X701058Y201092D01*
X701350Y201050D01*
X701725Y200884D01*
X701600Y201967D01*
X700475D01*
G01X698917Y199967D02*
X698667Y199675D01*
X698333Y199509D01*
X697958Y199467D01*
X697625Y199509D01*
X697292Y199717D01*
X697083Y199967D01*
X697042Y200217D01*
X697125Y200509D01*
X697417Y200717D01*
X697708Y200800D01*
X698083D01*
G01X697708D02*
X697458Y200925D01*
X697250Y201134D01*
X697167Y201384D01*
X697250Y201634D01*
X697458Y201842D01*
X697833Y201967D01*
X698208Y201925D01*
X698583Y201759D01*
G01X688597Y198540D02*
X686097D01*
G01X688597Y197582D02*
Y199498D01*
G01X686097Y200807D02*
X688597D01*
Y201807D01*
X688472Y202140D01*
X688180Y202390D01*
X687847Y202473D01*
X687514Y202390D01*
X687264Y202182D01*
X687139Y201807D01*
Y200807D01*
G01X686097Y204740D02*
X688597D01*
X688097Y204240D01*
G01X686097D02*
Y205240D01*
G01X687139Y207048D02*
X687430Y207340D01*
X687597Y207590D01*
X687680Y207923D01*
X687597Y208215D01*
X687430Y208423D01*
X687180Y208590D01*
X686889Y208632D01*
X686639Y208590D01*
X686389Y208423D01*
X686180Y208173D01*
X686097Y207882D01*
X686180Y207548D01*
X686430Y207257D01*
X686805Y207090D01*
X687222Y207048D01*
X687764Y207132D01*
X688055Y207257D01*
X688347Y207465D01*
X688555Y207757D01*
X688597Y208048D01*
X688514Y208340D01*
X688305Y208548D01*
G01X687139Y210148D02*
X687430Y210440D01*
X687597Y210690D01*
X687680Y211023D01*
X687597Y211315D01*
X687430Y211523D01*
X687180Y211690D01*
X686889Y211732D01*
X686639Y211690D01*
X686389Y211523D01*
X686180Y211273D01*
X686097Y210982D01*
X686180Y210648D01*
X686430Y210357D01*
X686805Y210190D01*
X687222Y210148D01*
X687764Y210232D01*
X688055Y210357D01*
X688347Y210565D01*
X688555Y210857D01*
X688597Y211148D01*
X688514Y211440D01*
X688305Y211648D01*
G01X683777Y190050D02*
X681277D01*
G01X683777Y189092D02*
Y191008D01*
G01X681277Y192317D02*
X683777D01*
Y193317D01*
X683652Y193650D01*
X683360Y193900D01*
X683027Y193983D01*
X682694Y193900D01*
X682444Y193692D01*
X682319Y193317D01*
Y192317D01*
G01X681277Y196250D02*
X683777D01*
X683277Y195750D01*
G01X681277D02*
Y196750D01*
G01X682319Y198558D02*
X682610Y198850D01*
X682777Y199100D01*
X682860Y199433D01*
X682777Y199725D01*
X682610Y199933D01*
X682360Y200100D01*
X682069Y200142D01*
X681819Y200100D01*
X681569Y199933D01*
X681360Y199683D01*
X681277Y199392D01*
X681360Y199058D01*
X681610Y198767D01*
X681985Y198600D01*
X682402Y198558D01*
X682944Y198642D01*
X683235Y198767D01*
X683527Y198975D01*
X683735Y199267D01*
X683777Y199558D01*
X683694Y199850D01*
X683485Y200058D01*
G01X681277Y202367D02*
X681819Y202450D01*
X682277Y202575D01*
X682694Y202742D01*
X683152Y202950D01*
X683777Y203283D01*
Y201617D01*
G01X708167Y179300D02*
X705667D01*
G01X708167Y178342D02*
Y180258D01*
G01X705667Y181567D02*
X708167D01*
Y182567D01*
X708042Y182900D01*
X707750Y183150D01*
X707417Y183233D01*
X707084Y183150D01*
X706834Y182942D01*
X706709Y182567D01*
Y181567D01*
G01X705667Y185500D02*
X708167D01*
X707667Y185000D01*
G01X705667D02*
Y186000D01*
G01X706709Y187808D02*
X707000Y188100D01*
X707167Y188350D01*
X707250Y188683D01*
X707167Y188975D01*
X707000Y189183D01*
X706750Y189350D01*
X706459Y189392D01*
X706209Y189350D01*
X705959Y189183D01*
X705750Y188933D01*
X705667Y188642D01*
X705750Y188308D01*
X706000Y188017D01*
X706375Y187850D01*
X706792Y187808D01*
X707334Y187892D01*
X707625Y188017D01*
X707917Y188225D01*
X708125Y188517D01*
X708167Y188808D01*
X708084Y189100D01*
X707875Y189308D01*
G01X705959Y190992D02*
X705750Y191283D01*
X705667Y191617D01*
X705750Y191950D01*
X706000Y192242D01*
X706375Y192450D01*
X706750Y192533D01*
X707209D01*
X707584Y192450D01*
X707917Y192242D01*
X708084Y191992D01*
X708167Y191700D01*
X708084Y191367D01*
X707917Y191117D01*
X707667Y190950D01*
X707334Y190867D01*
X707042Y190950D01*
X706750Y191158D01*
X706584Y191408D01*
X706542Y191700D01*
X706625Y192033D01*
X706834Y192283D01*
X707209Y192533D01*
G01X744483Y178667D02*
Y181167D01*
X743442D01*
X743108Y181042D01*
X742900Y180875D01*
X742817Y180542D01*
X742900Y180209D01*
X743150Y180000D01*
X743442Y179875D01*
X744483D01*
G01X743442D02*
X742817Y178667D01*
G01X741342Y179709D02*
X741050Y180000D01*
X740800Y180167D01*
X740467Y180250D01*
X740175Y180167D01*
X739967Y180000D01*
X739800Y179750D01*
X739758Y179459D01*
X739800Y179209D01*
X739967Y178959D01*
X740217Y178750D01*
X740508Y178667D01*
X740842Y178750D01*
X741133Y179000D01*
X741300Y179375D01*
X741342Y179792D01*
X741258Y180334D01*
X741133Y180625D01*
X740925Y180917D01*
X740633Y181125D01*
X740342Y181167D01*
X740050Y181084D01*
X739842Y180875D01*
G01X737533Y178667D02*
X737450Y179209D01*
X737325Y179667D01*
X737158Y180084D01*
X736950Y180542D01*
X736617Y181167D01*
X738283D01*
G01X735058Y178959D02*
X734767Y178750D01*
X734433Y178667D01*
X734100Y178750D01*
X733808Y179000D01*
X733600Y179375D01*
X733517Y179750D01*
Y180209D01*
X733600Y180584D01*
X733808Y180917D01*
X734058Y181084D01*
X734350Y181167D01*
X734683Y181084D01*
X734933Y180917D01*
X735100Y180667D01*
X735183Y180334D01*
X735100Y180042D01*
X734892Y179750D01*
X734642Y179584D01*
X734350Y179542D01*
X734017Y179625D01*
X733767Y179834D01*
X733517Y180209D01*
G01X740233Y199459D02*
X740483Y199584D01*
X740775Y199667D01*
X741108D01*
X741483Y199542D01*
X741775Y199334D01*
X741983Y199084D01*
X742150Y198667D01*
X742192Y198292D01*
X742108Y197917D01*
X741983Y197667D01*
X741733Y197417D01*
X741442Y197250D01*
X741150Y197167D01*
X740858D01*
X740567Y197250D01*
X740317Y197375D01*
X740108Y197542D01*
G01X738967Y197667D02*
X738717Y197375D01*
X738383Y197209D01*
X738008Y197167D01*
X737675Y197209D01*
X737342Y197417D01*
X737133Y197667D01*
X737092Y197917D01*
X737175Y198209D01*
X737467Y198417D01*
X737758Y198500D01*
X738133D01*
G01X737758D02*
X737508Y198625D01*
X737300Y198834D01*
X737217Y199084D01*
X737300Y199334D01*
X737508Y199542D01*
X737883Y199667D01*
X738258Y199625D01*
X738633Y199459D01*
G01X735867Y197667D02*
X735617Y197375D01*
X735283Y197209D01*
X734908Y197167D01*
X734575Y197209D01*
X734242Y197417D01*
X734033Y197667D01*
X733992Y197917D01*
X734075Y198209D01*
X734367Y198417D01*
X734658Y198500D01*
X735033D01*
G01X734658D02*
X734408Y198625D01*
X734200Y198834D01*
X734117Y199084D01*
X734200Y199334D01*
X734408Y199542D01*
X734783Y199667D01*
X735158Y199625D01*
X735533Y199459D01*
G01X732767Y197667D02*
X732517Y197375D01*
X732183Y197209D01*
X731808Y197167D01*
X731475Y197209D01*
X731142Y197417D01*
X730933Y197667D01*
X730892Y197917D01*
X730975Y198209D01*
X731267Y198417D01*
X731558Y198500D01*
X731933D01*
G01X731558D02*
X731308Y198625D01*
X731100Y198834D01*
X731017Y199084D01*
X731100Y199334D01*
X731308Y199542D01*
X731683Y199667D01*
X732058Y199625D01*
X732433Y199459D01*
G01X766000Y222500D02*
Y230500D01*
X785000D01*
Y246000D01*
X788500D01*
Y250500D01*
X792500D01*
Y288500D01*
X773600D01*
Y284000D01*
X767300D01*
Y289900D01*
X751800D01*
Y302900D01*
X744000D01*
Y309600D01*
X740300D01*
Y313400D01*
X735100D01*
Y304500D01*
X730000D01*
Y309700D01*
X729300D01*
Y328500D01*
X687350D01*
Y315400D01*
X691000D01*
Y310000D01*
X693500D01*
Y304500D01*
X698200D01*
Y302500D01*
X700000D01*
Y285500D01*
X712100Y273400D01*
X719200D01*
X720500Y272100D01*
Y222500D01*
X766000D01*
Y216000D01*
X771600D01*
Y199400D01*
G01X695259Y206167D02*
X695384Y205917D01*
X695467Y205625D01*
Y205292D01*
X695342Y204917D01*
X695134Y204625D01*
X694884Y204417D01*
X694467Y204250D01*
X694092Y204208D01*
X693717Y204292D01*
X693467Y204417D01*
X693217Y204667D01*
X693050Y204958D01*
X692967Y205250D01*
Y205542D01*
X693050Y205833D01*
X693175Y206083D01*
X693342Y206292D01*
G01X692967Y208850D02*
X695467D01*
X693675Y207308D01*
Y209392D01*
G01X693467Y210533D02*
X693175Y210783D01*
X693009Y211117D01*
X692967Y211492D01*
X693009Y211825D01*
X693217Y212158D01*
X693467Y212367D01*
X693717Y212408D01*
X694009Y212325D01*
X694217Y212033D01*
X694300Y211742D01*
Y211367D01*
G01Y211742D02*
X694425Y211992D01*
X694634Y212200D01*
X694884Y212283D01*
X695134Y212200D01*
X695342Y211992D01*
X695467Y211617D01*
X695425Y211242D01*
X695259Y210867D01*
G01X695050Y213758D02*
X695300Y214008D01*
X695425Y214300D01*
X695467Y214633D01*
X695384Y215050D01*
X695175Y215342D01*
X694925Y215425D01*
X694675Y215383D01*
X694467Y215217D01*
X694050Y214383D01*
X693759Y214008D01*
X693342Y213758D01*
X692967Y213675D01*
Y215425D01*
G01X699059Y205967D02*
X699184Y205717D01*
X699267Y205425D01*
Y205092D01*
X699142Y204717D01*
X698934Y204425D01*
X698684Y204217D01*
X698267Y204050D01*
X697892Y204008D01*
X697517Y204092D01*
X697267Y204217D01*
X697017Y204467D01*
X696850Y204758D01*
X696767Y205050D01*
Y205342D01*
X696850Y205633D01*
X696975Y205883D01*
X697142Y206092D01*
G01X696767Y208650D02*
X699267D01*
X697475Y207108D01*
Y209192D01*
G01X697267Y210333D02*
X696975Y210583D01*
X696809Y210917D01*
X696767Y211292D01*
X696809Y211625D01*
X697017Y211958D01*
X697267Y212167D01*
X697517Y212208D01*
X697809Y212125D01*
X698017Y211833D01*
X698100Y211542D01*
Y211167D01*
G01Y211542D02*
X698225Y211792D01*
X698434Y212000D01*
X698684Y212083D01*
X698934Y212000D01*
X699142Y211792D01*
X699267Y211417D01*
X699225Y211042D01*
X699059Y210667D01*
G01X697267Y213433D02*
X696975Y213683D01*
X696809Y214017D01*
X696767Y214392D01*
X696809Y214725D01*
X697017Y215058D01*
X697267Y215267D01*
X697517Y215308D01*
X697809Y215225D01*
X698017Y214933D01*
X698100Y214642D01*
Y214267D01*
G01Y214642D02*
X698225Y214892D01*
X698434Y215100D01*
X698684Y215183D01*
X698934Y215100D01*
X699142Y214892D01*
X699267Y214517D01*
X699225Y214142D01*
X699059Y213767D01*
G01X689683Y257467D02*
Y259967D01*
X688642D01*
X688308Y259842D01*
X688100Y259675D01*
X688017Y259342D01*
X688100Y259009D01*
X688350Y258800D01*
X688642Y258675D01*
X689683D01*
G01X688642D02*
X688017Y257467D01*
G01X686667Y257842D02*
X686417Y257634D01*
X686125Y257509D01*
X685750Y257467D01*
X685375Y257550D01*
X685083Y257717D01*
X684875Y258009D01*
X684833Y258342D01*
X684917Y258675D01*
X685125Y258884D01*
X685417Y259050D01*
X685708Y259092D01*
X686000Y259050D01*
X686375Y258884D01*
X686250Y259967D01*
X685125D01*
G01X682650Y257467D02*
X682358Y257509D01*
X682025Y257634D01*
X681817Y257842D01*
X681733Y258134D01*
X681817Y258425D01*
X682067Y258675D01*
X682442Y258800D01*
X682858D01*
X683108Y258884D01*
X683317Y259092D01*
X683400Y259384D01*
X683275Y259675D01*
X682983Y259884D01*
X682650Y259967D01*
X682317Y259884D01*
X682025Y259675D01*
X681900Y259384D01*
X681983Y259092D01*
X682192Y258884D01*
X682442Y258800D01*
X682858D01*
X683233Y258675D01*
X683483Y258425D01*
X683567Y258134D01*
X683483Y257842D01*
X683275Y257634D01*
X682942Y257509D01*
X682650Y257467D01*
G01X680467Y257967D02*
X680217Y257675D01*
X679883Y257509D01*
X679508Y257467D01*
X679175Y257509D01*
X678842Y257717D01*
X678633Y257967D01*
X678592Y258217D01*
X678675Y258509D01*
X678967Y258717D01*
X679258Y258800D01*
X679633D01*
G01X679258D02*
X679008Y258925D01*
X678800Y259134D01*
X678717Y259384D01*
X678800Y259634D01*
X679008Y259842D01*
X679383Y259967D01*
X679758Y259925D01*
X680133Y259759D01*
G01X704233Y246917D02*
Y249417D01*
X703192D01*
X702858Y249292D01*
X702650Y249125D01*
X702567Y248792D01*
X702650Y248459D01*
X702900Y248250D01*
X703192Y248125D01*
X704233D01*
G01X703192D02*
X702567Y246917D01*
G01X701217Y247292D02*
X700967Y247084D01*
X700675Y246959D01*
X700300Y246917D01*
X699925Y247000D01*
X699633Y247167D01*
X699425Y247459D01*
X699383Y247792D01*
X699467Y248125D01*
X699675Y248334D01*
X699967Y248500D01*
X700258Y248542D01*
X700550Y248500D01*
X700925Y248334D01*
X700800Y249417D01*
X699675D01*
G01X697200Y246917D02*
X696908Y246959D01*
X696575Y247084D01*
X696367Y247292D01*
X696283Y247584D01*
X696367Y247875D01*
X696617Y248125D01*
X696992Y248250D01*
X697408D01*
X697658Y248334D01*
X697867Y248542D01*
X697950Y248834D01*
X697825Y249125D01*
X697533Y249334D01*
X697200Y249417D01*
X696867Y249334D01*
X696575Y249125D01*
X696450Y248834D01*
X696533Y248542D01*
X696742Y248334D01*
X696992Y248250D01*
X697408D01*
X697783Y248125D01*
X698033Y247875D01*
X698117Y247584D01*
X698033Y247292D01*
X697825Y247084D01*
X697492Y246959D01*
X697200Y246917D01*
G01X693600D02*
Y249417D01*
X695142Y247625D01*
X693058D01*
G01X708373Y251883D02*
Y255883D01*
X715773D01*
G01X701983Y252967D02*
Y255467D01*
X700942D01*
X700608Y255342D01*
X700400Y255175D01*
X700317Y254842D01*
X700400Y254509D01*
X700650Y254300D01*
X700942Y254175D01*
X701983D01*
G01X700942D02*
X700317Y252967D01*
G01X698967Y253342D02*
X698717Y253134D01*
X698425Y253009D01*
X698050Y252967D01*
X697675Y253050D01*
X697383Y253217D01*
X697175Y253509D01*
X697133Y253842D01*
X697217Y254175D01*
X697425Y254384D01*
X697717Y254550D01*
X698008Y254592D01*
X698300Y254550D01*
X698675Y254384D01*
X698550Y255467D01*
X697425D01*
G01X695033Y252967D02*
X694950Y253509D01*
X694825Y253967D01*
X694658Y254384D01*
X694450Y254842D01*
X694117Y255467D01*
X695783D01*
G01X692767Y253342D02*
X692517Y253134D01*
X692225Y253009D01*
X691850Y252967D01*
X691475Y253050D01*
X691183Y253217D01*
X690975Y253509D01*
X690933Y253842D01*
X691017Y254175D01*
X691225Y254384D01*
X691517Y254550D01*
X691808Y254592D01*
X692100Y254550D01*
X692475Y254384D01*
X692350Y255467D01*
X691225D01*
G01X706979Y255964D02*
Y259964D01*
X714379D01*
G01X703383Y257267D02*
Y259767D01*
X702342D01*
X702008Y259642D01*
X701800Y259475D01*
X701717Y259142D01*
X701800Y258809D01*
X702050Y258600D01*
X702342Y258475D01*
X703383D01*
G01X702342D02*
X701717Y257267D01*
G01X700367Y257642D02*
X700117Y257434D01*
X699825Y257309D01*
X699450Y257267D01*
X699075Y257350D01*
X698783Y257517D01*
X698575Y257809D01*
X698533Y258142D01*
X698617Y258475D01*
X698825Y258684D01*
X699117Y258850D01*
X699408Y258892D01*
X699700Y258850D01*
X700075Y258684D01*
X699950Y259767D01*
X698825D01*
G01X696433Y257267D02*
X696350Y257809D01*
X696225Y258267D01*
X696058Y258684D01*
X695850Y259142D01*
X695517Y259767D01*
X697183D01*
G01X694167Y257767D02*
X693917Y257475D01*
X693583Y257309D01*
X693208Y257267D01*
X692875Y257309D01*
X692542Y257517D01*
X692333Y257767D01*
X692292Y258017D01*
X692375Y258309D01*
X692667Y258517D01*
X692958Y258600D01*
X693333D01*
G01X692958D02*
X692708Y258725D01*
X692500Y258934D01*
X692417Y259184D01*
X692500Y259434D01*
X692708Y259642D01*
X693083Y259767D01*
X693458Y259725D01*
X693833Y259559D01*
G01X713052Y263999D02*
Y259999D01*
X705652D01*
G01X689733Y253817D02*
Y256317D01*
X688692D01*
X688358Y256192D01*
X688150Y256025D01*
X688067Y255692D01*
X688150Y255359D01*
X688400Y255150D01*
X688692Y255025D01*
X689733D01*
G01X688692D02*
X688067Y253817D01*
G01X686717Y254192D02*
X686467Y253984D01*
X686175Y253859D01*
X685800Y253817D01*
X685425Y253900D01*
X685133Y254067D01*
X684925Y254359D01*
X684883Y254692D01*
X684967Y255025D01*
X685175Y255234D01*
X685467Y255400D01*
X685758Y255442D01*
X686050Y255400D01*
X686425Y255234D01*
X686300Y256317D01*
X685175D01*
G01X682783Y253817D02*
X682700Y254359D01*
X682575Y254817D01*
X682408Y255234D01*
X682200Y255692D01*
X681867Y256317D01*
X683533D01*
G01X679683Y253817D02*
X679600Y254359D01*
X679475Y254817D01*
X679308Y255234D01*
X679100Y255692D01*
X678767Y256317D01*
X680433D01*
G01X683600Y263100D02*
Y267100D01*
X691000D01*
G01X705200Y265000D02*
Y262500D01*
G01X706158Y265000D02*
X704242D01*
G01X702933Y262500D02*
Y265000D01*
X701933D01*
X701600Y264875D01*
X701350Y264583D01*
X701267Y264250D01*
X701350Y263917D01*
X701558Y263667D01*
X701933Y263542D01*
X702933D01*
G01X699000Y262500D02*
Y265000D01*
X699500Y264500D01*
G01Y262500D02*
X698500D01*
G01X696692Y264583D02*
X696442Y264833D01*
X696150Y264958D01*
X695817Y265000D01*
X695400Y264917D01*
X695108Y264708D01*
X695025Y264458D01*
X695067Y264208D01*
X695233Y264000D01*
X696067Y263583D01*
X696442Y263292D01*
X696692Y262875D01*
X696775Y262500D01*
X695025D01*
G01X692800D02*
X692508Y262542D01*
X692175Y262667D01*
X691967Y262875D01*
X691883Y263167D01*
X691967Y263458D01*
X692217Y263708D01*
X692592Y263833D01*
X693008D01*
X693258Y263917D01*
X693467Y264125D01*
X693550Y264417D01*
X693425Y264708D01*
X693133Y264917D01*
X692800Y265000D01*
X692467Y264917D01*
X692175Y264708D01*
X692050Y264417D01*
X692133Y264125D01*
X692342Y263917D01*
X692592Y263833D01*
X693008D01*
X693383Y263708D01*
X693633Y263458D01*
X693717Y263167D01*
X693633Y262875D01*
X693425Y262667D01*
X693092Y262542D01*
X692800Y262500D01*
G01X680017Y262400D02*
X677517D01*
G01X680017Y261442D02*
Y263358D01*
G01X677517Y264667D02*
X680017D01*
Y265667D01*
X679892Y266000D01*
X679600Y266250D01*
X679267Y266333D01*
X678934Y266250D01*
X678684Y266042D01*
X678559Y265667D01*
Y264667D01*
G01X677517Y268600D02*
X680017D01*
X679517Y268100D01*
G01X677517D02*
Y269100D01*
G01X680017Y271700D02*
X679934Y271367D01*
X679725Y271117D01*
X679475Y270950D01*
X679142Y270825D01*
X678767Y270783D01*
X678392Y270825D01*
X678059Y270950D01*
X677809Y271117D01*
X677600Y271367D01*
X677517Y271700D01*
X677600Y272033D01*
X677809Y272283D01*
X678059Y272450D01*
X678392Y272575D01*
X678767Y272617D01*
X679142Y272575D01*
X679475Y272450D01*
X679725Y272283D01*
X679934Y272033D01*
X680017Y271700D01*
G01X677809Y274092D02*
X677600Y274383D01*
X677517Y274717D01*
X677600Y275050D01*
X677850Y275342D01*
X678225Y275550D01*
X678600Y275633D01*
X679059D01*
X679434Y275550D01*
X679767Y275342D01*
X679934Y275092D01*
X680017Y274800D01*
X679934Y274467D01*
X679767Y274217D01*
X679517Y274050D01*
X679184Y273967D01*
X678892Y274050D01*
X678600Y274258D01*
X678434Y274508D01*
X678392Y274800D01*
X678475Y275133D01*
X678684Y275383D01*
X679059Y275633D01*
G01X705550Y245267D02*
Y242767D01*
G01X706508Y245267D02*
X704592D01*
G01X703283Y242767D02*
Y245267D01*
X702283D01*
X701950Y245142D01*
X701700Y244850D01*
X701617Y244517D01*
X701700Y244184D01*
X701908Y243934D01*
X702283Y243809D01*
X703283D01*
G01X699350Y242767D02*
Y245267D01*
X699850Y244767D01*
G01Y242767D02*
X698850D01*
G01X697042Y244850D02*
X696792Y245100D01*
X696500Y245225D01*
X696167Y245267D01*
X695750Y245184D01*
X695458Y244975D01*
X695375Y244725D01*
X695417Y244475D01*
X695583Y244267D01*
X696417Y243850D01*
X696792Y243559D01*
X697042Y243142D01*
X697125Y242767D01*
X695375D01*
G01X694067Y243267D02*
X693817Y242975D01*
X693483Y242809D01*
X693108Y242767D01*
X692775Y242809D01*
X692442Y243017D01*
X692233Y243267D01*
X692192Y243517D01*
X692275Y243809D01*
X692567Y244017D01*
X692858Y244100D01*
X693233D01*
G01X692858D02*
X692608Y244225D01*
X692400Y244434D01*
X692317Y244684D01*
X692400Y244934D01*
X692608Y245142D01*
X692983Y245267D01*
X693358Y245225D01*
X693733Y245059D01*
G01X707900Y240067D02*
Y237567D01*
G01X708858Y240067D02*
X706942D01*
G01X705633Y237567D02*
Y240067D01*
X704633D01*
X704300Y239942D01*
X704050Y239650D01*
X703967Y239317D01*
X704050Y238984D01*
X704258Y238734D01*
X704633Y238609D01*
X705633D01*
G01X701700Y237567D02*
Y240067D01*
X702200Y239567D01*
G01Y237567D02*
X701200D01*
G01X699392Y238609D02*
X699100Y238900D01*
X698850Y239067D01*
X698517Y239150D01*
X698225Y239067D01*
X698017Y238900D01*
X697850Y238650D01*
X697808Y238359D01*
X697850Y238109D01*
X698017Y237859D01*
X698267Y237650D01*
X698558Y237567D01*
X698892Y237650D01*
X699183Y237900D01*
X699350Y238275D01*
X699392Y238692D01*
X699308Y239234D01*
X699183Y239525D01*
X698975Y239817D01*
X698683Y240025D01*
X698392Y240067D01*
X698100Y239984D01*
X697892Y239775D01*
G01X696417Y238067D02*
X696167Y237775D01*
X695833Y237609D01*
X695458Y237567D01*
X695125Y237609D01*
X694792Y237817D01*
X694583Y238067D01*
X694542Y238317D01*
X694625Y238609D01*
X694917Y238817D01*
X695208Y238900D01*
X695583D01*
G01X695208D02*
X694958Y239025D01*
X694750Y239234D01*
X694667Y239484D01*
X694750Y239734D01*
X694958Y239942D01*
X695333Y240067D01*
X695708Y240025D01*
X696083Y239859D01*
G01X705500Y234167D02*
Y231667D01*
G01X706458Y234167D02*
X704542D01*
G01X703233Y231667D02*
Y234167D01*
X702233D01*
X701900Y234042D01*
X701650Y233750D01*
X701567Y233417D01*
X701650Y233084D01*
X701858Y232834D01*
X702233Y232709D01*
X703233D01*
G01X699300Y231667D02*
Y234167D01*
X699800Y233667D01*
G01Y231667D02*
X698800D01*
G01X696992Y232709D02*
X696700Y233000D01*
X696450Y233167D01*
X696117Y233250D01*
X695825Y233167D01*
X695617Y233000D01*
X695450Y232750D01*
X695408Y232459D01*
X695450Y232209D01*
X695617Y231959D01*
X695867Y231750D01*
X696158Y231667D01*
X696492Y231750D01*
X696783Y232000D01*
X696950Y232375D01*
X696992Y232792D01*
X696908Y233334D01*
X696783Y233625D01*
X696575Y233917D01*
X696283Y234125D01*
X695992Y234167D01*
X695700Y234084D01*
X695492Y233875D01*
G01X692600Y231667D02*
Y234167D01*
X694142Y232375D01*
X692058D01*
G01X675500Y282800D02*
Y215400D01*
G01X708333Y288900D02*
X705000Y295900D01*
X701667Y288900D01*
G01X702867Y291350D02*
X707133D01*
G01X673959Y312267D02*
X674084Y312017D01*
X674167Y311725D01*
Y311392D01*
X674042Y311017D01*
X673834Y310725D01*
X673584Y310517D01*
X673167Y310350D01*
X672792Y310308D01*
X672417Y310392D01*
X672167Y310517D01*
X671917Y310767D01*
X671750Y311058D01*
X671667Y311350D01*
Y311642D01*
X671750Y311933D01*
X671875Y312183D01*
X672042Y312392D01*
G01X672167Y313533D02*
X671875Y313783D01*
X671709Y314117D01*
X671667Y314492D01*
X671709Y314825D01*
X671917Y315158D01*
X672167Y315367D01*
X672417Y315408D01*
X672709Y315325D01*
X672917Y315033D01*
X673000Y314742D01*
Y314367D01*
G01Y314742D02*
X673125Y314992D01*
X673334Y315200D01*
X673584Y315283D01*
X673834Y315200D01*
X674042Y314992D01*
X674167Y314617D01*
X674125Y314242D01*
X673959Y313867D01*
G01X671667Y318050D02*
X674167D01*
X672375Y316508D01*
Y318592D01*
G01X672167Y319733D02*
X671875Y319983D01*
X671709Y320317D01*
X671667Y320692D01*
X671709Y321025D01*
X671917Y321358D01*
X672167Y321567D01*
X672417Y321608D01*
X672709Y321525D01*
X672917Y321233D01*
X673000Y320942D01*
Y320567D01*
G01Y320942D02*
X673125Y321192D01*
X673334Y321400D01*
X673584Y321483D01*
X673834Y321400D01*
X674042Y321192D01*
X674167Y320817D01*
X674125Y320442D01*
X673959Y320067D01*
G01X723130Y285930D02*
Y289930D01*
X730530D01*
G01X733967Y315217D02*
X736467D01*
Y316258D01*
X736342Y316592D01*
X736175Y316800D01*
X735842Y316883D01*
X735509Y316800D01*
X735300Y316550D01*
X735175Y316258D01*
Y315217D01*
G01Y316258D02*
X733967Y316883D01*
G01X735009Y318358D02*
X735300Y318650D01*
X735467Y318900D01*
X735550Y319233D01*
X735467Y319525D01*
X735300Y319733D01*
X735050Y319900D01*
X734759Y319942D01*
X734509Y319900D01*
X734259Y319733D01*
X734050Y319483D01*
X733967Y319192D01*
X734050Y318858D01*
X734300Y318567D01*
X734675Y318400D01*
X735092Y318358D01*
X735634Y318442D01*
X735925Y318567D01*
X736217Y318775D01*
X736425Y319067D01*
X736467Y319358D01*
X736384Y319650D01*
X736175Y319858D01*
G01X736050Y321458D02*
X736300Y321708D01*
X736425Y322000D01*
X736467Y322333D01*
X736384Y322750D01*
X736175Y323042D01*
X735925Y323125D01*
X735675Y323083D01*
X735467Y322917D01*
X735050Y322083D01*
X734759Y321708D01*
X734342Y321458D01*
X733967Y321375D01*
Y323125D01*
G01X736467Y325350D02*
X736384Y325017D01*
X736175Y324767D01*
X735925Y324600D01*
X735592Y324475D01*
X735217Y324433D01*
X734842Y324475D01*
X734509Y324600D01*
X734259Y324767D01*
X734050Y325017D01*
X733967Y325350D01*
X734050Y325683D01*
X734259Y325933D01*
X734509Y326100D01*
X734842Y326225D01*
X735217Y326267D01*
X735592Y326225D01*
X735925Y326100D01*
X736175Y325933D01*
X736384Y325683D01*
X736467Y325350D01*
G01X730230Y313269D02*
X734230D01*
Y305869D01*
G01X683600Y267200D02*
Y271200D01*
X691000D01*
G01X694100Y295800D02*
Y293300D01*
G01X695058Y295800D02*
X693142D01*
G01X691833Y293300D02*
Y295800D01*
X690833D01*
X690500Y295675D01*
X690250Y295383D01*
X690167Y295050D01*
X690250Y294717D01*
X690458Y294467D01*
X690833Y294342D01*
X691833D01*
G01X687900Y293300D02*
Y295800D01*
X688400Y295300D01*
G01Y293300D02*
X687400D01*
G01X684800D02*
Y295800D01*
X685300Y295300D01*
G01Y293300D02*
X684300D01*
G01X682408Y293592D02*
X682117Y293383D01*
X681783Y293300D01*
X681450Y293383D01*
X681158Y293633D01*
X680950Y294008D01*
X680867Y294383D01*
Y294842D01*
X680950Y295217D01*
X681158Y295550D01*
X681408Y295717D01*
X681700Y295800D01*
X682033Y295717D01*
X682283Y295550D01*
X682450Y295300D01*
X682533Y294967D01*
X682450Y294675D01*
X682242Y294383D01*
X681992Y294217D01*
X681700Y294175D01*
X681367Y294258D01*
X681117Y294467D01*
X680867Y294842D01*
G01X690350Y279267D02*
Y276767D01*
G01X691308Y279267D02*
X689392D01*
G01X688083Y276767D02*
Y279267D01*
X687083D01*
X686750Y279142D01*
X686500Y278850D01*
X686417Y278517D01*
X686500Y278184D01*
X686708Y277934D01*
X687083Y277809D01*
X688083D01*
G01X684150Y276767D02*
Y279267D01*
X684650Y278767D01*
G01Y276767D02*
X683650D01*
G01X681842Y278850D02*
X681592Y279100D01*
X681300Y279225D01*
X680967Y279267D01*
X680550Y279184D01*
X680258Y278975D01*
X680175Y278725D01*
X680217Y278475D01*
X680383Y278267D01*
X681217Y277850D01*
X681592Y277559D01*
X681842Y277142D01*
X681925Y276767D01*
X680175D01*
G01X678867Y277142D02*
X678617Y276934D01*
X678325Y276809D01*
X677950Y276767D01*
X677575Y276850D01*
X677283Y277017D01*
X677075Y277309D01*
X677033Y277642D01*
X677117Y277975D01*
X677325Y278184D01*
X677617Y278350D01*
X677908Y278392D01*
X678200Y278350D01*
X678575Y278184D01*
X678450Y279267D01*
X677325D01*
G01X690500Y282867D02*
Y280367D01*
G01X691458Y282867D02*
X689542D01*
G01X688233Y280367D02*
Y282867D01*
X687233D01*
X686900Y282742D01*
X686650Y282450D01*
X686567Y282117D01*
X686650Y281784D01*
X686858Y281534D01*
X687233Y281409D01*
X688233D01*
G01X684300Y280367D02*
Y282867D01*
X684800Y282367D01*
G01Y280367D02*
X683800D01*
G01X681992Y281409D02*
X681700Y281700D01*
X681450Y281867D01*
X681117Y281950D01*
X680825Y281867D01*
X680617Y281700D01*
X680450Y281450D01*
X680408Y281159D01*
X680450Y280909D01*
X680617Y280659D01*
X680867Y280450D01*
X681158Y280367D01*
X681492Y280450D01*
X681783Y280700D01*
X681950Y281075D01*
X681992Y281492D01*
X681908Y282034D01*
X681783Y282325D01*
X681575Y282617D01*
X681283Y282825D01*
X680992Y282867D01*
X680700Y282784D01*
X680492Y282575D01*
G01X678100Y282867D02*
X678433Y282784D01*
X678683Y282575D01*
X678850Y282325D01*
X678975Y281992D01*
X679017Y281617D01*
X678975Y281242D01*
X678850Y280909D01*
X678683Y280659D01*
X678433Y280450D01*
X678100Y280367D01*
X677767Y280450D01*
X677517Y280659D01*
X677350Y280909D01*
X677225Y281242D01*
X677183Y281617D01*
X677225Y281992D01*
X677350Y282325D01*
X677517Y282575D01*
X677767Y282784D01*
X678100Y282867D01*
G01X696450Y275667D02*
Y273167D01*
G01X697408Y275667D02*
X695492D01*
G01X694183Y273167D02*
Y275667D01*
X693183D01*
X692850Y275542D01*
X692600Y275250D01*
X692517Y274917D01*
X692600Y274584D01*
X692808Y274334D01*
X693183Y274209D01*
X694183D01*
G01X690250Y273167D02*
Y275667D01*
X690750Y275167D01*
G01Y273167D02*
X689750D01*
G01X687150Y275667D02*
X687483Y275584D01*
X687733Y275375D01*
X687900Y275125D01*
X688025Y274792D01*
X688067Y274417D01*
X688025Y274042D01*
X687900Y273709D01*
X687733Y273459D01*
X687483Y273250D01*
X687150Y273167D01*
X686817Y273250D01*
X686567Y273459D01*
X686400Y273709D01*
X686275Y274042D01*
X686233Y274417D01*
X686275Y274792D01*
X686400Y275125D01*
X686567Y275375D01*
X686817Y275584D01*
X687150Y275667D01*
G01X684050D02*
X684383Y275584D01*
X684633Y275375D01*
X684800Y275125D01*
X684925Y274792D01*
X684967Y274417D01*
X684925Y274042D01*
X684800Y273709D01*
X684633Y273459D01*
X684383Y273250D01*
X684050Y273167D01*
X683717Y273250D01*
X683467Y273459D01*
X683300Y273709D01*
X683175Y274042D01*
X683133Y274417D01*
X683175Y274792D01*
X683300Y275125D01*
X683467Y275375D01*
X683717Y275584D01*
X684050Y275667D01*
G01X691100Y286667D02*
Y284167D01*
G01X692058Y286667D02*
X690142D01*
G01X688833Y284167D02*
Y286667D01*
X687833D01*
X687500Y286542D01*
X687250Y286250D01*
X687167Y285917D01*
X687250Y285584D01*
X687458Y285334D01*
X687833Y285209D01*
X688833D01*
G01X684900Y284167D02*
Y286667D01*
X685400Y286167D01*
G01Y284167D02*
X684400D01*
G01X681800Y286667D02*
X682133Y286584D01*
X682383Y286375D01*
X682550Y286125D01*
X682675Y285792D01*
X682717Y285417D01*
X682675Y285042D01*
X682550Y284709D01*
X682383Y284459D01*
X682133Y284250D01*
X681800Y284167D01*
X681467Y284250D01*
X681217Y284459D01*
X681050Y284709D01*
X680925Y285042D01*
X680883Y285417D01*
X680925Y285792D01*
X681050Y286125D01*
X681217Y286375D01*
X681467Y286584D01*
X681800Y286667D01*
G01X678700Y284167D02*
X678408Y284209D01*
X678075Y284334D01*
X677867Y284542D01*
X677783Y284834D01*
X677867Y285125D01*
X678117Y285375D01*
X678492Y285500D01*
X678908D01*
X679158Y285584D01*
X679367Y285792D01*
X679450Y286084D01*
X679325Y286375D01*
X679033Y286584D01*
X678700Y286667D01*
X678367Y286584D01*
X678075Y286375D01*
X677950Y286084D01*
X678033Y285792D01*
X678242Y285584D01*
X678492Y285500D01*
X678908D01*
X679283Y285375D01*
X679533Y285125D01*
X679617Y284834D01*
X679533Y284542D01*
X679325Y284334D01*
X678992Y284209D01*
X678700Y284167D01*
G01X681959Y315767D02*
X682084Y315517D01*
X682167Y315225D01*
Y314892D01*
X682042Y314517D01*
X681834Y314225D01*
X681584Y314017D01*
X681167Y313850D01*
X680792Y313808D01*
X680417Y313892D01*
X680167Y314017D01*
X679917Y314267D01*
X679750Y314558D01*
X679667Y314850D01*
Y315142D01*
X679750Y315433D01*
X679875Y315683D01*
X680042Y315892D01*
G01X680167Y317033D02*
X679875Y317283D01*
X679709Y317617D01*
X679667Y317992D01*
X679709Y318325D01*
X679917Y318658D01*
X680167Y318867D01*
X680417Y318908D01*
X680709Y318825D01*
X680917Y318533D01*
X681000Y318242D01*
Y317867D01*
G01Y318242D02*
X681125Y318492D01*
X681334Y318700D01*
X681584Y318783D01*
X681834Y318700D01*
X682042Y318492D01*
X682167Y318117D01*
X682125Y317742D01*
X681959Y317367D01*
G01X679667Y321550D02*
X682167D01*
X680375Y320008D01*
Y322092D01*
G01X680042Y323233D02*
X679834Y323483D01*
X679709Y323775D01*
X679667Y324150D01*
X679750Y324525D01*
X679917Y324817D01*
X680209Y325025D01*
X680542Y325067D01*
X680875Y324983D01*
X681084Y324775D01*
X681250Y324483D01*
X681292Y324192D01*
X681250Y323900D01*
X681084Y323525D01*
X682167Y323650D01*
Y324775D01*
G01X695925Y327494D02*
Y321994D01*
G01X703925Y327494D02*
X695925D01*
G01X703925Y321994D02*
Y327494D01*
G01Y309894D02*
Y315394D01*
G01X695925Y309894D02*
X703925D01*
G01X695925Y315394D02*
Y309894D01*
G01X677959Y315767D02*
X678084Y315517D01*
X678167Y315225D01*
Y314892D01*
X678042Y314517D01*
X677834Y314225D01*
X677584Y314017D01*
X677167Y313850D01*
X676792Y313808D01*
X676417Y313892D01*
X676167Y314017D01*
X675917Y314267D01*
X675750Y314558D01*
X675667Y314850D01*
Y315142D01*
X675750Y315433D01*
X675875Y315683D01*
X676042Y315892D01*
G01X676167Y317033D02*
X675875Y317283D01*
X675709Y317617D01*
X675667Y317992D01*
X675709Y318325D01*
X675917Y318658D01*
X676167Y318867D01*
X676417Y318908D01*
X676709Y318825D01*
X676917Y318533D01*
X677000Y318242D01*
Y317867D01*
G01Y318242D02*
X677125Y318492D01*
X677334Y318700D01*
X677584Y318783D01*
X677834Y318700D01*
X678042Y318492D01*
X678167Y318117D01*
X678125Y317742D01*
X677959Y317367D01*
G01X675667Y321550D02*
X678167D01*
X676375Y320008D01*
Y322092D01*
G01X677750Y323358D02*
X678000Y323608D01*
X678125Y323900D01*
X678167Y324233D01*
X678084Y324650D01*
X677875Y324942D01*
X677625Y325025D01*
X677375Y324983D01*
X677167Y324817D01*
X676750Y323983D01*
X676459Y323608D01*
X676042Y323358D01*
X675667Y323275D01*
Y325025D01*
G01X716280Y327340D02*
X709280D01*
Y313940D01*
X716280D01*
Y327340D01*
G01X685959Y315767D02*
X686084Y315517D01*
X686167Y315225D01*
Y314892D01*
X686042Y314517D01*
X685834Y314225D01*
X685584Y314017D01*
X685167Y313850D01*
X684792Y313808D01*
X684417Y313892D01*
X684167Y314017D01*
X683917Y314267D01*
X683750Y314558D01*
X683667Y314850D01*
Y315142D01*
X683750Y315433D01*
X683875Y315683D01*
X684042Y315892D01*
G01X684167Y317033D02*
X683875Y317283D01*
X683709Y317617D01*
X683667Y317992D01*
X683709Y318325D01*
X683917Y318658D01*
X684167Y318867D01*
X684417Y318908D01*
X684709Y318825D01*
X684917Y318533D01*
X685000Y318242D01*
Y317867D01*
G01Y318242D02*
X685125Y318492D01*
X685334Y318700D01*
X685584Y318783D01*
X685834Y318700D01*
X686042Y318492D01*
X686167Y318117D01*
X686125Y317742D01*
X685959Y317367D01*
G01X683667Y321550D02*
X686167D01*
X684375Y320008D01*
Y322092D01*
G01X683667Y324650D02*
X686167D01*
X684375Y323108D01*
Y325192D01*
G01X728833Y450492D02*
X729083Y450617D01*
X729375Y450700D01*
X729708D01*
X730083Y450575D01*
X730375Y450367D01*
X730583Y450117D01*
X730750Y449700D01*
X730792Y449325D01*
X730708Y448950D01*
X730583Y448700D01*
X730333Y448450D01*
X730042Y448283D01*
X729750Y448200D01*
X729458D01*
X729167Y448283D01*
X728917Y448408D01*
X728708Y448575D01*
G01X727442Y450283D02*
X727192Y450533D01*
X726900Y450658D01*
X726567Y450700D01*
X726150Y450617D01*
X725858Y450408D01*
X725775Y450158D01*
X725817Y449908D01*
X725983Y449700D01*
X726817Y449283D01*
X727192Y448992D01*
X727442Y448575D01*
X727525Y448200D01*
X725775D01*
G01X723633D02*
X723550Y448742D01*
X723425Y449200D01*
X723258Y449617D01*
X723050Y450075D01*
X722717Y450700D01*
X724383D01*
G01X721367Y448700D02*
X721117Y448408D01*
X720783Y448242D01*
X720408Y448200D01*
X720075Y448242D01*
X719742Y448450D01*
X719533Y448700D01*
X719492Y448950D01*
X719575Y449242D01*
X719867Y449450D01*
X720158Y449533D01*
X720533D01*
G01X720158D02*
X719908Y449658D01*
X719700Y449867D01*
X719617Y450117D01*
X719700Y450367D01*
X719908Y450575D01*
X720283Y450700D01*
X720658Y450658D01*
X721033Y450492D01*
G01X728733Y445459D02*
X728983Y445584D01*
X729275Y445667D01*
X729608D01*
X729983Y445542D01*
X730275Y445334D01*
X730483Y445084D01*
X730650Y444667D01*
X730692Y444292D01*
X730608Y443917D01*
X730483Y443667D01*
X730233Y443417D01*
X729942Y443250D01*
X729650Y443167D01*
X729358D01*
X729067Y443250D01*
X728817Y443375D01*
X728608Y443542D01*
G01X727342Y445250D02*
X727092Y445500D01*
X726800Y445625D01*
X726467Y445667D01*
X726050Y445584D01*
X725758Y445375D01*
X725675Y445125D01*
X725717Y444875D01*
X725883Y444667D01*
X726717Y444250D01*
X727092Y443959D01*
X727342Y443542D01*
X727425Y443167D01*
X725675D01*
G01X723533D02*
X723450Y443709D01*
X723325Y444167D01*
X723158Y444584D01*
X722950Y445042D01*
X722617Y445667D01*
X724283D01*
G01X721267Y443542D02*
X721017Y443334D01*
X720725Y443209D01*
X720350Y443167D01*
X719975Y443250D01*
X719683Y443417D01*
X719475Y443709D01*
X719433Y444042D01*
X719517Y444375D01*
X719725Y444584D01*
X720017Y444750D01*
X720308Y444792D01*
X720600Y444750D01*
X720975Y444584D01*
X720850Y445667D01*
X719725D01*
G01X702533Y445817D02*
X705033D01*
Y446858D01*
X704908Y447192D01*
X704741Y447400D01*
X704408Y447483D01*
X704075Y447400D01*
X703866Y447150D01*
X703741Y446858D01*
Y445817D01*
G01Y446858D02*
X702533Y447483D01*
G01X702908Y448833D02*
X702700Y449083D01*
X702575Y449375D01*
X702533Y449750D01*
X702616Y450125D01*
X702783Y450417D01*
X703075Y450625D01*
X703408Y450667D01*
X703741Y450583D01*
X703950Y450375D01*
X704116Y450083D01*
X704158Y449792D01*
X704116Y449500D01*
X703950Y449125D01*
X705033Y449250D01*
Y450375D01*
G01X703575Y452058D02*
X703866Y452350D01*
X704033Y452600D01*
X704116Y452933D01*
X704033Y453225D01*
X703866Y453433D01*
X703616Y453600D01*
X703325Y453642D01*
X703075Y453600D01*
X702825Y453433D01*
X702616Y453183D01*
X702533Y452892D01*
X702616Y452558D01*
X702866Y452267D01*
X703241Y452100D01*
X703658Y452058D01*
X704200Y452142D01*
X704491Y452267D01*
X704783Y452475D01*
X704991Y452767D01*
X705033Y453058D01*
X704950Y453350D01*
X704741Y453558D01*
G01X702533Y455867D02*
X703075Y455950D01*
X703533Y456075D01*
X703950Y456242D01*
X704408Y456450D01*
X705033Y456783D01*
Y455117D01*
G01X706300Y454700D02*
X710300D01*
Y447300D01*
G01X717600Y486301D02*
X720100D01*
Y487342D01*
X719975Y487676D01*
X719808Y487884D01*
X719475Y487967D01*
X719142Y487884D01*
X718933Y487634D01*
X718808Y487342D01*
Y486301D01*
G01Y487342D02*
X717600Y487967D01*
G01X717975Y489317D02*
X717767Y489567D01*
X717642Y489859D01*
X717600Y490234D01*
X717683Y490609D01*
X717850Y490901D01*
X718142Y491109D01*
X718475Y491151D01*
X718808Y491067D01*
X719017Y490859D01*
X719183Y490567D01*
X719225Y490276D01*
X719183Y489984D01*
X719017Y489609D01*
X720100Y489734D01*
Y490859D01*
G01X717975Y492417D02*
X717767Y492667D01*
X717642Y492959D01*
X717600Y493334D01*
X717683Y493709D01*
X717850Y494001D01*
X718142Y494209D01*
X718475Y494251D01*
X718808Y494167D01*
X719017Y493959D01*
X719183Y493667D01*
X719225Y493376D01*
X719183Y493084D01*
X719017Y492709D01*
X720100Y492834D01*
Y493959D01*
G01X717892Y495726D02*
X717683Y496017D01*
X717600Y496351D01*
X717683Y496684D01*
X717933Y496976D01*
X718308Y497184D01*
X718683Y497267D01*
X719142D01*
X719517Y497184D01*
X719850Y496976D01*
X720017Y496726D01*
X720100Y496434D01*
X720017Y496101D01*
X719850Y495851D01*
X719600Y495684D01*
X719267Y495601D01*
X718975Y495684D01*
X718683Y495892D01*
X718517Y496142D01*
X718475Y496434D01*
X718558Y496767D01*
X718767Y497017D01*
X719142Y497267D01*
G01X713100Y486301D02*
X715600D01*
Y487342D01*
X715475Y487676D01*
X715308Y487884D01*
X714975Y487967D01*
X714642Y487884D01*
X714433Y487634D01*
X714308Y487342D01*
Y486301D01*
G01Y487342D02*
X713100Y487967D01*
G01X713475Y489317D02*
X713267Y489567D01*
X713142Y489859D01*
X713100Y490234D01*
X713183Y490609D01*
X713350Y490901D01*
X713642Y491109D01*
X713975Y491151D01*
X714308Y491067D01*
X714517Y490859D01*
X714683Y490567D01*
X714725Y490276D01*
X714683Y489984D01*
X714517Y489609D01*
X715600Y489734D01*
Y490859D01*
G01X714142Y492542D02*
X714433Y492834D01*
X714600Y493084D01*
X714683Y493417D01*
X714600Y493709D01*
X714433Y493917D01*
X714183Y494084D01*
X713892Y494126D01*
X713642Y494084D01*
X713392Y493917D01*
X713183Y493667D01*
X713100Y493376D01*
X713183Y493042D01*
X713433Y492751D01*
X713808Y492584D01*
X714225Y492542D01*
X714767Y492626D01*
X715058Y492751D01*
X715350Y492959D01*
X715558Y493251D01*
X715600Y493542D01*
X715517Y493834D01*
X715308Y494042D01*
G01X715600Y496434D02*
X715517Y496101D01*
X715308Y495851D01*
X715058Y495684D01*
X714725Y495559D01*
X714350Y495517D01*
X713975Y495559D01*
X713642Y495684D01*
X713392Y495851D01*
X713183Y496101D01*
X713100Y496434D01*
X713183Y496767D01*
X713392Y497017D01*
X713642Y497184D01*
X713975Y497309D01*
X714350Y497351D01*
X714725Y497309D01*
X715058Y497184D01*
X715308Y497017D01*
X715517Y496767D01*
X715600Y496434D01*
G01X722100Y486301D02*
X724600D01*
Y487342D01*
X724475Y487676D01*
X724308Y487884D01*
X723975Y487967D01*
X723642Y487884D01*
X723433Y487634D01*
X723308Y487342D01*
Y486301D01*
G01Y487342D02*
X722100Y487967D01*
G01X722475Y489317D02*
X722267Y489567D01*
X722142Y489859D01*
X722100Y490234D01*
X722183Y490609D01*
X722350Y490901D01*
X722642Y491109D01*
X722975Y491151D01*
X723308Y491067D01*
X723517Y490859D01*
X723683Y490567D01*
X723725Y490276D01*
X723683Y489984D01*
X723517Y489609D01*
X724600Y489734D01*
Y490859D01*
G01X723142Y492542D02*
X723433Y492834D01*
X723600Y493084D01*
X723683Y493417D01*
X723600Y493709D01*
X723433Y493917D01*
X723183Y494084D01*
X722892Y494126D01*
X722642Y494084D01*
X722392Y493917D01*
X722183Y493667D01*
X722100Y493376D01*
X722183Y493042D01*
X722433Y492751D01*
X722808Y492584D01*
X723225Y492542D01*
X723767Y492626D01*
X724058Y492751D01*
X724350Y492959D01*
X724558Y493251D01*
X724600Y493542D01*
X724517Y493834D01*
X724308Y494042D01*
G01X722100Y496434D02*
X724600D01*
X724100Y495934D01*
G01X722100D02*
Y496934D01*
G01X728100Y487117D02*
X730600D01*
Y488158D01*
X730475Y488492D01*
X730308Y488700D01*
X729975Y488783D01*
X729642Y488700D01*
X729433Y488450D01*
X729308Y488158D01*
Y487117D01*
G01Y488158D02*
X728100Y488783D01*
G01X728475Y490133D02*
X728267Y490383D01*
X728142Y490675D01*
X728100Y491050D01*
X728183Y491425D01*
X728350Y491717D01*
X728642Y491925D01*
X728975Y491967D01*
X729308Y491883D01*
X729517Y491675D01*
X729683Y491383D01*
X729725Y491092D01*
X729683Y490800D01*
X729517Y490425D01*
X730600Y490550D01*
Y491675D01*
G01X729142Y493358D02*
X729433Y493650D01*
X729600Y493900D01*
X729683Y494233D01*
X729600Y494525D01*
X729433Y494733D01*
X729183Y494900D01*
X728892Y494942D01*
X728642Y494900D01*
X728392Y494733D01*
X728183Y494483D01*
X728100Y494192D01*
X728183Y493858D01*
X728433Y493567D01*
X728808Y493400D01*
X729225Y493358D01*
X729767Y493442D01*
X730058Y493567D01*
X730350Y493775D01*
X730558Y494067D01*
X730600Y494358D01*
X730517Y494650D01*
X730308Y494858D01*
G01X730183Y496458D02*
X730433Y496708D01*
X730558Y497000D01*
X730600Y497333D01*
X730517Y497750D01*
X730308Y498042D01*
X730058Y498125D01*
X729808Y498083D01*
X729600Y497917D01*
X729183Y497083D01*
X728892Y496708D01*
X728475Y496458D01*
X728100Y496375D01*
Y498125D01*
G01X725983Y480667D02*
Y483167D01*
X724983D01*
X724650Y483042D01*
X724400Y482750D01*
X724317Y482417D01*
X724400Y482084D01*
X724608Y481834D01*
X724983Y481709D01*
X725983D01*
G01X722925Y481000D02*
X722592Y480792D01*
X722217Y480667D01*
X721883D01*
X721550Y480792D01*
X721300Y481000D01*
X721175Y481292D01*
X721258Y481584D01*
X721467Y481834D01*
X721842Y482000D01*
X722342Y482084D01*
X722633Y482250D01*
X722758Y482542D01*
X722675Y482834D01*
X722467Y483042D01*
X722175Y483167D01*
X721883D01*
X721592Y483084D01*
X721342Y482875D01*
G01X719783Y480667D02*
Y483167D01*
X718783D01*
X718450Y483042D01*
X718200Y482750D01*
X718117Y482417D01*
X718200Y482084D01*
X718408Y481834D01*
X718783Y481709D01*
X719783D01*
G01X715850Y480667D02*
Y483167D01*
X716350Y482667D01*
G01Y480667D02*
X715350D01*
G01X690733Y555458D02*
X690983Y555583D01*
X691275Y555666D01*
X691608D01*
X691983Y555541D01*
X692275Y555333D01*
X692483Y555083D01*
X692650Y554666D01*
X692692Y554291D01*
X692608Y553916D01*
X692483Y553666D01*
X692233Y553416D01*
X691942Y553249D01*
X691650Y553166D01*
X691358D01*
X691067Y553249D01*
X690817Y553374D01*
X690608Y553541D01*
G01X688550Y553166D02*
Y555666D01*
X689050Y555166D01*
G01Y553166D02*
X688050D01*
G01X686367Y553541D02*
X686117Y553333D01*
X685825Y553208D01*
X685450Y553166D01*
X685075Y553249D01*
X684783Y553416D01*
X684575Y553708D01*
X684533Y554041D01*
X684617Y554374D01*
X684825Y554583D01*
X685117Y554749D01*
X685408Y554791D01*
X685700Y554749D01*
X686075Y554583D01*
X685950Y555666D01*
X684825D01*
G01X682433Y553166D02*
X682350Y553708D01*
X682225Y554166D01*
X682058Y554583D01*
X681850Y555041D01*
X681517Y555666D01*
X683183D01*
G01X691166Y537017D02*
X693666D01*
Y538058D01*
X693541Y538392D01*
X693374Y538600D01*
X693041Y538683D01*
X692708Y538600D01*
X692499Y538350D01*
X692374Y538058D01*
Y537017D01*
G01Y538058D02*
X691166Y538683D01*
G01Y541450D02*
X693666D01*
X691874Y539908D01*
Y541992D01*
G01X692208Y543258D02*
X692499Y543550D01*
X692666Y543800D01*
X692749Y544133D01*
X692666Y544425D01*
X692499Y544633D01*
X692249Y544800D01*
X691958Y544842D01*
X691708Y544800D01*
X691458Y544633D01*
X691249Y544383D01*
X691166Y544092D01*
X691249Y543758D01*
X691499Y543467D01*
X691874Y543300D01*
X692291Y543258D01*
X692833Y543342D01*
X693124Y543467D01*
X693416Y543675D01*
X693624Y543967D01*
X693666Y544258D01*
X693583Y544550D01*
X693374Y544758D01*
G01X691166Y547650D02*
X693666D01*
X691874Y546108D01*
Y548192D01*
G01X698166Y589017D02*
X700666D01*
Y590058D01*
X700541Y590392D01*
X700374Y590600D01*
X700041Y590683D01*
X699708Y590600D01*
X699499Y590350D01*
X699374Y590058D01*
Y589017D01*
G01Y590058D02*
X698166Y590683D01*
G01Y593450D02*
X700666D01*
X698874Y591908D01*
Y593992D01*
G01X699208Y595258D02*
X699499Y595550D01*
X699666Y595800D01*
X699749Y596133D01*
X699666Y596425D01*
X699499Y596633D01*
X699249Y596800D01*
X698958Y596842D01*
X698708Y596800D01*
X698458Y596633D01*
X698249Y596383D01*
X698166Y596092D01*
X698249Y595758D01*
X698499Y595467D01*
X698874Y595300D01*
X699291Y595258D01*
X699833Y595342D01*
X700124Y595467D01*
X700416Y595675D01*
X700624Y595967D01*
X700666Y596258D01*
X700583Y596550D01*
X700374Y596758D01*
G01X699208Y598358D02*
X699499Y598650D01*
X699666Y598900D01*
X699749Y599233D01*
X699666Y599525D01*
X699499Y599733D01*
X699249Y599900D01*
X698958Y599942D01*
X698708Y599900D01*
X698458Y599733D01*
X698249Y599483D01*
X698166Y599192D01*
X698249Y598858D01*
X698499Y598567D01*
X698874Y598400D01*
X699291Y598358D01*
X699833Y598442D01*
X700124Y598567D01*
X700416Y598775D01*
X700624Y599067D01*
X700666Y599358D01*
X700583Y599650D01*
X700374Y599858D01*
G01X701233Y612959D02*
X701483Y613084D01*
X701775Y613167D01*
X702108D01*
X702483Y613042D01*
X702775Y612834D01*
X702983Y612584D01*
X703150Y612167D01*
X703192Y611792D01*
X703108Y611417D01*
X702983Y611167D01*
X702733Y610917D01*
X702442Y610750D01*
X702150Y610667D01*
X701858D01*
X701567Y610750D01*
X701317Y610875D01*
X701108Y611042D01*
G01X699050Y610667D02*
Y613167D01*
X699550Y612667D01*
G01Y610667D02*
X698550D01*
G01X696867Y611042D02*
X696617Y610834D01*
X696325Y610709D01*
X695950Y610667D01*
X695575Y610750D01*
X695283Y610917D01*
X695075Y611209D01*
X695033Y611542D01*
X695117Y611875D01*
X695325Y612084D01*
X695617Y612250D01*
X695908Y612292D01*
X696200Y612250D01*
X696575Y612084D01*
X696450Y613167D01*
X695325D01*
G01X692850Y610667D02*
X692558Y610709D01*
X692225Y610834D01*
X692017Y611042D01*
X691933Y611334D01*
X692017Y611625D01*
X692267Y611875D01*
X692642Y612000D01*
X693058D01*
X693308Y612084D01*
X693517Y612292D01*
X693600Y612584D01*
X693475Y612875D01*
X693183Y613084D01*
X692850Y613167D01*
X692517Y613084D01*
X692225Y612875D01*
X692100Y612584D01*
X692183Y612292D01*
X692392Y612084D01*
X692642Y612000D01*
X693058D01*
X693433Y611875D01*
X693683Y611625D01*
X693767Y611334D01*
X693683Y611042D01*
X693475Y610834D01*
X693142Y610709D01*
X692850Y610667D01*
G01X889500Y599000D02*
Y682700D01*
X820400D01*
Y721400D01*
X700100D01*
Y669800D01*
X750500D01*
Y599000D01*
X889500D01*
G01X728816Y687810D02*
Y685310D01*
G01X729774Y687810D02*
X727858D01*
G01X726549Y685310D02*
Y687810D01*
X725549D01*
X725216Y687685D01*
X724966Y687393D01*
X724883Y687060D01*
X724966Y686727D01*
X725174Y686477D01*
X725549Y686352D01*
X726549D01*
G01X722616Y685310D02*
Y687810D01*
X723116Y687310D01*
G01Y685310D02*
X722116D01*
G01X719516D02*
Y687810D01*
X720016Y687310D01*
G01Y685310D02*
X719016D01*
G01X717208Y687393D02*
X716958Y687643D01*
X716666Y687768D01*
X716333Y687810D01*
X715916Y687727D01*
X715624Y687518D01*
X715541Y687268D01*
X715583Y687018D01*
X715749Y686810D01*
X716583Y686393D01*
X716958Y686102D01*
X717208Y685685D01*
X717291Y685310D01*
X715541D01*
G01X735766Y693143D02*
Y690643D01*
G01X736724Y693143D02*
X734808D01*
G01X733499Y690643D02*
Y693143D01*
X732499D01*
X732166Y693018D01*
X731916Y692726D01*
X731833Y692393D01*
X731916Y692060D01*
X732124Y691810D01*
X732499Y691685D01*
X733499D01*
G01X729566Y690643D02*
X729274Y690685D01*
X728941Y690810D01*
X728733Y691018D01*
X728649Y691310D01*
X728733Y691601D01*
X728983Y691851D01*
X729358Y691976D01*
X729774D01*
X730024Y692060D01*
X730233Y692268D01*
X730316Y692560D01*
X730191Y692851D01*
X729899Y693060D01*
X729566Y693143D01*
X729233Y693060D01*
X728941Y692851D01*
X728816Y692560D01*
X728899Y692268D01*
X729108Y692060D01*
X729358Y691976D01*
X729774D01*
X730149Y691851D01*
X730399Y691601D01*
X730483Y691310D01*
X730399Y691018D01*
X730191Y690810D01*
X729858Y690685D01*
X729566Y690643D01*
G01X726466D02*
X726174Y690685D01*
X725841Y690810D01*
X725633Y691018D01*
X725549Y691310D01*
X725633Y691601D01*
X725883Y691851D01*
X726258Y691976D01*
X726674D01*
X726924Y692060D01*
X727133Y692268D01*
X727216Y692560D01*
X727091Y692851D01*
X726799Y693060D01*
X726466Y693143D01*
X726133Y693060D01*
X725841Y692851D01*
X725716Y692560D01*
X725799Y692268D01*
X726008Y692060D01*
X726258Y691976D01*
X726674D01*
X727049Y691851D01*
X727299Y691601D01*
X727383Y691310D01*
X727299Y691018D01*
X727091Y690810D01*
X726758Y690685D01*
X726466Y690643D01*
G01X719766Y702810D02*
Y700310D01*
G01X720724Y702810D02*
X718808D01*
G01X717499Y700310D02*
Y702810D01*
X716499D01*
X716166Y702685D01*
X715916Y702393D01*
X715833Y702060D01*
X715916Y701727D01*
X716124Y701477D01*
X716499Y701352D01*
X717499D01*
G01X714274Y700602D02*
X713983Y700393D01*
X713649Y700310D01*
X713316Y700393D01*
X713024Y700643D01*
X712816Y701018D01*
X712733Y701393D01*
Y701852D01*
X712816Y702227D01*
X713024Y702560D01*
X713274Y702727D01*
X713566Y702810D01*
X713899Y702727D01*
X714149Y702560D01*
X714316Y702310D01*
X714399Y701977D01*
X714316Y701685D01*
X714108Y701393D01*
X713858Y701227D01*
X713566Y701185D01*
X713233Y701268D01*
X712983Y701477D01*
X712733Y701852D01*
G01X710549Y700310D02*
X710466Y700852D01*
X710341Y701310D01*
X710174Y701727D01*
X709966Y702185D01*
X709633Y702810D01*
X711299D01*
G01X723316Y693143D02*
Y690643D01*
G01X724274Y693143D02*
X722358D01*
G01X721049Y690643D02*
Y693143D01*
X720049D01*
X719716Y693018D01*
X719466Y692726D01*
X719383Y692393D01*
X719466Y692060D01*
X719674Y691810D01*
X720049Y691685D01*
X721049D01*
G01X717116Y690643D02*
Y693143D01*
X717616Y692643D01*
G01Y690643D02*
X716616D01*
G01X714016Y693143D02*
X714349Y693060D01*
X714599Y692851D01*
X714766Y692601D01*
X714891Y692268D01*
X714933Y691893D01*
X714891Y691518D01*
X714766Y691185D01*
X714599Y690935D01*
X714349Y690726D01*
X714016Y690643D01*
X713683Y690726D01*
X713433Y690935D01*
X713266Y691185D01*
X713141Y691518D01*
X713099Y691893D01*
X713141Y692268D01*
X713266Y692601D01*
X713433Y692851D01*
X713683Y693060D01*
X714016Y693143D01*
G01X710916Y690643D02*
Y693143D01*
X711416Y692643D01*
G01Y690643D02*
X710416D01*
G01X715316Y697810D02*
Y695310D01*
G01X716274Y697810D02*
X714358D01*
G01X713049Y695310D02*
Y697810D01*
X712049D01*
X711716Y697685D01*
X711466Y697393D01*
X711383Y697060D01*
X711466Y696727D01*
X711674Y696477D01*
X712049Y696352D01*
X713049D01*
G01X709116Y695310D02*
Y697810D01*
X709616Y697310D01*
G01Y695310D02*
X708616D01*
G01X706016Y697810D02*
X706349Y697727D01*
X706599Y697518D01*
X706766Y697268D01*
X706891Y696935D01*
X706933Y696560D01*
X706891Y696185D01*
X706766Y695852D01*
X706599Y695602D01*
X706349Y695393D01*
X706016Y695310D01*
X705683Y695393D01*
X705433Y695602D01*
X705266Y695852D01*
X705141Y696185D01*
X705099Y696560D01*
X705141Y696935D01*
X705266Y697268D01*
X705433Y697518D01*
X705683Y697727D01*
X706016Y697810D01*
G01X703833Y695810D02*
X703583Y695518D01*
X703249Y695352D01*
X702874Y695310D01*
X702541Y695352D01*
X702208Y695560D01*
X701999Y695810D01*
X701958Y696060D01*
X702041Y696352D01*
X702333Y696560D01*
X702624Y696643D01*
X702999D01*
G01X702624D02*
X702374Y696768D01*
X702166Y696977D01*
X702083Y697227D01*
X702166Y697477D01*
X702374Y697685D01*
X702749Y697810D01*
X703124Y697768D01*
X703499Y697602D01*
G01X736316Y703143D02*
Y700643D01*
G01X737274Y703143D02*
X735358D01*
G01X734049Y700643D02*
Y703143D01*
X733049D01*
X732716Y703018D01*
X732466Y702726D01*
X732383Y702393D01*
X732466Y702060D01*
X732674Y701810D01*
X733049Y701685D01*
X734049D01*
G01X730116Y700643D02*
Y703143D01*
X730616Y702643D01*
G01Y700643D02*
X729616D01*
G01X727016Y703143D02*
X727349Y703060D01*
X727599Y702851D01*
X727766Y702601D01*
X727891Y702268D01*
X727933Y701893D01*
X727891Y701518D01*
X727766Y701185D01*
X727599Y700935D01*
X727349Y700726D01*
X727016Y700643D01*
X726683Y700726D01*
X726433Y700935D01*
X726266Y701185D01*
X726141Y701518D01*
X726099Y701893D01*
X726141Y702268D01*
X726266Y702601D01*
X726433Y702851D01*
X726683Y703060D01*
X727016Y703143D01*
G01X723416Y700643D02*
Y703143D01*
X724958Y701351D01*
X722874D01*
G01X732816Y698310D02*
Y695810D01*
G01X733774Y698310D02*
X731858D01*
G01X730549Y695810D02*
Y698310D01*
X729549D01*
X729216Y698185D01*
X728966Y697893D01*
X728883Y697560D01*
X728966Y697227D01*
X729174Y696977D01*
X729549Y696852D01*
X730549D01*
G01X726616Y695810D02*
Y698310D01*
X727116Y697810D01*
G01Y695810D02*
X726116D01*
G01X723516Y698310D02*
X723849Y698227D01*
X724099Y698018D01*
X724266Y697768D01*
X724391Y697435D01*
X724433Y697060D01*
X724391Y696685D01*
X724266Y696352D01*
X724099Y696102D01*
X723849Y695893D01*
X723516Y695810D01*
X723183Y695893D01*
X722933Y696102D01*
X722766Y696352D01*
X722641Y696685D01*
X722599Y697060D01*
X722641Y697435D01*
X722766Y697768D01*
X722933Y698018D01*
X723183Y698227D01*
X723516Y698310D01*
G01X721208Y696852D02*
X720916Y697143D01*
X720666Y697310D01*
X720333Y697393D01*
X720041Y697310D01*
X719833Y697143D01*
X719666Y696893D01*
X719624Y696602D01*
X719666Y696352D01*
X719833Y696102D01*
X720083Y695893D01*
X720374Y695810D01*
X720708Y695893D01*
X720999Y696143D01*
X721166Y696518D01*
X721208Y696935D01*
X721124Y697477D01*
X720999Y697768D01*
X720791Y698060D01*
X720499Y698268D01*
X720208Y698310D01*
X719916Y698227D01*
X719708Y698018D01*
G01X724916Y706560D02*
X727416D01*
Y707601D01*
X727291Y707935D01*
X727124Y708143D01*
X726791Y708226D01*
X726458Y708143D01*
X726249Y707893D01*
X726124Y707601D01*
Y706560D01*
G01Y707601D02*
X724916Y708226D01*
G01X725958Y709701D02*
X726249Y709993D01*
X726416Y710243D01*
X726499Y710576D01*
X726416Y710868D01*
X726249Y711076D01*
X725999Y711243D01*
X725708Y711285D01*
X725458Y711243D01*
X725208Y711076D01*
X724999Y710826D01*
X724916Y710535D01*
X724999Y710201D01*
X725249Y709910D01*
X725624Y709743D01*
X726041Y709701D01*
X726583Y709785D01*
X726874Y709910D01*
X727166Y710118D01*
X727374Y710410D01*
X727416Y710701D01*
X727333Y710993D01*
X727124Y711201D01*
G01X724916Y713593D02*
X724958Y713885D01*
X725083Y714218D01*
X725291Y714426D01*
X725583Y714510D01*
X725874Y714426D01*
X726124Y714176D01*
X726249Y713801D01*
Y713385D01*
X726333Y713135D01*
X726541Y712926D01*
X726833Y712843D01*
X727124Y712968D01*
X727333Y713260D01*
X727416Y713593D01*
X727333Y713926D01*
X727124Y714218D01*
X726833Y714343D01*
X726541Y714260D01*
X726333Y714051D01*
X726249Y713801D01*
Y713385D01*
X726124Y713010D01*
X725874Y712760D01*
X725583Y712676D01*
X725291Y712760D01*
X725083Y712968D01*
X724958Y713301D01*
X724916Y713593D01*
G01X725958Y715901D02*
X726249Y716193D01*
X726416Y716443D01*
X726499Y716776D01*
X726416Y717068D01*
X726249Y717276D01*
X725999Y717443D01*
X725708Y717485D01*
X725458Y717443D01*
X725208Y717276D01*
X724999Y717026D01*
X724916Y716735D01*
X724999Y716401D01*
X725249Y716110D01*
X725624Y715943D01*
X726041Y715901D01*
X726583Y715985D01*
X726874Y716110D01*
X727166Y716318D01*
X727374Y716610D01*
X727416Y716901D01*
X727333Y717193D01*
X727124Y717401D01*
G01X735208Y708310D02*
X735333Y708060D01*
X735416Y707768D01*
Y707435D01*
X735291Y707060D01*
X735083Y706768D01*
X734833Y706560D01*
X734416Y706393D01*
X734041Y706351D01*
X733666Y706435D01*
X733416Y706560D01*
X733166Y706810D01*
X732999Y707101D01*
X732916Y707393D01*
Y707685D01*
X732999Y707976D01*
X733124Y708226D01*
X733291Y708435D01*
G01X733416Y709576D02*
X733124Y709826D01*
X732958Y710160D01*
X732916Y710535D01*
X732958Y710868D01*
X733166Y711201D01*
X733416Y711410D01*
X733666Y711451D01*
X733958Y711368D01*
X734166Y711076D01*
X734249Y710785D01*
Y710410D01*
G01Y710785D02*
X734374Y711035D01*
X734583Y711243D01*
X734833Y711326D01*
X735083Y711243D01*
X735291Y711035D01*
X735416Y710660D01*
X735374Y710285D01*
X735208Y709910D01*
G01X733208Y712885D02*
X732999Y713176D01*
X732916Y713510D01*
X732999Y713843D01*
X733249Y714135D01*
X733624Y714343D01*
X733999Y714426D01*
X734458D01*
X734833Y714343D01*
X735166Y714135D01*
X735333Y713885D01*
X735416Y713593D01*
X735333Y713260D01*
X735166Y713010D01*
X734916Y712843D01*
X734583Y712760D01*
X734291Y712843D01*
X733999Y713051D01*
X733833Y713301D01*
X733791Y713593D01*
X733874Y713926D01*
X734083Y714176D01*
X734458Y714426D01*
G01X732916Y717193D02*
X735416D01*
X733624Y715651D01*
Y717735D01*
G01X723208Y708310D02*
X723333Y708060D01*
X723416Y707768D01*
Y707435D01*
X723291Y707060D01*
X723083Y706768D01*
X722833Y706560D01*
X722416Y706393D01*
X722041Y706351D01*
X721666Y706435D01*
X721416Y706560D01*
X721166Y706810D01*
X720999Y707101D01*
X720916Y707393D01*
Y707685D01*
X720999Y707976D01*
X721124Y708226D01*
X721291Y708435D01*
G01X721416Y709576D02*
X721124Y709826D01*
X720958Y710160D01*
X720916Y710535D01*
X720958Y710868D01*
X721166Y711201D01*
X721416Y711410D01*
X721666Y711451D01*
X721958Y711368D01*
X722166Y711076D01*
X722249Y710785D01*
Y710410D01*
G01Y710785D02*
X722374Y711035D01*
X722583Y711243D01*
X722833Y711326D01*
X723083Y711243D01*
X723291Y711035D01*
X723416Y710660D01*
X723374Y710285D01*
X723208Y709910D01*
G01X721958Y712801D02*
X722249Y713093D01*
X722416Y713343D01*
X722499Y713676D01*
X722416Y713968D01*
X722249Y714176D01*
X721999Y714343D01*
X721708Y714385D01*
X721458Y714343D01*
X721208Y714176D01*
X720999Y713926D01*
X720916Y713635D01*
X720999Y713301D01*
X721249Y713010D01*
X721624Y712843D01*
X722041Y712801D01*
X722583Y712885D01*
X722874Y713010D01*
X723166Y713218D01*
X723374Y713510D01*
X723416Y713801D01*
X723333Y714093D01*
X723124Y714301D01*
G01X722999Y715901D02*
X723249Y716151D01*
X723374Y716443D01*
X723416Y716776D01*
X723333Y717193D01*
X723124Y717485D01*
X722874Y717568D01*
X722624Y717526D01*
X722416Y717360D01*
X721999Y716526D01*
X721708Y716151D01*
X721291Y715901D01*
X720916Y715818D01*
Y717568D01*
G01X719208Y708310D02*
X719333Y708060D01*
X719416Y707768D01*
Y707435D01*
X719291Y707060D01*
X719083Y706768D01*
X718833Y706560D01*
X718416Y706393D01*
X718041Y706351D01*
X717666Y706435D01*
X717416Y706560D01*
X717166Y706810D01*
X716999Y707101D01*
X716916Y707393D01*
Y707685D01*
X716999Y707976D01*
X717124Y708226D01*
X717291Y708435D01*
G01X717416Y709576D02*
X717124Y709826D01*
X716958Y710160D01*
X716916Y710535D01*
X716958Y710868D01*
X717166Y711201D01*
X717416Y711410D01*
X717666Y711451D01*
X717958Y711368D01*
X718166Y711076D01*
X718249Y710785D01*
Y710410D01*
G01Y710785D02*
X718374Y711035D01*
X718583Y711243D01*
X718833Y711326D01*
X719083Y711243D01*
X719291Y711035D01*
X719416Y710660D01*
X719374Y710285D01*
X719208Y709910D01*
G01X717958Y712801D02*
X718249Y713093D01*
X718416Y713343D01*
X718499Y713676D01*
X718416Y713968D01*
X718249Y714176D01*
X717999Y714343D01*
X717708Y714385D01*
X717458Y714343D01*
X717208Y714176D01*
X716999Y713926D01*
X716916Y713635D01*
X716999Y713301D01*
X717249Y713010D01*
X717624Y712843D01*
X718041Y712801D01*
X718583Y712885D01*
X718874Y713010D01*
X719166Y713218D01*
X719374Y713510D01*
X719416Y713801D01*
X719333Y714093D01*
X719124Y714301D01*
G01X717416Y715776D02*
X717124Y716026D01*
X716958Y716360D01*
X716916Y716735D01*
X716958Y717068D01*
X717166Y717401D01*
X717416Y717610D01*
X717666Y717651D01*
X717958Y717568D01*
X718166Y717276D01*
X718249Y716985D01*
Y716610D01*
G01Y716985D02*
X718374Y717235D01*
X718583Y717443D01*
X718833Y717526D01*
X719083Y717443D01*
X719291Y717235D01*
X719416Y716860D01*
X719374Y716485D01*
X719208Y716110D01*
G01X731416Y706560D02*
X728916D01*
Y708226D01*
G01X730999Y709701D02*
X731249Y709951D01*
X731374Y710243D01*
X731416Y710576D01*
X731333Y710993D01*
X731124Y711285D01*
X730874Y711368D01*
X730624Y711326D01*
X730416Y711160D01*
X729999Y710326D01*
X729708Y709951D01*
X729291Y709701D01*
X728916Y709618D01*
Y711368D01*
G01X731416Y713593D02*
X731333Y713260D01*
X731124Y713010D01*
X730874Y712843D01*
X730541Y712718D01*
X730166Y712676D01*
X729791Y712718D01*
X729458Y712843D01*
X729208Y713010D01*
X728999Y713260D01*
X728916Y713593D01*
X728999Y713926D01*
X729208Y714176D01*
X729458Y714343D01*
X729791Y714468D01*
X730166Y714510D01*
X730541Y714468D01*
X730874Y714343D01*
X731124Y714176D01*
X731333Y713926D01*
X731416Y713593D01*
G01X767733Y68292D02*
X767983Y68417D01*
X768275Y68500D01*
X768608D01*
X768983Y68375D01*
X769275Y68167D01*
X769483Y67917D01*
X769650Y67500D01*
X769692Y67125D01*
X769608Y66750D01*
X769483Y66500D01*
X769233Y66250D01*
X768942Y66083D01*
X768650Y66000D01*
X768358D01*
X768067Y66083D01*
X767817Y66208D01*
X767608Y66375D01*
G01X765050Y66000D02*
Y68500D01*
X766592Y66708D01*
X764508D01*
G01X762450Y66000D02*
X762158Y66042D01*
X761825Y66167D01*
X761617Y66375D01*
X761533Y66667D01*
X761617Y66958D01*
X761867Y67208D01*
X762242Y67333D01*
X762658D01*
X762908Y67417D01*
X763117Y67625D01*
X763200Y67917D01*
X763075Y68208D01*
X762783Y68417D01*
X762450Y68500D01*
X762117Y68417D01*
X761825Y68208D01*
X761700Y67917D01*
X761783Y67625D01*
X761992Y67417D01*
X762242Y67333D01*
X762658D01*
X763033Y67208D01*
X763283Y66958D01*
X763367Y66667D01*
X763283Y66375D01*
X763075Y66167D01*
X762742Y66042D01*
X762450Y66000D01*
G01X760058Y66292D02*
X759767Y66083D01*
X759433Y66000D01*
X759100Y66083D01*
X758808Y66333D01*
X758600Y66708D01*
X758517Y67083D01*
Y67542D01*
X758600Y67917D01*
X758808Y68250D01*
X759058Y68417D01*
X759350Y68500D01*
X759683Y68417D01*
X759933Y68250D01*
X760100Y68000D01*
X760183Y67667D01*
X760100Y67375D01*
X759892Y67083D01*
X759642Y66917D01*
X759350Y66875D01*
X759017Y66958D01*
X758767Y67167D01*
X758517Y67542D01*
G01X767233Y57792D02*
X767483Y57917D01*
X767775Y58000D01*
X768108D01*
X768483Y57875D01*
X768775Y57667D01*
X768983Y57417D01*
X769150Y57000D01*
X769192Y56625D01*
X769108Y56250D01*
X768983Y56000D01*
X768733Y55750D01*
X768442Y55583D01*
X768150Y55500D01*
X767858D01*
X767567Y55583D01*
X767317Y55708D01*
X767108Y55875D01*
G01X764550Y55500D02*
Y58000D01*
X766092Y56208D01*
X764008D01*
G01X761950Y55500D02*
X761658Y55542D01*
X761325Y55667D01*
X761117Y55875D01*
X761033Y56167D01*
X761117Y56458D01*
X761367Y56708D01*
X761742Y56833D01*
X762158D01*
X762408Y56917D01*
X762617Y57125D01*
X762700Y57417D01*
X762575Y57708D01*
X762283Y57917D01*
X761950Y58000D01*
X761617Y57917D01*
X761325Y57708D01*
X761200Y57417D01*
X761283Y57125D01*
X761492Y56917D01*
X761742Y56833D01*
X762158D01*
X762533Y56708D01*
X762783Y56458D01*
X762867Y56167D01*
X762783Y55875D01*
X762575Y55667D01*
X762242Y55542D01*
X761950Y55500D01*
G01X758850D02*
X758558Y55542D01*
X758225Y55667D01*
X758017Y55875D01*
X757933Y56167D01*
X758017Y56458D01*
X758267Y56708D01*
X758642Y56833D01*
X759058D01*
X759308Y56917D01*
X759517Y57125D01*
X759600Y57417D01*
X759475Y57708D01*
X759183Y57917D01*
X758850Y58000D01*
X758517Y57917D01*
X758225Y57708D01*
X758100Y57417D01*
X758183Y57125D01*
X758392Y56917D01*
X758642Y56833D01*
X759058D01*
X759433Y56708D01*
X759683Y56458D01*
X759767Y56167D01*
X759683Y55875D01*
X759475Y55667D01*
X759142Y55542D01*
X758850Y55500D01*
G01X767233Y62292D02*
X767483Y62417D01*
X767775Y62500D01*
X768108D01*
X768483Y62375D01*
X768775Y62167D01*
X768983Y61917D01*
X769150Y61500D01*
X769192Y61125D01*
X769108Y60750D01*
X768983Y60500D01*
X768733Y60250D01*
X768442Y60083D01*
X768150Y60000D01*
X767858D01*
X767567Y60083D01*
X767317Y60208D01*
X767108Y60375D01*
G01X764550Y60000D02*
Y62500D01*
X766092Y60708D01*
X764008D01*
G01X761950Y60000D02*
X761658Y60042D01*
X761325Y60167D01*
X761117Y60375D01*
X761033Y60667D01*
X761117Y60958D01*
X761367Y61208D01*
X761742Y61333D01*
X762158D01*
X762408Y61417D01*
X762617Y61625D01*
X762700Y61917D01*
X762575Y62208D01*
X762283Y62417D01*
X761950Y62500D01*
X761617Y62417D01*
X761325Y62208D01*
X761200Y61917D01*
X761283Y61625D01*
X761492Y61417D01*
X761742Y61333D01*
X762158D01*
X762533Y61208D01*
X762783Y60958D01*
X762867Y60667D01*
X762783Y60375D01*
X762575Y60167D01*
X762242Y60042D01*
X761950Y60000D01*
G01X758933D02*
X758850Y60542D01*
X758725Y61000D01*
X758558Y61417D01*
X758350Y61875D01*
X758017Y62500D01*
X759683D01*
G01X762533Y108192D02*
X762783Y108317D01*
X763075Y108400D01*
X763408D01*
X763783Y108275D01*
X764075Y108067D01*
X764283Y107817D01*
X764450Y107400D01*
X764492Y107025D01*
X764408Y106650D01*
X764283Y106400D01*
X764033Y106150D01*
X763742Y105983D01*
X763450Y105900D01*
X763158D01*
X762867Y105983D01*
X762617Y106108D01*
X762408Y106275D01*
G01X759850Y105900D02*
Y108400D01*
X761392Y106608D01*
X759308D01*
G01X757958Y106192D02*
X757667Y105983D01*
X757333Y105900D01*
X757000Y105983D01*
X756708Y106233D01*
X756500Y106608D01*
X756417Y106983D01*
Y107442D01*
X756500Y107817D01*
X756708Y108150D01*
X756958Y108317D01*
X757250Y108400D01*
X757583Y108317D01*
X757833Y108150D01*
X758000Y107900D01*
X758083Y107567D01*
X758000Y107275D01*
X757792Y106983D01*
X757542Y106817D01*
X757250Y106775D01*
X756917Y106858D01*
X756667Y107067D01*
X756417Y107442D01*
G01X755067Y106400D02*
X754817Y106108D01*
X754483Y105942D01*
X754108Y105900D01*
X753775Y105942D01*
X753442Y106150D01*
X753233Y106400D01*
X753192Y106650D01*
X753275Y106942D01*
X753567Y107150D01*
X753858Y107233D01*
X754233D01*
G01X753858D02*
X753608Y107358D01*
X753400Y107567D01*
X753317Y107817D01*
X753400Y108067D01*
X753608Y108275D01*
X753983Y108400D01*
X754358Y108358D01*
X754733Y108192D01*
G01X762533Y112192D02*
X762783Y112317D01*
X763075Y112400D01*
X763408D01*
X763783Y112275D01*
X764075Y112067D01*
X764283Y111817D01*
X764450Y111400D01*
X764492Y111025D01*
X764408Y110650D01*
X764283Y110400D01*
X764033Y110150D01*
X763742Y109983D01*
X763450Y109900D01*
X763158D01*
X762867Y109983D01*
X762617Y110108D01*
X762408Y110275D01*
G01X759850Y109900D02*
Y112400D01*
X761392Y110608D01*
X759308D01*
G01X757958Y110192D02*
X757667Y109983D01*
X757333Y109900D01*
X757000Y109983D01*
X756708Y110233D01*
X756500Y110608D01*
X756417Y110983D01*
Y111442D01*
X756500Y111817D01*
X756708Y112150D01*
X756958Y112317D01*
X757250Y112400D01*
X757583Y112317D01*
X757833Y112150D01*
X758000Y111900D01*
X758083Y111567D01*
X758000Y111275D01*
X757792Y110983D01*
X757542Y110817D01*
X757250Y110775D01*
X756917Y110858D01*
X756667Y111067D01*
X756417Y111442D01*
G01X754942Y111983D02*
X754692Y112233D01*
X754400Y112358D01*
X754067Y112400D01*
X753650Y112317D01*
X753358Y112108D01*
X753275Y111858D01*
X753317Y111608D01*
X753483Y111400D01*
X754317Y110983D01*
X754692Y110692D01*
X754942Y110275D01*
X755025Y109900D01*
X753275D01*
G01X762533Y116192D02*
X762783Y116317D01*
X763075Y116400D01*
X763408D01*
X763783Y116275D01*
X764075Y116067D01*
X764283Y115817D01*
X764450Y115400D01*
X764492Y115025D01*
X764408Y114650D01*
X764283Y114400D01*
X764033Y114150D01*
X763742Y113983D01*
X763450Y113900D01*
X763158D01*
X762867Y113983D01*
X762617Y114108D01*
X762408Y114275D01*
G01X759850Y113900D02*
Y116400D01*
X761392Y114608D01*
X759308D01*
G01X757958Y114192D02*
X757667Y113983D01*
X757333Y113900D01*
X757000Y113983D01*
X756708Y114233D01*
X756500Y114608D01*
X756417Y114983D01*
Y115442D01*
X756500Y115817D01*
X756708Y116150D01*
X756958Y116317D01*
X757250Y116400D01*
X757583Y116317D01*
X757833Y116150D01*
X758000Y115900D01*
X758083Y115567D01*
X758000Y115275D01*
X757792Y114983D01*
X757542Y114817D01*
X757250Y114775D01*
X756917Y114858D01*
X756667Y115067D01*
X756417Y115442D01*
G01X754150Y113900D02*
Y116400D01*
X754650Y115900D01*
G01Y113900D02*
X753650D01*
G01X762533Y120692D02*
X762783Y120817D01*
X763075Y120900D01*
X763408D01*
X763783Y120775D01*
X764075Y120567D01*
X764283Y120317D01*
X764450Y119900D01*
X764492Y119525D01*
X764408Y119150D01*
X764283Y118900D01*
X764033Y118650D01*
X763742Y118483D01*
X763450Y118400D01*
X763158D01*
X762867Y118483D01*
X762617Y118608D01*
X762408Y118775D01*
G01X759850Y118400D02*
Y120900D01*
X761392Y119108D01*
X759308D01*
G01X757958Y118692D02*
X757667Y118483D01*
X757333Y118400D01*
X757000Y118483D01*
X756708Y118733D01*
X756500Y119108D01*
X756417Y119483D01*
Y119942D01*
X756500Y120317D01*
X756708Y120650D01*
X756958Y120817D01*
X757250Y120900D01*
X757583Y120817D01*
X757833Y120650D01*
X758000Y120400D01*
X758083Y120067D01*
X758000Y119775D01*
X757792Y119483D01*
X757542Y119317D01*
X757250Y119275D01*
X756917Y119358D01*
X756667Y119567D01*
X756417Y119942D01*
G01X754150Y120900D02*
X754483Y120817D01*
X754733Y120608D01*
X754900Y120358D01*
X755025Y120025D01*
X755067Y119650D01*
X755025Y119275D01*
X754900Y118942D01*
X754733Y118692D01*
X754483Y118483D01*
X754150Y118400D01*
X753817Y118483D01*
X753567Y118692D01*
X753400Y118942D01*
X753275Y119275D01*
X753233Y119650D01*
X753275Y120025D01*
X753400Y120358D01*
X753567Y120608D01*
X753817Y120817D01*
X754150Y120900D01*
G01X767733Y72292D02*
X767983Y72417D01*
X768275Y72500D01*
X768608D01*
X768983Y72375D01*
X769275Y72167D01*
X769483Y71917D01*
X769650Y71500D01*
X769692Y71125D01*
X769608Y70750D01*
X769483Y70500D01*
X769233Y70250D01*
X768942Y70083D01*
X768650Y70000D01*
X768358D01*
X768067Y70083D01*
X767817Y70208D01*
X767608Y70375D01*
G01X765050Y70000D02*
Y72500D01*
X766592Y70708D01*
X764508D01*
G01X762450Y70000D02*
X762158Y70042D01*
X761825Y70167D01*
X761617Y70375D01*
X761533Y70667D01*
X761617Y70958D01*
X761867Y71208D01*
X762242Y71333D01*
X762658D01*
X762908Y71417D01*
X763117Y71625D01*
X763200Y71917D01*
X763075Y72208D01*
X762783Y72417D01*
X762450Y72500D01*
X762117Y72417D01*
X761825Y72208D01*
X761700Y71917D01*
X761783Y71625D01*
X761992Y71417D01*
X762242Y71333D01*
X762658D01*
X763033Y71208D01*
X763283Y70958D01*
X763367Y70667D01*
X763283Y70375D01*
X763075Y70167D01*
X762742Y70042D01*
X762450Y70000D01*
G01X760142Y71042D02*
X759850Y71333D01*
X759600Y71500D01*
X759267Y71583D01*
X758975Y71500D01*
X758767Y71333D01*
X758600Y71083D01*
X758558Y70792D01*
X758600Y70542D01*
X758767Y70292D01*
X759017Y70083D01*
X759308Y70000D01*
X759642Y70083D01*
X759933Y70333D01*
X760100Y70708D01*
X760142Y71125D01*
X760058Y71667D01*
X759933Y71958D01*
X759725Y72250D01*
X759433Y72458D01*
X759142Y72500D01*
X758850Y72417D01*
X758642Y72208D01*
G01X769100Y183200D02*
Y192500D01*
G01X771500Y177900D02*
X809200D01*
G01X743333Y194259D02*
X743583Y194384D01*
X743875Y194467D01*
X744208D01*
X744583Y194342D01*
X744875Y194134D01*
X745083Y193884D01*
X745250Y193467D01*
X745292Y193092D01*
X745208Y192717D01*
X745083Y192467D01*
X744833Y192217D01*
X744542Y192050D01*
X744250Y191967D01*
X743958D01*
X743667Y192050D01*
X743417Y192175D01*
X743208Y192342D01*
G01X742067Y192467D02*
X741817Y192175D01*
X741483Y192009D01*
X741108Y191967D01*
X740775Y192009D01*
X740442Y192217D01*
X740233Y192467D01*
X740192Y192717D01*
X740275Y193009D01*
X740567Y193217D01*
X740858Y193300D01*
X741233D01*
G01X740858D02*
X740608Y193425D01*
X740400Y193634D01*
X740317Y193884D01*
X740400Y194134D01*
X740608Y194342D01*
X740983Y194467D01*
X741358Y194425D01*
X741733Y194259D01*
G01X738967Y192467D02*
X738717Y192175D01*
X738383Y192009D01*
X738008Y191967D01*
X737675Y192009D01*
X737342Y192217D01*
X737133Y192467D01*
X737092Y192717D01*
X737175Y193009D01*
X737467Y193217D01*
X737758Y193300D01*
X738133D01*
G01X737758D02*
X737508Y193425D01*
X737300Y193634D01*
X737217Y193884D01*
X737300Y194134D01*
X737508Y194342D01*
X737883Y194467D01*
X738258Y194425D01*
X738633Y194259D01*
G01X734950Y191967D02*
Y194467D01*
X735450Y193967D01*
G01Y191967D02*
X734450D01*
G01X743533Y189859D02*
X743783Y189984D01*
X744075Y190067D01*
X744408D01*
X744783Y189942D01*
X745075Y189734D01*
X745283Y189484D01*
X745450Y189067D01*
X745492Y188692D01*
X745408Y188317D01*
X745283Y188067D01*
X745033Y187817D01*
X744742Y187650D01*
X744450Y187567D01*
X744158D01*
X743867Y187650D01*
X743617Y187775D01*
X743408Y187942D01*
G01X742267Y188067D02*
X742017Y187775D01*
X741683Y187609D01*
X741308Y187567D01*
X740975Y187609D01*
X740642Y187817D01*
X740433Y188067D01*
X740392Y188317D01*
X740475Y188609D01*
X740767Y188817D01*
X741058Y188900D01*
X741433D01*
G01X741058D02*
X740808Y189025D01*
X740600Y189234D01*
X740517Y189484D01*
X740600Y189734D01*
X740808Y189942D01*
X741183Y190067D01*
X741558Y190025D01*
X741933Y189859D01*
G01X739167Y188067D02*
X738917Y187775D01*
X738583Y187609D01*
X738208Y187567D01*
X737875Y187609D01*
X737542Y187817D01*
X737333Y188067D01*
X737292Y188317D01*
X737375Y188609D01*
X737667Y188817D01*
X737958Y188900D01*
X738333D01*
G01X737958D02*
X737708Y189025D01*
X737500Y189234D01*
X737417Y189484D01*
X737500Y189734D01*
X737708Y189942D01*
X738083Y190067D01*
X738458Y190025D01*
X738833Y189859D01*
G01X735942Y189650D02*
X735692Y189900D01*
X735400Y190025D01*
X735067Y190067D01*
X734650Y189984D01*
X734358Y189775D01*
X734275Y189525D01*
X734317Y189275D01*
X734483Y189067D01*
X735317Y188650D01*
X735692Y188359D01*
X735942Y187942D01*
X736025Y187567D01*
X734275D01*
G01X747667Y186017D02*
X750167D01*
Y187058D01*
X750042Y187392D01*
X749875Y187600D01*
X749542Y187683D01*
X749209Y187600D01*
X749000Y187350D01*
X748875Y187058D01*
Y186017D01*
G01Y187058D02*
X747667Y187683D01*
G01X748709Y189158D02*
X749000Y189450D01*
X749167Y189700D01*
X749250Y190033D01*
X749167Y190325D01*
X749000Y190533D01*
X748750Y190700D01*
X748459Y190742D01*
X748209Y190700D01*
X747959Y190533D01*
X747750Y190283D01*
X747667Y189992D01*
X747750Y189658D01*
X748000Y189367D01*
X748375Y189200D01*
X748792Y189158D01*
X749334Y189242D01*
X749625Y189367D01*
X749917Y189575D01*
X750125Y189867D01*
X750167Y190158D01*
X750084Y190450D01*
X749875Y190658D01*
G01X747667Y193050D02*
X750167D01*
X749667Y192550D01*
G01X747667D02*
Y193550D01*
G01Y196150D02*
X747709Y196442D01*
X747834Y196775D01*
X748042Y196983D01*
X748334Y197067D01*
X748625Y196983D01*
X748875Y196733D01*
X749000Y196358D01*
Y195942D01*
X749084Y195692D01*
X749292Y195483D01*
X749584Y195400D01*
X749875Y195525D01*
X750084Y195817D01*
X750167Y196150D01*
X750084Y196483D01*
X749875Y196775D01*
X749584Y196900D01*
X749292Y196817D01*
X749084Y196608D01*
X749000Y196358D01*
Y195942D01*
X748875Y195567D01*
X748625Y195317D01*
X748334Y195233D01*
X748042Y195317D01*
X747834Y195525D01*
X747709Y195858D01*
X747667Y196150D01*
G01X770529Y193954D02*
X766529D01*
Y201354D01*
G01X774200Y180200D02*
Y184200D01*
X781600D01*
G01X788073Y180318D02*
Y184318D01*
X795473D01*
G01X759300Y178800D02*
Y182800D01*
X766700D01*
G01X743333Y185459D02*
X743583Y185584D01*
X743875Y185667D01*
X744208D01*
X744583Y185542D01*
X744875Y185334D01*
X745083Y185084D01*
X745250Y184667D01*
X745292Y184292D01*
X745208Y183917D01*
X745083Y183667D01*
X744833Y183417D01*
X744542Y183250D01*
X744250Y183167D01*
X743958D01*
X743667Y183250D01*
X743417Y183375D01*
X743208Y183542D01*
G01X742067Y183667D02*
X741817Y183375D01*
X741483Y183209D01*
X741108Y183167D01*
X740775Y183209D01*
X740442Y183417D01*
X740233Y183667D01*
X740192Y183917D01*
X740275Y184209D01*
X740567Y184417D01*
X740858Y184500D01*
X741233D01*
G01X740858D02*
X740608Y184625D01*
X740400Y184834D01*
X740317Y185084D01*
X740400Y185334D01*
X740608Y185542D01*
X740983Y185667D01*
X741358Y185625D01*
X741733Y185459D01*
G01X738967Y183667D02*
X738717Y183375D01*
X738383Y183209D01*
X738008Y183167D01*
X737675Y183209D01*
X737342Y183417D01*
X737133Y183667D01*
X737092Y183917D01*
X737175Y184209D01*
X737467Y184417D01*
X737758Y184500D01*
X738133D01*
G01X737758D02*
X737508Y184625D01*
X737300Y184834D01*
X737217Y185084D01*
X737300Y185334D01*
X737508Y185542D01*
X737883Y185667D01*
X738258Y185625D01*
X738633Y185459D01*
G01X734950Y185667D02*
X735283Y185584D01*
X735533Y185375D01*
X735700Y185125D01*
X735825Y184792D01*
X735867Y184417D01*
X735825Y184042D01*
X735700Y183709D01*
X735533Y183459D01*
X735283Y183250D01*
X734950Y183167D01*
X734617Y183250D01*
X734367Y183459D01*
X734200Y183709D01*
X734075Y184042D01*
X734033Y184417D01*
X734075Y184792D01*
X734200Y185125D01*
X734367Y185375D01*
X734617Y185584D01*
X734950Y185667D01*
G01X784200Y184700D02*
Y191700D01*
X770800D01*
Y184700D01*
X784200D01*
G01X798737Y184718D02*
Y191718D01*
X785337D01*
Y184718D01*
X798737D01*
G01X744433Y176567D02*
Y174067D01*
X742767D01*
G01X740500D02*
Y176567D01*
X741000Y176067D01*
G01Y174067D02*
X740000D01*
G01X738317Y174567D02*
X738067Y174275D01*
X737733Y174109D01*
X737358Y174067D01*
X737025Y174109D01*
X736692Y174317D01*
X736483Y174567D01*
X736442Y174817D01*
X736525Y175109D01*
X736817Y175317D01*
X737108Y175400D01*
X737483D01*
G01X737108D02*
X736858Y175525D01*
X736650Y175734D01*
X736567Y175984D01*
X736650Y176234D01*
X736858Y176442D01*
X737233Y176567D01*
X737608Y176525D01*
X737983Y176359D01*
G01X769300Y171400D02*
Y178400D01*
X755900D01*
Y171400D01*
X769300D01*
G01X792600Y261800D02*
X806000D01*
Y260000D01*
X812400D01*
Y260800D01*
X817700D01*
Y257000D01*
X822200D01*
Y251000D01*
X823800D01*
G01X780990Y247880D02*
Y251880D01*
X788390D01*
G01X751100Y210500D02*
Y206500D01*
X743700D01*
G01X805833Y313359D02*
X806083Y313484D01*
X806375Y313567D01*
X806708D01*
X807083Y313442D01*
X807375Y313234D01*
X807583Y312984D01*
X807750Y312567D01*
X807792Y312192D01*
X807708Y311817D01*
X807583Y311567D01*
X807333Y311317D01*
X807042Y311150D01*
X806750Y311067D01*
X806458D01*
X806167Y311150D01*
X805917Y311275D01*
X805708Y311442D01*
G01X804567Y311567D02*
X804317Y311275D01*
X803983Y311109D01*
X803608Y311067D01*
X803275Y311109D01*
X802942Y311317D01*
X802733Y311567D01*
X802692Y311817D01*
X802775Y312109D01*
X803067Y312317D01*
X803358Y312400D01*
X803733D01*
G01X803358D02*
X803108Y312525D01*
X802900Y312734D01*
X802817Y312984D01*
X802900Y313234D01*
X803108Y313442D01*
X803483Y313567D01*
X803858Y313525D01*
X804233Y313359D01*
G01X801342Y312109D02*
X801050Y312400D01*
X800800Y312567D01*
X800467Y312650D01*
X800175Y312567D01*
X799967Y312400D01*
X799800Y312150D01*
X799758Y311859D01*
X799800Y311609D01*
X799967Y311359D01*
X800217Y311150D01*
X800508Y311067D01*
X800842Y311150D01*
X801133Y311400D01*
X801300Y311775D01*
X801342Y312192D01*
X801258Y312734D01*
X801133Y313025D01*
X800925Y313317D01*
X800633Y313525D01*
X800342Y313567D01*
X800050Y313484D01*
X799842Y313275D01*
G01X798367Y311442D02*
X798117Y311234D01*
X797825Y311109D01*
X797450Y311067D01*
X797075Y311150D01*
X796783Y311317D01*
X796575Y311609D01*
X796533Y311942D01*
X796617Y312275D01*
X796825Y312484D01*
X797117Y312650D01*
X797408Y312692D01*
X797700Y312650D01*
X798075Y312484D01*
X797950Y313567D01*
X796825D01*
G01X806233Y321659D02*
X806483Y321784D01*
X806775Y321867D01*
X807108D01*
X807483Y321742D01*
X807775Y321534D01*
X807983Y321284D01*
X808150Y320867D01*
X808192Y320492D01*
X808108Y320117D01*
X807983Y319867D01*
X807733Y319617D01*
X807442Y319450D01*
X807150Y319367D01*
X806858D01*
X806567Y319450D01*
X806317Y319575D01*
X806108Y319742D01*
G01X804967Y319867D02*
X804717Y319575D01*
X804383Y319409D01*
X804008Y319367D01*
X803675Y319409D01*
X803342Y319617D01*
X803133Y319867D01*
X803092Y320117D01*
X803175Y320409D01*
X803467Y320617D01*
X803758Y320700D01*
X804133D01*
G01X803758D02*
X803508Y320825D01*
X803300Y321034D01*
X803217Y321284D01*
X803300Y321534D01*
X803508Y321742D01*
X803883Y321867D01*
X804258Y321825D01*
X804633Y321659D01*
G01X801033Y319367D02*
X800950Y319909D01*
X800825Y320367D01*
X800658Y320784D01*
X800450Y321242D01*
X800117Y321867D01*
X801783D01*
G01X798642Y320409D02*
X798350Y320700D01*
X798100Y320867D01*
X797767Y320950D01*
X797475Y320867D01*
X797267Y320700D01*
X797100Y320450D01*
X797058Y320159D01*
X797100Y319909D01*
X797267Y319659D01*
X797517Y319450D01*
X797808Y319367D01*
X798142Y319450D01*
X798433Y319700D01*
X798600Y320075D01*
X798642Y320492D01*
X798558Y321034D01*
X798433Y321325D01*
X798225Y321617D01*
X797933Y321825D01*
X797642Y321867D01*
X797350Y321784D01*
X797142Y321575D01*
G01X806233Y317459D02*
X806483Y317584D01*
X806775Y317667D01*
X807108D01*
X807483Y317542D01*
X807775Y317334D01*
X807983Y317084D01*
X808150Y316667D01*
X808192Y316292D01*
X808108Y315917D01*
X807983Y315667D01*
X807733Y315417D01*
X807442Y315250D01*
X807150Y315167D01*
X806858D01*
X806567Y315250D01*
X806317Y315375D01*
X806108Y315542D01*
G01X804967Y315667D02*
X804717Y315375D01*
X804383Y315209D01*
X804008Y315167D01*
X803675Y315209D01*
X803342Y315417D01*
X803133Y315667D01*
X803092Y315917D01*
X803175Y316209D01*
X803467Y316417D01*
X803758Y316500D01*
X804133D01*
G01X803758D02*
X803508Y316625D01*
X803300Y316834D01*
X803217Y317084D01*
X803300Y317334D01*
X803508Y317542D01*
X803883Y317667D01*
X804258Y317625D01*
X804633Y317459D01*
G01X801033Y315167D02*
X800950Y315709D01*
X800825Y316167D01*
X800658Y316584D01*
X800450Y317042D01*
X800117Y317667D01*
X801783D01*
G01X797933Y315167D02*
X797850Y315709D01*
X797725Y316167D01*
X797558Y316584D01*
X797350Y317042D01*
X797017Y317667D01*
X798683D01*
G01X752859Y316567D02*
X752984Y316317D01*
X753067Y316025D01*
Y315692D01*
X752942Y315317D01*
X752734Y315025D01*
X752484Y314817D01*
X752067Y314650D01*
X751692Y314608D01*
X751317Y314692D01*
X751067Y314817D01*
X750817Y315067D01*
X750650Y315358D01*
X750567Y315650D01*
Y315942D01*
X750650Y316233D01*
X750775Y316483D01*
X750942Y316692D01*
G01X751067Y317833D02*
X750775Y318083D01*
X750609Y318417D01*
X750567Y318792D01*
X750609Y319125D01*
X750817Y319458D01*
X751067Y319667D01*
X751317Y319708D01*
X751609Y319625D01*
X751817Y319333D01*
X751900Y319042D01*
Y318667D01*
G01Y319042D02*
X752025Y319292D01*
X752234Y319500D01*
X752484Y319583D01*
X752734Y319500D01*
X752942Y319292D01*
X753067Y318917D01*
X753025Y318542D01*
X752859Y318167D01*
G01X753067Y321850D02*
X752984Y321517D01*
X752775Y321267D01*
X752525Y321100D01*
X752192Y320975D01*
X751817Y320933D01*
X751442Y320975D01*
X751109Y321100D01*
X750859Y321267D01*
X750650Y321517D01*
X750567Y321850D01*
X750650Y322183D01*
X750859Y322433D01*
X751109Y322600D01*
X751442Y322725D01*
X751817Y322767D01*
X752192Y322725D01*
X752525Y322600D01*
X752775Y322433D01*
X752984Y322183D01*
X753067Y321850D01*
G01X750567Y325450D02*
X753067D01*
X751275Y323908D01*
Y325992D01*
G01X765792Y317567D02*
X765917Y317317D01*
X766000Y317025D01*
Y316692D01*
X765875Y316317D01*
X765667Y316025D01*
X765417Y315817D01*
X765000Y315650D01*
X764625Y315608D01*
X764250Y315692D01*
X764000Y315817D01*
X763750Y316067D01*
X763583Y316358D01*
X763500Y316650D01*
Y316942D01*
X763583Y317233D01*
X763708Y317483D01*
X763875Y317692D01*
G01X764000Y318833D02*
X763708Y319083D01*
X763542Y319417D01*
X763500Y319792D01*
X763542Y320125D01*
X763750Y320458D01*
X764000Y320667D01*
X764250Y320708D01*
X764542Y320625D01*
X764750Y320333D01*
X764833Y320042D01*
Y319667D01*
G01Y320042D02*
X764958Y320292D01*
X765167Y320500D01*
X765417Y320583D01*
X765667Y320500D01*
X765875Y320292D01*
X766000Y319917D01*
X765958Y319542D01*
X765792Y319167D01*
G01X766000Y322850D02*
X765917Y322517D01*
X765708Y322267D01*
X765458Y322100D01*
X765125Y321975D01*
X764750Y321933D01*
X764375Y321975D01*
X764042Y322100D01*
X763792Y322267D01*
X763583Y322517D01*
X763500Y322850D01*
X763583Y323183D01*
X763792Y323433D01*
X764042Y323600D01*
X764375Y323725D01*
X764750Y323767D01*
X765125Y323725D01*
X765458Y323600D01*
X765708Y323433D01*
X765917Y323183D01*
X766000Y322850D01*
G01X764000Y325033D02*
X763708Y325283D01*
X763542Y325617D01*
X763500Y325992D01*
X763542Y326325D01*
X763750Y326658D01*
X764000Y326867D01*
X764250Y326908D01*
X764542Y326825D01*
X764750Y326533D01*
X764833Y326242D01*
Y325867D01*
G01Y326242D02*
X764958Y326492D01*
X765167Y326700D01*
X765417Y326783D01*
X765667Y326700D01*
X765875Y326492D01*
X766000Y326117D01*
X765958Y325742D01*
X765792Y325367D01*
G01X769192Y314867D02*
X769317Y314617D01*
X769400Y314325D01*
Y313992D01*
X769275Y313617D01*
X769067Y313325D01*
X768817Y313117D01*
X768400Y312950D01*
X768025Y312908D01*
X767650Y312992D01*
X767400Y313117D01*
X767150Y313367D01*
X766983Y313658D01*
X766900Y313950D01*
Y314242D01*
X766983Y314533D01*
X767108Y314783D01*
X767275Y314992D01*
G01X767400Y316133D02*
X767108Y316383D01*
X766942Y316717D01*
X766900Y317092D01*
X766942Y317425D01*
X767150Y317758D01*
X767400Y317967D01*
X767650Y318008D01*
X767942Y317925D01*
X768150Y317633D01*
X768233Y317342D01*
Y316967D01*
G01Y317342D02*
X768358Y317592D01*
X768567Y317800D01*
X768817Y317883D01*
X769067Y317800D01*
X769275Y317592D01*
X769400Y317217D01*
X769358Y316842D01*
X769192Y316467D01*
G01X769400Y320150D02*
X769317Y319817D01*
X769108Y319567D01*
X768858Y319400D01*
X768525Y319275D01*
X768150Y319233D01*
X767775Y319275D01*
X767442Y319400D01*
X767192Y319567D01*
X766983Y319817D01*
X766900Y320150D01*
X766983Y320483D01*
X767192Y320733D01*
X767442Y320900D01*
X767775Y321025D01*
X768150Y321067D01*
X768525Y321025D01*
X768858Y320900D01*
X769108Y320733D01*
X769317Y320483D01*
X769400Y320150D01*
G01X768983Y322458D02*
X769233Y322708D01*
X769358Y323000D01*
X769400Y323333D01*
X769317Y323750D01*
X769108Y324042D01*
X768858Y324125D01*
X768608Y324083D01*
X768400Y323917D01*
X767983Y323083D01*
X767692Y322708D01*
X767275Y322458D01*
X766900Y322375D01*
Y324125D01*
G01X773092Y317667D02*
X773217Y317417D01*
X773300Y317125D01*
Y316792D01*
X773175Y316417D01*
X772967Y316125D01*
X772717Y315917D01*
X772300Y315750D01*
X771925Y315708D01*
X771550Y315792D01*
X771300Y315917D01*
X771050Y316167D01*
X770883Y316458D01*
X770800Y316750D01*
Y317042D01*
X770883Y317333D01*
X771008Y317583D01*
X771175Y317792D01*
G01X771300Y318933D02*
X771008Y319183D01*
X770842Y319517D01*
X770800Y319892D01*
X770842Y320225D01*
X771050Y320558D01*
X771300Y320767D01*
X771550Y320808D01*
X771842Y320725D01*
X772050Y320433D01*
X772133Y320142D01*
Y319767D01*
G01Y320142D02*
X772258Y320392D01*
X772467Y320600D01*
X772717Y320683D01*
X772967Y320600D01*
X773175Y320392D01*
X773300Y320017D01*
X773258Y319642D01*
X773092Y319267D01*
G01X773300Y322950D02*
X773217Y322617D01*
X773008Y322367D01*
X772758Y322200D01*
X772425Y322075D01*
X772050Y322033D01*
X771675Y322075D01*
X771342Y322200D01*
X771092Y322367D01*
X770883Y322617D01*
X770800Y322950D01*
X770883Y323283D01*
X771092Y323533D01*
X771342Y323700D01*
X771675Y323825D01*
X772050Y323867D01*
X772425Y323825D01*
X772758Y323700D01*
X773008Y323533D01*
X773217Y323283D01*
X773300Y322950D01*
G01X770800Y326050D02*
X773300D01*
X772800Y325550D01*
G01X770800D02*
Y326550D01*
G01X771859Y287367D02*
X771984Y287117D01*
X772067Y286825D01*
Y286492D01*
X771942Y286117D01*
X771734Y285825D01*
X771484Y285617D01*
X771067Y285450D01*
X770692Y285408D01*
X770317Y285492D01*
X770067Y285617D01*
X769817Y285867D01*
X769650Y286158D01*
X769567Y286450D01*
Y286742D01*
X769650Y287033D01*
X769775Y287283D01*
X769942Y287492D01*
G01X770067Y288633D02*
X769775Y288883D01*
X769609Y289217D01*
X769567Y289592D01*
X769609Y289925D01*
X769817Y290258D01*
X770067Y290467D01*
X770317Y290508D01*
X770609Y290425D01*
X770817Y290133D01*
X770900Y289842D01*
Y289467D01*
G01Y289842D02*
X771025Y290092D01*
X771234Y290300D01*
X771484Y290383D01*
X771734Y290300D01*
X771942Y290092D01*
X772067Y289717D01*
X772025Y289342D01*
X771859Y288967D01*
G01X769567Y292567D02*
X770109Y292650D01*
X770567Y292775D01*
X770984Y292942D01*
X771442Y293150D01*
X772067Y293483D01*
Y291817D01*
G01Y295750D02*
X771984Y295417D01*
X771775Y295167D01*
X771525Y295000D01*
X771192Y294875D01*
X770817Y294833D01*
X770442Y294875D01*
X770109Y295000D01*
X769859Y295167D01*
X769650Y295417D01*
X769567Y295750D01*
X769650Y296083D01*
X769859Y296333D01*
X770109Y296500D01*
X770442Y296625D01*
X770817Y296667D01*
X771192Y296625D01*
X771525Y296500D01*
X771775Y296333D01*
X771984Y296083D01*
X772067Y295750D01*
G01X772892Y305167D02*
X773017Y304917D01*
X773100Y304625D01*
Y304292D01*
X772975Y303917D01*
X772767Y303625D01*
X772517Y303417D01*
X772100Y303250D01*
X771725Y303208D01*
X771350Y303292D01*
X771100Y303417D01*
X770850Y303667D01*
X770683Y303958D01*
X770600Y304250D01*
Y304542D01*
X770683Y304833D01*
X770808Y305083D01*
X770975Y305292D01*
G01X771100Y306433D02*
X770808Y306683D01*
X770642Y307017D01*
X770600Y307392D01*
X770642Y307725D01*
X770850Y308058D01*
X771100Y308267D01*
X771350Y308308D01*
X771642Y308225D01*
X771850Y307933D01*
X771933Y307642D01*
Y307267D01*
G01Y307642D02*
X772058Y307892D01*
X772267Y308100D01*
X772517Y308183D01*
X772767Y308100D01*
X772975Y307892D01*
X773100Y307517D01*
X773058Y307142D01*
X772892Y306767D01*
G01X770600Y310367D02*
X771142Y310450D01*
X771600Y310575D01*
X772017Y310742D01*
X772475Y310950D01*
X773100Y311283D01*
Y309617D01*
G01X772683Y312758D02*
X772933Y313008D01*
X773058Y313300D01*
X773100Y313633D01*
X773017Y314050D01*
X772808Y314342D01*
X772558Y314425D01*
X772308Y314383D01*
X772100Y314217D01*
X771683Y313383D01*
X771392Y313008D01*
X770975Y312758D01*
X770600Y312675D01*
Y314425D01*
G01X788959Y462267D02*
X789084Y462017D01*
X789167Y461725D01*
Y461392D01*
X789042Y461017D01*
X788834Y460725D01*
X788584Y460517D01*
X788167Y460350D01*
X787792Y460308D01*
X787417Y460392D01*
X787167Y460517D01*
X786917Y460767D01*
X786750Y461058D01*
X786667Y461350D01*
Y461642D01*
X786750Y461933D01*
X786875Y462183D01*
X787042Y462392D01*
G01X788750Y463658D02*
X789000Y463908D01*
X789125Y464200D01*
X789167Y464533D01*
X789084Y464950D01*
X788875Y465242D01*
X788625Y465325D01*
X788375Y465283D01*
X788167Y465117D01*
X787750Y464283D01*
X787459Y463908D01*
X787042Y463658D01*
X786667Y463575D01*
Y465325D01*
G01X787709Y466758D02*
X788000Y467050D01*
X788167Y467300D01*
X788250Y467633D01*
X788167Y467925D01*
X788000Y468133D01*
X787750Y468300D01*
X787459Y468342D01*
X787209Y468300D01*
X786959Y468133D01*
X786750Y467883D01*
X786667Y467592D01*
X786750Y467258D01*
X787000Y466967D01*
X787375Y466800D01*
X787792Y466758D01*
X788334Y466842D01*
X788625Y466967D01*
X788917Y467175D01*
X789125Y467467D01*
X789167Y467758D01*
X789084Y468050D01*
X788875Y468258D01*
G01X789167Y470650D02*
X789084Y470317D01*
X788875Y470067D01*
X788625Y469900D01*
X788292Y469775D01*
X787917Y469733D01*
X787542Y469775D01*
X787209Y469900D01*
X786959Y470067D01*
X786750Y470317D01*
X786667Y470650D01*
X786750Y470983D01*
X786959Y471233D01*
X787209Y471400D01*
X787542Y471525D01*
X787917Y471567D01*
X788292Y471525D01*
X788625Y471400D01*
X788875Y471233D01*
X789084Y470983D01*
X789167Y470650D01*
G01X790600Y438200D02*
Y443700D01*
G01X782600Y438200D02*
X790600D01*
G01X782600Y443700D02*
Y438200D01*
G01Y455800D02*
Y450300D01*
G01X790600Y455800D02*
X782600D01*
G01X790600Y450300D02*
Y455800D01*
G01X779459Y462267D02*
X779584Y462017D01*
X779667Y461725D01*
Y461392D01*
X779542Y461017D01*
X779334Y460725D01*
X779084Y460517D01*
X778667Y460350D01*
X778292Y460308D01*
X777917Y460392D01*
X777667Y460517D01*
X777417Y460767D01*
X777250Y461058D01*
X777167Y461350D01*
Y461642D01*
X777250Y461933D01*
X777375Y462183D01*
X777542Y462392D01*
G01X779250Y463658D02*
X779500Y463908D01*
X779625Y464200D01*
X779667Y464533D01*
X779584Y464950D01*
X779375Y465242D01*
X779125Y465325D01*
X778875Y465283D01*
X778667Y465117D01*
X778250Y464283D01*
X777959Y463908D01*
X777542Y463658D01*
X777167Y463575D01*
Y465325D01*
G01X778209Y466758D02*
X778500Y467050D01*
X778667Y467300D01*
X778750Y467633D01*
X778667Y467925D01*
X778500Y468133D01*
X778250Y468300D01*
X777959Y468342D01*
X777709Y468300D01*
X777459Y468133D01*
X777250Y467883D01*
X777167Y467592D01*
X777250Y467258D01*
X777500Y466967D01*
X777875Y466800D01*
X778292Y466758D01*
X778834Y466842D01*
X779125Y466967D01*
X779417Y467175D01*
X779625Y467467D01*
X779667Y467758D01*
X779584Y468050D01*
X779375Y468258D01*
G01X777167Y470650D02*
X779667D01*
X779167Y470150D01*
G01X777167D02*
Y471150D01*
G01X781600Y438200D02*
Y443700D01*
G01X773600Y438200D02*
X781600D01*
G01X773600Y443700D02*
Y438200D01*
G01Y455800D02*
Y450300D01*
G01X781600Y455800D02*
X773600D01*
G01X781600Y450300D02*
Y455800D01*
G01X742100Y486084D02*
X738100D01*
Y493484D01*
G01X737600Y486084D02*
X733600D01*
Y493484D01*
G01X746600Y486084D02*
X742600D01*
Y493484D01*
G01X748600Y494300D02*
X752600D01*
Y486900D01*
G01X766992Y486267D02*
X767117Y486017D01*
X767200Y485725D01*
Y485392D01*
X767075Y485017D01*
X766867Y484725D01*
X766617Y484517D01*
X766200Y484350D01*
X765825Y484308D01*
X765450Y484392D01*
X765200Y484517D01*
X764950Y484767D01*
X764783Y485058D01*
X764700Y485350D01*
Y485642D01*
X764783Y485933D01*
X764908Y486183D01*
X765075Y486392D01*
G01X766783Y487658D02*
X767033Y487908D01*
X767158Y488200D01*
X767200Y488533D01*
X767117Y488950D01*
X766908Y489242D01*
X766658Y489325D01*
X766408Y489283D01*
X766200Y489117D01*
X765783Y488283D01*
X765492Y487908D01*
X765075Y487658D01*
X764700Y487575D01*
Y489325D01*
G01Y491550D02*
X764742Y491842D01*
X764867Y492175D01*
X765075Y492383D01*
X765367Y492467D01*
X765658Y492383D01*
X765908Y492133D01*
X766033Y491758D01*
Y491342D01*
X766117Y491092D01*
X766325Y490883D01*
X766617Y490800D01*
X766908Y490925D01*
X767117Y491217D01*
X767200Y491550D01*
X767117Y491883D01*
X766908Y492175D01*
X766617Y492300D01*
X766325Y492217D01*
X766117Y492008D01*
X766033Y491758D01*
Y491342D01*
X765908Y490967D01*
X765658Y490717D01*
X765367Y490633D01*
X765075Y490717D01*
X764867Y490925D01*
X764742Y491258D01*
X764700Y491550D01*
G01X765742Y493858D02*
X766033Y494150D01*
X766200Y494400D01*
X766283Y494733D01*
X766200Y495025D01*
X766033Y495233D01*
X765783Y495400D01*
X765492Y495442D01*
X765242Y495400D01*
X764992Y495233D01*
X764783Y494983D01*
X764700Y494692D01*
X764783Y494358D01*
X765033Y494067D01*
X765408Y493900D01*
X765825Y493858D01*
X766367Y493942D01*
X766658Y494067D01*
X766950Y494275D01*
X767158Y494567D01*
X767200Y494858D01*
X767117Y495150D01*
X766908Y495358D01*
G01X755026Y467791D02*
X755276Y467916D01*
X755568Y467999D01*
X755901D01*
X756276Y467874D01*
X756568Y467666D01*
X756776Y467416D01*
X756943Y466999D01*
X756985Y466624D01*
X756901Y466249D01*
X756776Y465999D01*
X756526Y465749D01*
X756235Y465582D01*
X755943Y465499D01*
X755651D01*
X755360Y465582D01*
X755110Y465707D01*
X754901Y465874D01*
G01X753635Y467582D02*
X753385Y467832D01*
X753093Y467957D01*
X752760Y467999D01*
X752343Y467916D01*
X752051Y467707D01*
X751968Y467457D01*
X752010Y467207D01*
X752176Y466999D01*
X753010Y466582D01*
X753385Y466291D01*
X753635Y465874D01*
X753718Y465499D01*
X751968D01*
G01X749743D02*
X749451Y465541D01*
X749118Y465666D01*
X748910Y465874D01*
X748826Y466166D01*
X748910Y466457D01*
X749160Y466707D01*
X749535Y466832D01*
X749951D01*
X750201Y466916D01*
X750410Y467124D01*
X750493Y467416D01*
X750368Y467707D01*
X750076Y467916D01*
X749743Y467999D01*
X749410Y467916D01*
X749118Y467707D01*
X748993Y467416D01*
X749076Y467124D01*
X749285Y466916D01*
X749535Y466832D01*
X749951D01*
X750326Y466707D01*
X750576Y466457D01*
X750660Y466166D01*
X750576Y465874D01*
X750368Y465666D01*
X750035Y465541D01*
X749743Y465499D01*
G01X747560Y465999D02*
X747310Y465707D01*
X746976Y465541D01*
X746601Y465499D01*
X746268Y465541D01*
X745935Y465749D01*
X745726Y465999D01*
X745685Y466249D01*
X745768Y466541D01*
X746060Y466749D01*
X746351Y466832D01*
X746726D01*
G01X746351D02*
X746101Y466957D01*
X745893Y467166D01*
X745810Y467416D01*
X745893Y467666D01*
X746101Y467874D01*
X746476Y467999D01*
X746851Y467957D01*
X747226Y467791D01*
G01X758400Y478900D02*
X752900D01*
G01X758400Y470900D02*
Y478900D01*
G01X752900Y470900D02*
X758400D01*
G01X740800D02*
X746300D01*
G01X740800Y478900D02*
Y470900D01*
G01X746300Y478900D02*
X740800D01*
G01X800149Y630735D02*
X800399Y630860D01*
X800691Y630943D01*
X801024D01*
X801399Y630818D01*
X801691Y630610D01*
X801899Y630360D01*
X802066Y629943D01*
X802108Y629568D01*
X802024Y629193D01*
X801899Y628943D01*
X801649Y628693D01*
X801358Y628526D01*
X801066Y628443D01*
X800774D01*
X800483Y628526D01*
X800233Y628651D01*
X800024Y628818D01*
G01X797466Y628443D02*
Y630943D01*
X799008Y629151D01*
X796924D01*
G01X795658Y630526D02*
X795408Y630776D01*
X795116Y630901D01*
X794783Y630943D01*
X794366Y630860D01*
X794074Y630651D01*
X793991Y630401D01*
X794033Y630151D01*
X794199Y629943D01*
X795033Y629526D01*
X795408Y629235D01*
X795658Y628818D01*
X795741Y628443D01*
X793991D01*
G01X792558Y629485D02*
X792266Y629776D01*
X792016Y629943D01*
X791683Y630026D01*
X791391Y629943D01*
X791183Y629776D01*
X791016Y629526D01*
X790974Y629235D01*
X791016Y628985D01*
X791183Y628735D01*
X791433Y628526D01*
X791724Y628443D01*
X792058Y628526D01*
X792349Y628776D01*
X792516Y629151D01*
X792558Y629568D01*
X792474Y630110D01*
X792349Y630401D01*
X792141Y630693D01*
X791849Y630901D01*
X791558Y630943D01*
X791266Y630860D01*
X791058Y630651D01*
G01X800249Y649335D02*
X800499Y649460D01*
X800791Y649543D01*
X801124D01*
X801499Y649418D01*
X801791Y649210D01*
X801999Y648960D01*
X802166Y648543D01*
X802208Y648168D01*
X802124Y647793D01*
X801999Y647543D01*
X801749Y647293D01*
X801458Y647126D01*
X801166Y647043D01*
X800874D01*
X800583Y647126D01*
X800333Y647251D01*
X800124Y647418D01*
G01X797566Y647043D02*
Y649543D01*
X799108Y647751D01*
X797024D01*
G01X795758Y649126D02*
X795508Y649376D01*
X795216Y649501D01*
X794883Y649543D01*
X794466Y649460D01*
X794174Y649251D01*
X794091Y649001D01*
X794133Y648751D01*
X794299Y648543D01*
X795133Y648126D01*
X795508Y647835D01*
X795758Y647418D01*
X795841Y647043D01*
X794091D01*
G01X792574Y647335D02*
X792283Y647126D01*
X791949Y647043D01*
X791616Y647126D01*
X791324Y647376D01*
X791116Y647751D01*
X791033Y648126D01*
Y648585D01*
X791116Y648960D01*
X791324Y649293D01*
X791574Y649460D01*
X791866Y649543D01*
X792199Y649460D01*
X792449Y649293D01*
X792616Y649043D01*
X792699Y648710D01*
X792616Y648418D01*
X792408Y648126D01*
X792158Y647960D01*
X791866Y647918D01*
X791533Y648001D01*
X791283Y648210D01*
X791033Y648585D01*
G01X772949Y634435D02*
X773199Y634560D01*
X773491Y634643D01*
X773824D01*
X774199Y634518D01*
X774491Y634310D01*
X774699Y634060D01*
X774866Y633643D01*
X774908Y633268D01*
X774824Y632893D01*
X774699Y632643D01*
X774449Y632393D01*
X774158Y632226D01*
X773866Y632143D01*
X773574D01*
X773283Y632226D01*
X773033Y632351D01*
X772824Y632518D01*
G01X770266Y632143D02*
Y634643D01*
X771808Y632851D01*
X769724D01*
G01X767749Y632143D02*
X767666Y632685D01*
X767541Y633143D01*
X767374Y633560D01*
X767166Y634018D01*
X766833Y634643D01*
X768499D01*
G01X765483Y632518D02*
X765233Y632310D01*
X764941Y632185D01*
X764566Y632143D01*
X764191Y632226D01*
X763899Y632393D01*
X763691Y632685D01*
X763649Y633018D01*
X763733Y633351D01*
X763941Y633560D01*
X764233Y633726D01*
X764524Y633768D01*
X764816Y633726D01*
X765191Y633560D01*
X765066Y634643D01*
X763941D01*
G01X772949Y618435D02*
X773199Y618560D01*
X773491Y618643D01*
X773824D01*
X774199Y618518D01*
X774491Y618310D01*
X774699Y618060D01*
X774866Y617643D01*
X774908Y617268D01*
X774824Y616893D01*
X774699Y616643D01*
X774449Y616393D01*
X774158Y616226D01*
X773866Y616143D01*
X773574D01*
X773283Y616226D01*
X773033Y616351D01*
X772824Y616518D01*
G01X770266Y616143D02*
Y618643D01*
X771808Y616851D01*
X769724D01*
G01X767749Y616143D02*
X767666Y616685D01*
X767541Y617143D01*
X767374Y617560D01*
X767166Y618018D01*
X766833Y618643D01*
X768499D01*
G01X765274Y616435D02*
X764983Y616226D01*
X764649Y616143D01*
X764316Y616226D01*
X764024Y616476D01*
X763816Y616851D01*
X763733Y617226D01*
Y617685D01*
X763816Y618060D01*
X764024Y618393D01*
X764274Y618560D01*
X764566Y618643D01*
X764899Y618560D01*
X765149Y618393D01*
X765316Y618143D01*
X765399Y617810D01*
X765316Y617518D01*
X765108Y617226D01*
X764858Y617060D01*
X764566Y617018D01*
X764233Y617101D01*
X763983Y617310D01*
X763733Y617685D01*
G01X772949Y614435D02*
X773199Y614560D01*
X773491Y614643D01*
X773824D01*
X774199Y614518D01*
X774491Y614310D01*
X774699Y614060D01*
X774866Y613643D01*
X774908Y613268D01*
X774824Y612893D01*
X774699Y612643D01*
X774449Y612393D01*
X774158Y612226D01*
X773866Y612143D01*
X773574D01*
X773283Y612226D01*
X773033Y612351D01*
X772824Y612518D01*
G01X770266Y612143D02*
Y614643D01*
X771808Y612851D01*
X769724D01*
G01X767666Y612143D02*
X767374Y612185D01*
X767041Y612310D01*
X766833Y612518D01*
X766749Y612810D01*
X766833Y613101D01*
X767083Y613351D01*
X767458Y613476D01*
X767874D01*
X768124Y613560D01*
X768333Y613768D01*
X768416Y614060D01*
X768291Y614351D01*
X767999Y614560D01*
X767666Y614643D01*
X767333Y614560D01*
X767041Y614351D01*
X766916Y614060D01*
X766999Y613768D01*
X767208Y613560D01*
X767458Y613476D01*
X767874D01*
X768249Y613351D01*
X768499Y613101D01*
X768583Y612810D01*
X768499Y612518D01*
X768291Y612310D01*
X767958Y612185D01*
X767666Y612143D01*
G01X764566Y614643D02*
X764899Y614560D01*
X765149Y614351D01*
X765316Y614101D01*
X765441Y613768D01*
X765483Y613393D01*
X765441Y613018D01*
X765316Y612685D01*
X765149Y612435D01*
X764899Y612226D01*
X764566Y612143D01*
X764233Y612226D01*
X763983Y612435D01*
X763816Y612685D01*
X763691Y613018D01*
X763649Y613393D01*
X763691Y613768D01*
X763816Y614101D01*
X763983Y614351D01*
X764233Y614560D01*
X764566Y614643D01*
G01X772949Y638435D02*
X773199Y638560D01*
X773491Y638643D01*
X773824D01*
X774199Y638518D01*
X774491Y638310D01*
X774699Y638060D01*
X774866Y637643D01*
X774908Y637268D01*
X774824Y636893D01*
X774699Y636643D01*
X774449Y636393D01*
X774158Y636226D01*
X773866Y636143D01*
X773574D01*
X773283Y636226D01*
X773033Y636351D01*
X772824Y636518D01*
G01X770266Y636143D02*
Y638643D01*
X771808Y636851D01*
X769724D01*
G01X767749Y636143D02*
X767666Y636685D01*
X767541Y637143D01*
X767374Y637560D01*
X767166Y638018D01*
X766833Y638643D01*
X768499D01*
G01X764066Y636143D02*
Y638643D01*
X765608Y636851D01*
X763524D01*
G01X772949Y642435D02*
X773199Y642560D01*
X773491Y642643D01*
X773824D01*
X774199Y642518D01*
X774491Y642310D01*
X774699Y642060D01*
X774866Y641643D01*
X774908Y641268D01*
X774824Y640893D01*
X774699Y640643D01*
X774449Y640393D01*
X774158Y640226D01*
X773866Y640143D01*
X773574D01*
X773283Y640226D01*
X773033Y640351D01*
X772824Y640518D01*
G01X770266Y640143D02*
Y642643D01*
X771808Y640851D01*
X769724D01*
G01X767749Y640143D02*
X767666Y640685D01*
X767541Y641143D01*
X767374Y641560D01*
X767166Y642018D01*
X766833Y642643D01*
X768499D01*
G01X765483Y640643D02*
X765233Y640351D01*
X764899Y640185D01*
X764524Y640143D01*
X764191Y640185D01*
X763858Y640393D01*
X763649Y640643D01*
X763608Y640893D01*
X763691Y641185D01*
X763983Y641393D01*
X764274Y641476D01*
X764649D01*
G01X764274D02*
X764024Y641601D01*
X763816Y641810D01*
X763733Y642060D01*
X763816Y642310D01*
X764024Y642518D01*
X764399Y642643D01*
X764774Y642601D01*
X765149Y642435D01*
G01X772949Y646435D02*
X773199Y646560D01*
X773491Y646643D01*
X773824D01*
X774199Y646518D01*
X774491Y646310D01*
X774699Y646060D01*
X774866Y645643D01*
X774908Y645268D01*
X774824Y644893D01*
X774699Y644643D01*
X774449Y644393D01*
X774158Y644226D01*
X773866Y644143D01*
X773574D01*
X773283Y644226D01*
X773033Y644351D01*
X772824Y644518D01*
G01X770266Y644143D02*
Y646643D01*
X771808Y644851D01*
X769724D01*
G01X768458Y645185D02*
X768166Y645476D01*
X767916Y645643D01*
X767583Y645726D01*
X767291Y645643D01*
X767083Y645476D01*
X766916Y645226D01*
X766874Y644935D01*
X766916Y644685D01*
X767083Y644435D01*
X767333Y644226D01*
X767624Y644143D01*
X767958Y644226D01*
X768249Y644476D01*
X768416Y644851D01*
X768458Y645268D01*
X768374Y645810D01*
X768249Y646101D01*
X768041Y646393D01*
X767749Y646601D01*
X767458Y646643D01*
X767166Y646560D01*
X766958Y646351D01*
G01X764649Y644143D02*
X764566Y644685D01*
X764441Y645143D01*
X764274Y645560D01*
X764066Y646018D01*
X763733Y646643D01*
X765399D01*
G01X783008Y655310D02*
X783133Y655060D01*
X783216Y654768D01*
Y654435D01*
X783091Y654060D01*
X782883Y653768D01*
X782633Y653560D01*
X782216Y653393D01*
X781841Y653351D01*
X781466Y653435D01*
X781216Y653560D01*
X780966Y653810D01*
X780799Y654101D01*
X780716Y654393D01*
Y654685D01*
X780799Y654976D01*
X780924Y655226D01*
X781091Y655435D01*
G01X780716Y657993D02*
X783216D01*
X781424Y656451D01*
Y658535D01*
G01X781758Y659801D02*
X782049Y660093D01*
X782216Y660343D01*
X782299Y660676D01*
X782216Y660968D01*
X782049Y661176D01*
X781799Y661343D01*
X781508Y661385D01*
X781258Y661343D01*
X781008Y661176D01*
X780799Y660926D01*
X780716Y660635D01*
X780799Y660301D01*
X781049Y660010D01*
X781424Y659843D01*
X781841Y659801D01*
X782383Y659885D01*
X782674Y660010D01*
X782966Y660218D01*
X783174Y660510D01*
X783216Y660801D01*
X783133Y661093D01*
X782924Y661301D01*
G01X780716Y663693D02*
X780758Y663985D01*
X780883Y664318D01*
X781091Y664526D01*
X781383Y664610D01*
X781674Y664526D01*
X781924Y664276D01*
X782049Y663901D01*
Y663485D01*
X782133Y663235D01*
X782341Y663026D01*
X782633Y662943D01*
X782924Y663068D01*
X783133Y663360D01*
X783216Y663693D01*
X783133Y664026D01*
X782924Y664318D01*
X782633Y664443D01*
X782341Y664360D01*
X782133Y664151D01*
X782049Y663901D01*
Y663485D01*
X781924Y663110D01*
X781674Y662860D01*
X781383Y662776D01*
X781091Y662860D01*
X780883Y663068D01*
X780758Y663401D01*
X780716Y663693D01*
G01X787249Y614435D02*
X787499Y614560D01*
X787791Y614643D01*
X788124D01*
X788499Y614518D01*
X788791Y614310D01*
X788999Y614060D01*
X789166Y613643D01*
X789208Y613268D01*
X789124Y612893D01*
X788999Y612643D01*
X788749Y612393D01*
X788458Y612226D01*
X788166Y612143D01*
X787874D01*
X787583Y612226D01*
X787333Y612351D01*
X787124Y612518D01*
G01X784566Y612143D02*
Y614643D01*
X786108Y612851D01*
X784024D01*
G01X782883Y612643D02*
X782633Y612351D01*
X782299Y612185D01*
X781924Y612143D01*
X781591Y612185D01*
X781258Y612393D01*
X781049Y612643D01*
X781008Y612893D01*
X781091Y613185D01*
X781383Y613393D01*
X781674Y613476D01*
X782049D01*
G01X781674D02*
X781424Y613601D01*
X781216Y613810D01*
X781133Y614060D01*
X781216Y614310D01*
X781424Y614518D01*
X781799Y614643D01*
X782174Y614601D01*
X782549Y614435D01*
G01X778866Y612143D02*
Y614643D01*
X779366Y614143D01*
G01Y612143D02*
X778366D01*
G01X787249Y618435D02*
X787499Y618560D01*
X787791Y618643D01*
X788124D01*
X788499Y618518D01*
X788791Y618310D01*
X788999Y618060D01*
X789166Y617643D01*
X789208Y617268D01*
X789124Y616893D01*
X788999Y616643D01*
X788749Y616393D01*
X788458Y616226D01*
X788166Y616143D01*
X787874D01*
X787583Y616226D01*
X787333Y616351D01*
X787124Y616518D01*
G01X784566Y616143D02*
Y618643D01*
X786108Y616851D01*
X784024D01*
G01X781466Y616143D02*
Y618643D01*
X783008Y616851D01*
X780924D01*
G01X778366Y616143D02*
Y618643D01*
X779908Y616851D01*
X777824D01*
G01X800249Y645335D02*
X800499Y645460D01*
X800791Y645543D01*
X801124D01*
X801499Y645418D01*
X801791Y645210D01*
X801999Y644960D01*
X802166Y644543D01*
X802208Y644168D01*
X802124Y643793D01*
X801999Y643543D01*
X801749Y643293D01*
X801458Y643126D01*
X801166Y643043D01*
X800874D01*
X800583Y643126D01*
X800333Y643251D01*
X800124Y643418D01*
G01X797566Y643043D02*
Y645543D01*
X799108Y643751D01*
X797024D01*
G01X795883Y643543D02*
X795633Y643251D01*
X795299Y643085D01*
X794924Y643043D01*
X794591Y643085D01*
X794258Y643293D01*
X794049Y643543D01*
X794008Y643793D01*
X794091Y644085D01*
X794383Y644293D01*
X794674Y644376D01*
X795049D01*
G01X794674D02*
X794424Y644501D01*
X794216Y644710D01*
X794133Y644960D01*
X794216Y645210D01*
X794424Y645418D01*
X794799Y645543D01*
X795174Y645501D01*
X795549Y645335D01*
G01X791866Y645543D02*
X792199Y645460D01*
X792449Y645251D01*
X792616Y645001D01*
X792741Y644668D01*
X792783Y644293D01*
X792741Y643918D01*
X792616Y643585D01*
X792449Y643335D01*
X792199Y643126D01*
X791866Y643043D01*
X791533Y643126D01*
X791283Y643335D01*
X791116Y643585D01*
X790991Y643918D01*
X790949Y644293D01*
X790991Y644668D01*
X791116Y645001D01*
X791283Y645251D01*
X791533Y645460D01*
X791866Y645543D01*
G01X772949Y630435D02*
X773199Y630560D01*
X773491Y630643D01*
X773824D01*
X774199Y630518D01*
X774491Y630310D01*
X774699Y630060D01*
X774866Y629643D01*
X774908Y629268D01*
X774824Y628893D01*
X774699Y628643D01*
X774449Y628393D01*
X774158Y628226D01*
X773866Y628143D01*
X773574D01*
X773283Y628226D01*
X773033Y628351D01*
X772824Y628518D01*
G01X770266Y628143D02*
Y630643D01*
X771808Y628851D01*
X769724D01*
G01X767749Y628143D02*
X767666Y628685D01*
X767541Y629143D01*
X767374Y629560D01*
X767166Y630018D01*
X766833Y630643D01*
X768499D01*
G01X765358Y629185D02*
X765066Y629476D01*
X764816Y629643D01*
X764483Y629726D01*
X764191Y629643D01*
X763983Y629476D01*
X763816Y629226D01*
X763774Y628935D01*
X763816Y628685D01*
X763983Y628435D01*
X764233Y628226D01*
X764524Y628143D01*
X764858Y628226D01*
X765149Y628476D01*
X765316Y628851D01*
X765358Y629268D01*
X765274Y629810D01*
X765149Y630101D01*
X764941Y630393D01*
X764649Y630601D01*
X764358Y630643D01*
X764066Y630560D01*
X763858Y630351D01*
G01X772949Y626435D02*
X773199Y626560D01*
X773491Y626643D01*
X773824D01*
X774199Y626518D01*
X774491Y626310D01*
X774699Y626060D01*
X774866Y625643D01*
X774908Y625268D01*
X774824Y624893D01*
X774699Y624643D01*
X774449Y624393D01*
X774158Y624226D01*
X773866Y624143D01*
X773574D01*
X773283Y624226D01*
X773033Y624351D01*
X772824Y624518D01*
G01X770266Y624143D02*
Y626643D01*
X771808Y624851D01*
X769724D01*
G01X767749Y624143D02*
X767666Y624685D01*
X767541Y625143D01*
X767374Y625560D01*
X767166Y626018D01*
X766833Y626643D01*
X768499D01*
G01X764649Y624143D02*
X764566Y624685D01*
X764441Y625143D01*
X764274Y625560D01*
X764066Y626018D01*
X763733Y626643D01*
X765399D01*
G01X772949Y622435D02*
X773199Y622560D01*
X773491Y622643D01*
X773824D01*
X774199Y622518D01*
X774491Y622310D01*
X774699Y622060D01*
X774866Y621643D01*
X774908Y621268D01*
X774824Y620893D01*
X774699Y620643D01*
X774449Y620393D01*
X774158Y620226D01*
X773866Y620143D01*
X773574D01*
X773283Y620226D01*
X773033Y620351D01*
X772824Y620518D01*
G01X770266Y620143D02*
Y622643D01*
X771808Y620851D01*
X769724D01*
G01X767749Y620143D02*
X767666Y620685D01*
X767541Y621143D01*
X767374Y621560D01*
X767166Y622018D01*
X766833Y622643D01*
X768499D01*
G01X764566Y620143D02*
X764274Y620185D01*
X763941Y620310D01*
X763733Y620518D01*
X763649Y620810D01*
X763733Y621101D01*
X763983Y621351D01*
X764358Y621476D01*
X764774D01*
X765024Y621560D01*
X765233Y621768D01*
X765316Y622060D01*
X765191Y622351D01*
X764899Y622560D01*
X764566Y622643D01*
X764233Y622560D01*
X763941Y622351D01*
X763816Y622060D01*
X763899Y621768D01*
X764108Y621560D01*
X764358Y621476D01*
X764774D01*
X765149Y621351D01*
X765399Y621101D01*
X765483Y620810D01*
X765399Y620518D01*
X765191Y620310D01*
X764858Y620185D01*
X764566Y620143D01*
G01X787449Y642135D02*
X787699Y642260D01*
X787991Y642343D01*
X788324D01*
X788699Y642218D01*
X788991Y642010D01*
X789199Y641760D01*
X789366Y641343D01*
X789408Y640968D01*
X789324Y640593D01*
X789199Y640343D01*
X788949Y640093D01*
X788658Y639926D01*
X788366Y639843D01*
X788074D01*
X787783Y639926D01*
X787533Y640051D01*
X787324Y640218D01*
G01X786183Y640343D02*
X785933Y640051D01*
X785599Y639885D01*
X785224Y639843D01*
X784891Y639885D01*
X784558Y640093D01*
X784349Y640343D01*
X784308Y640593D01*
X784391Y640885D01*
X784683Y641093D01*
X784974Y641176D01*
X785349D01*
G01X784974D02*
X784724Y641301D01*
X784516Y641510D01*
X784433Y641760D01*
X784516Y642010D01*
X784724Y642218D01*
X785099Y642343D01*
X785474Y642301D01*
X785849Y642135D01*
G01X782166Y639843D02*
X781874Y639885D01*
X781541Y640010D01*
X781333Y640218D01*
X781249Y640510D01*
X781333Y640801D01*
X781583Y641051D01*
X781958Y641176D01*
X782374D01*
X782624Y641260D01*
X782833Y641468D01*
X782916Y641760D01*
X782791Y642051D01*
X782499Y642260D01*
X782166Y642343D01*
X781833Y642260D01*
X781541Y642051D01*
X781416Y641760D01*
X781499Y641468D01*
X781708Y641260D01*
X781958Y641176D01*
X782374D01*
X782749Y641051D01*
X782999Y640801D01*
X783083Y640510D01*
X782999Y640218D01*
X782791Y640010D01*
X782458Y639885D01*
X782166Y639843D01*
G01X779149D02*
X779066Y640385D01*
X778941Y640843D01*
X778774Y641260D01*
X778566Y641718D01*
X778233Y642343D01*
X779899D01*
G01X801708Y608310D02*
X801833Y608060D01*
X801916Y607768D01*
Y607435D01*
X801791Y607060D01*
X801583Y606768D01*
X801333Y606560D01*
X800916Y606393D01*
X800541Y606351D01*
X800166Y606435D01*
X799916Y606560D01*
X799666Y606810D01*
X799499Y607101D01*
X799416Y607393D01*
Y607685D01*
X799499Y607976D01*
X799624Y608226D01*
X799791Y608435D01*
G01X799916Y609576D02*
X799624Y609826D01*
X799458Y610160D01*
X799416Y610535D01*
X799458Y610868D01*
X799666Y611201D01*
X799916Y611410D01*
X800166Y611451D01*
X800458Y611368D01*
X800666Y611076D01*
X800749Y610785D01*
Y610410D01*
G01Y610785D02*
X800874Y611035D01*
X801083Y611243D01*
X801333Y611326D01*
X801583Y611243D01*
X801791Y611035D01*
X801916Y610660D01*
X801874Y610285D01*
X801708Y609910D01*
G01X799416Y613593D02*
X799458Y613885D01*
X799583Y614218D01*
X799791Y614426D01*
X800083Y614510D01*
X800374Y614426D01*
X800624Y614176D01*
X800749Y613801D01*
Y613385D01*
X800833Y613135D01*
X801041Y612926D01*
X801333Y612843D01*
X801624Y612968D01*
X801833Y613260D01*
X801916Y613593D01*
X801833Y613926D01*
X801624Y614218D01*
X801333Y614343D01*
X801041Y614260D01*
X800833Y614051D01*
X800749Y613801D01*
Y613385D01*
X800624Y613010D01*
X800374Y612760D01*
X800083Y612676D01*
X799791Y612760D01*
X799583Y612968D01*
X799458Y613301D01*
X799416Y613593D01*
G01X799708Y615985D02*
X799499Y616276D01*
X799416Y616610D01*
X799499Y616943D01*
X799749Y617235D01*
X800124Y617443D01*
X800499Y617526D01*
X800958D01*
X801333Y617443D01*
X801666Y617235D01*
X801833Y616985D01*
X801916Y616693D01*
X801833Y616360D01*
X801666Y616110D01*
X801416Y615943D01*
X801083Y615860D01*
X800791Y615943D01*
X800499Y616151D01*
X800333Y616401D01*
X800291Y616693D01*
X800374Y617026D01*
X800583Y617276D01*
X800958Y617526D01*
G01X797616Y652643D02*
X795116D01*
G01X797616Y651685D02*
Y653601D01*
G01X795116Y654910D02*
X797616D01*
Y655910D01*
X797491Y656243D01*
X797199Y656493D01*
X796866Y656576D01*
X796533Y656493D01*
X796283Y656285D01*
X796158Y655910D01*
Y654910D01*
G01X795116Y658843D02*
X797616D01*
X797116Y658343D01*
G01X795116D02*
Y659343D01*
G01X795491Y661026D02*
X795283Y661276D01*
X795158Y661568D01*
X795116Y661943D01*
X795199Y662318D01*
X795366Y662610D01*
X795658Y662818D01*
X795991Y662860D01*
X796324Y662776D01*
X796533Y662568D01*
X796699Y662276D01*
X796741Y661985D01*
X796699Y661693D01*
X796533Y661318D01*
X797616Y661443D01*
Y662568D01*
G01X795408Y664335D02*
X795199Y664626D01*
X795116Y664960D01*
X795199Y665293D01*
X795449Y665585D01*
X795824Y665793D01*
X796199Y665876D01*
X796658D01*
X797033Y665793D01*
X797366Y665585D01*
X797533Y665335D01*
X797616Y665043D01*
X797533Y664710D01*
X797366Y664460D01*
X797116Y664293D01*
X796783Y664210D01*
X796491Y664293D01*
X796199Y664501D01*
X796033Y664751D01*
X795991Y665043D01*
X796074Y665376D01*
X796283Y665626D01*
X796658Y665876D01*
G01X793616Y652643D02*
X791116D01*
G01X793616Y651685D02*
Y653601D01*
G01X791116Y654910D02*
X793616D01*
Y655910D01*
X793491Y656243D01*
X793199Y656493D01*
X792866Y656576D01*
X792533Y656493D01*
X792283Y656285D01*
X792158Y655910D01*
Y654910D01*
G01X791408Y658135D02*
X791199Y658426D01*
X791116Y658760D01*
X791199Y659093D01*
X791449Y659385D01*
X791824Y659593D01*
X792199Y659676D01*
X792658D01*
X793033Y659593D01*
X793366Y659385D01*
X793533Y659135D01*
X793616Y658843D01*
X793533Y658510D01*
X793366Y658260D01*
X793116Y658093D01*
X792783Y658010D01*
X792491Y658093D01*
X792199Y658301D01*
X792033Y658551D01*
X791991Y658843D01*
X792074Y659176D01*
X792283Y659426D01*
X792658Y659676D01*
G01X793199Y661151D02*
X793449Y661401D01*
X793574Y661693D01*
X793616Y662026D01*
X793533Y662443D01*
X793324Y662735D01*
X793074Y662818D01*
X792824Y662776D01*
X792616Y662610D01*
X792199Y661776D01*
X791908Y661401D01*
X791491Y661151D01*
X791116Y661068D01*
Y662818D01*
G01X789616Y652643D02*
X787116D01*
G01X789616Y651685D02*
Y653601D01*
G01X787116Y654910D02*
X789616D01*
Y655910D01*
X789491Y656243D01*
X789199Y656493D01*
X788866Y656576D01*
X788533Y656493D01*
X788283Y656285D01*
X788158Y655910D01*
Y654910D01*
G01X787116Y658843D02*
X789616D01*
X789116Y658343D01*
G01X787116D02*
Y659343D01*
G01Y662443D02*
X789616D01*
X787824Y660901D01*
Y662985D01*
G01X787116Y665043D02*
X787158Y665335D01*
X787283Y665668D01*
X787491Y665876D01*
X787783Y665960D01*
X788074Y665876D01*
X788324Y665626D01*
X788449Y665251D01*
Y664835D01*
X788533Y664585D01*
X788741Y664376D01*
X789033Y664293D01*
X789324Y664418D01*
X789533Y664710D01*
X789616Y665043D01*
X789533Y665376D01*
X789324Y665668D01*
X789033Y665793D01*
X788741Y665710D01*
X788533Y665501D01*
X788449Y665251D01*
Y664835D01*
X788324Y664460D01*
X788074Y664210D01*
X787783Y664126D01*
X787491Y664210D01*
X787283Y664418D01*
X787158Y664751D01*
X787116Y665043D01*
G01X770816Y659643D02*
Y657143D01*
G01X771774Y659643D02*
X769858D01*
G01X768549Y657143D02*
Y659643D01*
X767549D01*
X767216Y659518D01*
X766966Y659226D01*
X766883Y658893D01*
X766966Y658560D01*
X767174Y658310D01*
X767549Y658185D01*
X768549D01*
G01X764616Y657143D02*
Y659643D01*
X765116Y659143D01*
G01Y657143D02*
X764116D01*
G01X761516D02*
Y659643D01*
X762016Y659143D01*
G01Y657143D02*
X761016D01*
G01X759208Y658185D02*
X758916Y658476D01*
X758666Y658643D01*
X758333Y658726D01*
X758041Y658643D01*
X757833Y658476D01*
X757666Y658226D01*
X757624Y657935D01*
X757666Y657685D01*
X757833Y657435D01*
X758083Y657226D01*
X758374Y657143D01*
X758708Y657226D01*
X758999Y657476D01*
X759166Y657851D01*
X759208Y658268D01*
X759124Y658810D01*
X758999Y659101D01*
X758791Y659393D01*
X758499Y659601D01*
X758208Y659643D01*
X757916Y659560D01*
X757708Y659351D01*
G01X777616Y658943D02*
X775116D01*
G01X777616Y657985D02*
Y659901D01*
G01X775116Y661210D02*
X777616D01*
Y662210D01*
X777491Y662543D01*
X777199Y662793D01*
X776866Y662876D01*
X776533Y662793D01*
X776283Y662585D01*
X776158Y662210D01*
Y661210D01*
G01X775116Y665143D02*
X777616D01*
X777116Y664643D01*
G01X775116D02*
Y665643D01*
G01Y668243D02*
X777616D01*
X777116Y667743D01*
G01X775116D02*
Y668743D01*
G01Y671343D02*
X775158Y671635D01*
X775283Y671968D01*
X775491Y672176D01*
X775783Y672260D01*
X776074Y672176D01*
X776324Y671926D01*
X776449Y671551D01*
Y671135D01*
X776533Y670885D01*
X776741Y670676D01*
X777033Y670593D01*
X777324Y670718D01*
X777533Y671010D01*
X777616Y671343D01*
X777533Y671676D01*
X777324Y671968D01*
X777033Y672093D01*
X776741Y672010D01*
X776533Y671801D01*
X776449Y671551D01*
Y671135D01*
X776324Y670760D01*
X776074Y670510D01*
X775783Y670426D01*
X775491Y670510D01*
X775283Y670718D01*
X775158Y671051D01*
X775116Y671343D01*
G01X777816Y655643D02*
Y653143D01*
G01X778774Y655643D02*
X776858D01*
G01X775549Y653143D02*
Y655643D01*
X774549D01*
X774216Y655518D01*
X773966Y655226D01*
X773883Y654893D01*
X773966Y654560D01*
X774174Y654310D01*
X774549Y654185D01*
X775549D01*
G01X771616Y653143D02*
Y655643D01*
X772116Y655143D01*
G01Y653143D02*
X771116D01*
G01X769308Y655226D02*
X769058Y655476D01*
X768766Y655601D01*
X768433Y655643D01*
X768016Y655560D01*
X767724Y655351D01*
X767641Y655101D01*
X767683Y654851D01*
X767849Y654643D01*
X768683Y654226D01*
X769058Y653935D01*
X769308Y653518D01*
X769391Y653143D01*
X767641D01*
G01X765499D02*
X765416Y653685D01*
X765291Y654143D01*
X765124Y654560D01*
X764916Y655018D01*
X764583Y655643D01*
X766249D01*
G01X800149Y638735D02*
X800399Y638860D01*
X800691Y638943D01*
X801024D01*
X801399Y638818D01*
X801691Y638610D01*
X801899Y638360D01*
X802066Y637943D01*
X802108Y637568D01*
X802024Y637193D01*
X801899Y636943D01*
X801649Y636693D01*
X801358Y636526D01*
X801066Y636443D01*
X800774D01*
X800483Y636526D01*
X800233Y636651D01*
X800024Y636818D01*
G01X798883Y636943D02*
X798633Y636651D01*
X798299Y636485D01*
X797924Y636443D01*
X797591Y636485D01*
X797258Y636693D01*
X797049Y636943D01*
X797008Y637193D01*
X797091Y637485D01*
X797383Y637693D01*
X797674Y637776D01*
X798049D01*
G01X797674D02*
X797424Y637901D01*
X797216Y638110D01*
X797133Y638360D01*
X797216Y638610D01*
X797424Y638818D01*
X797799Y638943D01*
X798174Y638901D01*
X798549Y638735D01*
G01X795574Y636735D02*
X795283Y636526D01*
X794949Y636443D01*
X794616Y636526D01*
X794324Y636776D01*
X794116Y637151D01*
X794033Y637526D01*
Y637985D01*
X794116Y638360D01*
X794324Y638693D01*
X794574Y638860D01*
X794866Y638943D01*
X795199Y638860D01*
X795449Y638693D01*
X795616Y638443D01*
X795699Y638110D01*
X795616Y637818D01*
X795408Y637526D01*
X795158Y637360D01*
X794866Y637318D01*
X794533Y637401D01*
X794283Y637610D01*
X794033Y637985D01*
G01X792474Y636735D02*
X792183Y636526D01*
X791849Y636443D01*
X791516Y636526D01*
X791224Y636776D01*
X791016Y637151D01*
X790933Y637526D01*
Y637985D01*
X791016Y638360D01*
X791224Y638693D01*
X791474Y638860D01*
X791766Y638943D01*
X792099Y638860D01*
X792349Y638693D01*
X792516Y638443D01*
X792599Y638110D01*
X792516Y637818D01*
X792308Y637526D01*
X792058Y637360D01*
X791766Y637318D01*
X791433Y637401D01*
X791183Y637610D01*
X790933Y637985D01*
G01X800149Y626735D02*
X800399Y626860D01*
X800691Y626943D01*
X801024D01*
X801399Y626818D01*
X801691Y626610D01*
X801899Y626360D01*
X802066Y625943D01*
X802108Y625568D01*
X802024Y625193D01*
X801899Y624943D01*
X801649Y624693D01*
X801358Y624526D01*
X801066Y624443D01*
X800774D01*
X800483Y624526D01*
X800233Y624651D01*
X800024Y624818D01*
G01X797466Y624443D02*
Y626943D01*
X799008Y625151D01*
X796924D01*
G01X794866Y626943D02*
X795199Y626860D01*
X795449Y626651D01*
X795616Y626401D01*
X795741Y626068D01*
X795783Y625693D01*
X795741Y625318D01*
X795616Y624985D01*
X795449Y624735D01*
X795199Y624526D01*
X794866Y624443D01*
X794533Y624526D01*
X794283Y624735D01*
X794116Y624985D01*
X793991Y625318D01*
X793949Y625693D01*
X793991Y626068D01*
X794116Y626401D01*
X794283Y626651D01*
X794533Y626860D01*
X794866Y626943D01*
G01X791266Y624443D02*
Y626943D01*
X792808Y625151D01*
X790724D01*
G01X800149Y622735D02*
X800399Y622860D01*
X800691Y622943D01*
X801024D01*
X801399Y622818D01*
X801691Y622610D01*
X801899Y622360D01*
X802066Y621943D01*
X802108Y621568D01*
X802024Y621193D01*
X801899Y620943D01*
X801649Y620693D01*
X801358Y620526D01*
X801066Y620443D01*
X800774D01*
X800483Y620526D01*
X800233Y620651D01*
X800024Y620818D01*
G01X797466Y620443D02*
Y622943D01*
X799008Y621151D01*
X796924D01*
G01X794866Y620443D02*
Y622943D01*
X795366Y622443D01*
G01Y620443D02*
X794366D01*
G01X791766D02*
Y622943D01*
X792266Y622443D01*
G01Y620443D02*
X791266D01*
G01X800149Y634735D02*
X800399Y634860D01*
X800691Y634943D01*
X801024D01*
X801399Y634818D01*
X801691Y634610D01*
X801899Y634360D01*
X802066Y633943D01*
X802108Y633568D01*
X802024Y633193D01*
X801899Y632943D01*
X801649Y632693D01*
X801358Y632526D01*
X801066Y632443D01*
X800774D01*
X800483Y632526D01*
X800233Y632651D01*
X800024Y632818D01*
G01X797466Y632443D02*
Y634943D01*
X799008Y633151D01*
X796924D01*
G01X794866Y632443D02*
Y634943D01*
X795366Y634443D01*
G01Y632443D02*
X794366D01*
G01X792558Y634526D02*
X792308Y634776D01*
X792016Y634901D01*
X791683Y634943D01*
X791266Y634860D01*
X790974Y634651D01*
X790891Y634401D01*
X790933Y634151D01*
X791099Y633943D01*
X791933Y633526D01*
X792308Y633235D01*
X792558Y632818D01*
X792641Y632443D01*
X790891D01*
G01X765849Y675435D02*
X766099Y675560D01*
X766391Y675643D01*
X766724D01*
X767099Y675518D01*
X767391Y675310D01*
X767599Y675060D01*
X767766Y674643D01*
X767808Y674268D01*
X767724Y673893D01*
X767599Y673643D01*
X767349Y673393D01*
X767058Y673226D01*
X766766Y673143D01*
X766474D01*
X766183Y673226D01*
X765933Y673351D01*
X765724Y673518D01*
G01X763166Y673143D02*
Y675643D01*
X764708Y673851D01*
X762624D01*
G01X761358Y674185D02*
X761066Y674476D01*
X760816Y674643D01*
X760483Y674726D01*
X760191Y674643D01*
X759983Y674476D01*
X759816Y674226D01*
X759774Y673935D01*
X759816Y673685D01*
X759983Y673435D01*
X760233Y673226D01*
X760524Y673143D01*
X760858Y673226D01*
X761149Y673476D01*
X761316Y673851D01*
X761358Y674268D01*
X761274Y674810D01*
X761149Y675101D01*
X760941Y675393D01*
X760649Y675601D01*
X760358Y675643D01*
X760066Y675560D01*
X759858Y675351D01*
G01X758174Y673435D02*
X757883Y673226D01*
X757549Y673143D01*
X757216Y673226D01*
X756924Y673476D01*
X756716Y673851D01*
X756633Y674226D01*
Y674685D01*
X756716Y675060D01*
X756924Y675393D01*
X757174Y675560D01*
X757466Y675643D01*
X757799Y675560D01*
X758049Y675393D01*
X758216Y675143D01*
X758299Y674810D01*
X758216Y674518D01*
X758008Y674226D01*
X757758Y674060D01*
X757466Y674018D01*
X757133Y674101D01*
X756883Y674310D01*
X756633Y674685D01*
G01X791349Y685935D02*
X791599Y686060D01*
X791891Y686143D01*
X792224D01*
X792599Y686018D01*
X792891Y685810D01*
X793099Y685560D01*
X793266Y685143D01*
X793308Y684768D01*
X793224Y684393D01*
X793099Y684143D01*
X792849Y683893D01*
X792558Y683726D01*
X792266Y683643D01*
X791974D01*
X791683Y683726D01*
X791433Y683851D01*
X791224Y684018D01*
G01X788666Y683643D02*
Y686143D01*
X790208Y684351D01*
X788124D01*
G01X786983Y684018D02*
X786733Y683810D01*
X786441Y683685D01*
X786066Y683643D01*
X785691Y683726D01*
X785399Y683893D01*
X785191Y684185D01*
X785149Y684518D01*
X785233Y684851D01*
X785441Y685060D01*
X785733Y685226D01*
X786024Y685268D01*
X786316Y685226D01*
X786691Y685060D01*
X786566Y686143D01*
X785441D01*
G01X782966D02*
X783299Y686060D01*
X783549Y685851D01*
X783716Y685601D01*
X783841Y685268D01*
X783883Y684893D01*
X783841Y684518D01*
X783716Y684185D01*
X783549Y683935D01*
X783299Y683726D01*
X782966Y683643D01*
X782633Y683726D01*
X782383Y683935D01*
X782216Y684185D01*
X782091Y684518D01*
X782049Y684893D01*
X782091Y685268D01*
X782216Y685601D01*
X782383Y685851D01*
X782633Y686060D01*
X782966Y686143D01*
G01X778349Y680435D02*
X778599Y680560D01*
X778891Y680643D01*
X779224D01*
X779599Y680518D01*
X779891Y680310D01*
X780099Y680060D01*
X780266Y679643D01*
X780308Y679268D01*
X780224Y678893D01*
X780099Y678643D01*
X779849Y678393D01*
X779558Y678226D01*
X779266Y678143D01*
X778974D01*
X778683Y678226D01*
X778433Y678351D01*
X778224Y678518D01*
G01X775666Y678143D02*
Y680643D01*
X777208Y678851D01*
X775124D01*
G01X773983Y678518D02*
X773733Y678310D01*
X773441Y678185D01*
X773066Y678143D01*
X772691Y678226D01*
X772399Y678393D01*
X772191Y678685D01*
X772149Y679018D01*
X772233Y679351D01*
X772441Y679560D01*
X772733Y679726D01*
X773024Y679768D01*
X773316Y679726D01*
X773691Y679560D01*
X773566Y680643D01*
X772441D01*
G01X769966Y678143D02*
Y680643D01*
X770466Y680143D01*
G01Y678143D02*
X769466D01*
G01X791349Y680435D02*
X791599Y680560D01*
X791891Y680643D01*
X792224D01*
X792599Y680518D01*
X792891Y680310D01*
X793099Y680060D01*
X793266Y679643D01*
X793308Y679268D01*
X793224Y678893D01*
X793099Y678643D01*
X792849Y678393D01*
X792558Y678226D01*
X792266Y678143D01*
X791974D01*
X791683Y678226D01*
X791433Y678351D01*
X791224Y678518D01*
G01X788666Y678143D02*
Y680643D01*
X790208Y678851D01*
X788124D01*
G01X786983Y678518D02*
X786733Y678310D01*
X786441Y678185D01*
X786066Y678143D01*
X785691Y678226D01*
X785399Y678393D01*
X785191Y678685D01*
X785149Y679018D01*
X785233Y679351D01*
X785441Y679560D01*
X785733Y679726D01*
X786024Y679768D01*
X786316Y679726D01*
X786691Y679560D01*
X786566Y680643D01*
X785441D01*
G01X783758Y680226D02*
X783508Y680476D01*
X783216Y680601D01*
X782883Y680643D01*
X782466Y680560D01*
X782174Y680351D01*
X782091Y680101D01*
X782133Y679851D01*
X782299Y679643D01*
X783133Y679226D01*
X783508Y678935D01*
X783758Y678518D01*
X783841Y678143D01*
X782091D01*
G01X752349Y685935D02*
X752599Y686060D01*
X752891Y686143D01*
X753224D01*
X753599Y686018D01*
X753891Y685810D01*
X754099Y685560D01*
X754266Y685143D01*
X754308Y684768D01*
X754224Y684393D01*
X754099Y684143D01*
X753849Y683893D01*
X753558Y683726D01*
X753266Y683643D01*
X752974D01*
X752683Y683726D01*
X752433Y683851D01*
X752224Y684018D01*
G01X749666Y683643D02*
Y686143D01*
X751208Y684351D01*
X749124D01*
G01X747149Y683643D02*
X747066Y684185D01*
X746941Y684643D01*
X746774Y685060D01*
X746566Y685518D01*
X746233Y686143D01*
X747899D01*
G01X743966D02*
X744299Y686060D01*
X744549Y685851D01*
X744716Y685601D01*
X744841Y685268D01*
X744883Y684893D01*
X744841Y684518D01*
X744716Y684185D01*
X744549Y683935D01*
X744299Y683726D01*
X743966Y683643D01*
X743633Y683726D01*
X743383Y683935D01*
X743216Y684185D01*
X743091Y684518D01*
X743049Y684893D01*
X743091Y685268D01*
X743216Y685601D01*
X743383Y685851D01*
X743633Y686060D01*
X743966Y686143D01*
G01X765349Y685935D02*
X765599Y686060D01*
X765891Y686143D01*
X766224D01*
X766599Y686018D01*
X766891Y685810D01*
X767099Y685560D01*
X767266Y685143D01*
X767308Y684768D01*
X767224Y684393D01*
X767099Y684143D01*
X766849Y683893D01*
X766558Y683726D01*
X766266Y683643D01*
X765974D01*
X765683Y683726D01*
X765433Y683851D01*
X765224Y684018D01*
G01X762666Y683643D02*
Y686143D01*
X764208Y684351D01*
X762124D01*
G01X760149Y683643D02*
X760066Y684185D01*
X759941Y684643D01*
X759774Y685060D01*
X759566Y685518D01*
X759233Y686143D01*
X760899D01*
G01X756966Y683643D02*
Y686143D01*
X757466Y685643D01*
G01Y683643D02*
X756466D01*
G01X778349Y685935D02*
X778599Y686060D01*
X778891Y686143D01*
X779224D01*
X779599Y686018D01*
X779891Y685810D01*
X780099Y685560D01*
X780266Y685143D01*
X780308Y684768D01*
X780224Y684393D01*
X780099Y684143D01*
X779849Y683893D01*
X779558Y683726D01*
X779266Y683643D01*
X778974D01*
X778683Y683726D01*
X778433Y683851D01*
X778224Y684018D01*
G01X775666Y683643D02*
Y686143D01*
X777208Y684351D01*
X775124D01*
G01X773149Y683643D02*
X773066Y684185D01*
X772941Y684643D01*
X772774Y685060D01*
X772566Y685518D01*
X772233Y686143D01*
X773899D01*
G01X770758Y685726D02*
X770508Y685976D01*
X770216Y686101D01*
X769883Y686143D01*
X769466Y686060D01*
X769174Y685851D01*
X769091Y685601D01*
X769133Y685351D01*
X769299Y685143D01*
X770133Y684726D01*
X770508Y684435D01*
X770758Y684018D01*
X770841Y683643D01*
X769091D01*
G01X767099Y678143D02*
Y680643D01*
X766058D01*
X765724Y680518D01*
X765516Y680351D01*
X765433Y680018D01*
X765516Y679685D01*
X765766Y679476D01*
X766058Y679351D01*
X767099D01*
G01X766058D02*
X765433Y678143D01*
G01X763958Y679185D02*
X763666Y679476D01*
X763416Y679643D01*
X763083Y679726D01*
X762791Y679643D01*
X762583Y679476D01*
X762416Y679226D01*
X762374Y678935D01*
X762416Y678685D01*
X762583Y678435D01*
X762833Y678226D01*
X763124Y678143D01*
X763458Y678226D01*
X763749Y678476D01*
X763916Y678851D01*
X763958Y679268D01*
X763874Y679810D01*
X763749Y680101D01*
X763541Y680393D01*
X763249Y680601D01*
X762958Y680643D01*
X762666Y680560D01*
X762458Y680351D01*
G01X760983Y678518D02*
X760733Y678310D01*
X760441Y678185D01*
X760066Y678143D01*
X759691Y678226D01*
X759399Y678393D01*
X759191Y678685D01*
X759149Y679018D01*
X759233Y679351D01*
X759441Y679560D01*
X759733Y679726D01*
X760024Y679768D01*
X760316Y679726D01*
X760691Y679560D01*
X760566Y680643D01*
X759441D01*
G01X756966D02*
X757299Y680560D01*
X757549Y680351D01*
X757716Y680101D01*
X757841Y679768D01*
X757883Y679393D01*
X757841Y679018D01*
X757716Y678685D01*
X757549Y678435D01*
X757299Y678226D01*
X756966Y678143D01*
X756633Y678226D01*
X756383Y678435D01*
X756216Y678685D01*
X756091Y679018D01*
X756049Y679393D01*
X756091Y679768D01*
X756216Y680101D01*
X756383Y680351D01*
X756633Y680560D01*
X756966Y680643D01*
G01X807316Y694310D02*
Y691810D01*
G01X808274Y694310D02*
X806358D01*
G01X805049Y691810D02*
Y694310D01*
X804049D01*
X803716Y694185D01*
X803466Y693893D01*
X803383Y693560D01*
X803466Y693227D01*
X803674Y692977D01*
X804049Y692852D01*
X805049D01*
G01X801116Y691810D02*
Y694310D01*
X801616Y693810D01*
G01Y691810D02*
X800616D01*
G01X798933Y692310D02*
X798683Y692018D01*
X798349Y691852D01*
X797974Y691810D01*
X797641Y691852D01*
X797308Y692060D01*
X797099Y692310D01*
X797058Y692560D01*
X797141Y692852D01*
X797433Y693060D01*
X797724Y693143D01*
X798099D01*
G01X797724D02*
X797474Y693268D01*
X797266Y693477D01*
X797183Y693727D01*
X797266Y693977D01*
X797474Y694185D01*
X797849Y694310D01*
X798224Y694268D01*
X798599Y694102D01*
G01X794916Y691810D02*
Y694310D01*
X795416Y693810D01*
G01Y691810D02*
X794416D01*
G01X765816Y694143D02*
Y691643D01*
G01X766774Y694143D02*
X764858D01*
G01X763549Y691643D02*
Y694143D01*
X762549D01*
X762216Y694018D01*
X761966Y693726D01*
X761883Y693393D01*
X761966Y693060D01*
X762174Y692810D01*
X762549Y692685D01*
X763549D01*
G01X759616Y691643D02*
Y694143D01*
X760116Y693643D01*
G01Y691643D02*
X759116D01*
G01X757433Y692018D02*
X757183Y691810D01*
X756891Y691685D01*
X756516Y691643D01*
X756141Y691726D01*
X755849Y691893D01*
X755641Y692185D01*
X755599Y692518D01*
X755683Y692851D01*
X755891Y693060D01*
X756183Y693226D01*
X756474Y693268D01*
X756766Y693226D01*
X757141Y693060D01*
X757016Y694143D01*
X755891D01*
G01X754208Y692685D02*
X753916Y692976D01*
X753666Y693143D01*
X753333Y693226D01*
X753041Y693143D01*
X752833Y692976D01*
X752666Y692726D01*
X752624Y692435D01*
X752666Y692185D01*
X752833Y691935D01*
X753083Y691726D01*
X753374Y691643D01*
X753708Y691726D01*
X753999Y691976D01*
X754166Y692351D01*
X754208Y692768D01*
X754124Y693310D01*
X753999Y693601D01*
X753791Y693893D01*
X753499Y694101D01*
X753208Y694143D01*
X752916Y694060D01*
X752708Y693851D01*
G01X809016Y683243D02*
Y680743D01*
G01X809974Y683243D02*
X808058D01*
G01X806749Y680743D02*
Y683243D01*
X805749D01*
X805416Y683118D01*
X805166Y682826D01*
X805083Y682493D01*
X805166Y682160D01*
X805374Y681910D01*
X805749Y681785D01*
X806749D01*
G01X802816Y680743D02*
Y683243D01*
X803316Y682743D01*
G01Y680743D02*
X802316D01*
G01X800508Y681785D02*
X800216Y682076D01*
X799966Y682243D01*
X799633Y682326D01*
X799341Y682243D01*
X799133Y682076D01*
X798966Y681826D01*
X798924Y681535D01*
X798966Y681285D01*
X799133Y681035D01*
X799383Y680826D01*
X799674Y680743D01*
X800008Y680826D01*
X800299Y681076D01*
X800466Y681451D01*
X800508Y681868D01*
X800424Y682410D01*
X800299Y682701D01*
X800091Y682993D01*
X799799Y683201D01*
X799508Y683243D01*
X799216Y683160D01*
X799008Y682951D01*
G01X796616Y680743D02*
Y683243D01*
X797116Y682743D01*
G01Y680743D02*
X796116D01*
G01X749266Y703143D02*
Y700643D01*
G01X750224Y703143D02*
X748308D01*
G01X746999Y700643D02*
Y703143D01*
X745999D01*
X745666Y703018D01*
X745416Y702726D01*
X745333Y702393D01*
X745416Y702060D01*
X745624Y701810D01*
X745999Y701685D01*
X746999D01*
G01X743066Y700643D02*
X742774Y700685D01*
X742441Y700810D01*
X742233Y701018D01*
X742149Y701310D01*
X742233Y701601D01*
X742483Y701851D01*
X742858Y701976D01*
X743274D01*
X743524Y702060D01*
X743733Y702268D01*
X743816Y702560D01*
X743691Y702851D01*
X743399Y703060D01*
X743066Y703143D01*
X742733Y703060D01*
X742441Y702851D01*
X742316Y702560D01*
X742399Y702268D01*
X742608Y702060D01*
X742858Y701976D01*
X743274D01*
X743649Y701851D01*
X743899Y701601D01*
X743983Y701310D01*
X743899Y701018D01*
X743691Y700810D01*
X743358Y700685D01*
X743066Y700643D01*
G01X740883Y701018D02*
X740633Y700810D01*
X740341Y700685D01*
X739966Y700643D01*
X739591Y700726D01*
X739299Y700893D01*
X739091Y701185D01*
X739049Y701518D01*
X739133Y701851D01*
X739341Y702060D01*
X739633Y702226D01*
X739924Y702268D01*
X740216Y702226D01*
X740591Y702060D01*
X740466Y703143D01*
X739341D01*
G01X778266Y694143D02*
Y691643D01*
G01X779224Y694143D02*
X777308D01*
G01X775999Y691643D02*
Y694143D01*
X774999D01*
X774666Y694018D01*
X774416Y693726D01*
X774333Y693393D01*
X774416Y693060D01*
X774624Y692810D01*
X774999Y692685D01*
X775999D01*
G01X772066Y691643D02*
X771774Y691685D01*
X771441Y691810D01*
X771233Y692018D01*
X771149Y692310D01*
X771233Y692601D01*
X771483Y692851D01*
X771858Y692976D01*
X772274D01*
X772524Y693060D01*
X772733Y693268D01*
X772816Y693560D01*
X772691Y693851D01*
X772399Y694060D01*
X772066Y694143D01*
X771733Y694060D01*
X771441Y693851D01*
X771316Y693560D01*
X771399Y693268D01*
X771608Y693060D01*
X771858Y692976D01*
X772274D01*
X772649Y692851D01*
X772899Y692601D01*
X772983Y692310D01*
X772899Y692018D01*
X772691Y691810D01*
X772358Y691685D01*
X772066Y691643D01*
G01X769758Y692685D02*
X769466Y692976D01*
X769216Y693143D01*
X768883Y693226D01*
X768591Y693143D01*
X768383Y692976D01*
X768216Y692726D01*
X768174Y692435D01*
X768216Y692185D01*
X768383Y691935D01*
X768633Y691726D01*
X768924Y691643D01*
X769258Y691726D01*
X769549Y691976D01*
X769716Y692351D01*
X769758Y692768D01*
X769674Y693310D01*
X769549Y693601D01*
X769341Y693893D01*
X769049Y694101D01*
X768758Y694143D01*
X768466Y694060D01*
X768258Y693851D01*
G01X796766Y698810D02*
Y696310D01*
G01X797724Y698810D02*
X795808D01*
G01X794499Y696310D02*
Y698810D01*
X793499D01*
X793166Y698685D01*
X792916Y698393D01*
X792833Y698060D01*
X792916Y697727D01*
X793124Y697477D01*
X793499Y697352D01*
X794499D01*
G01X790566Y696310D02*
X790274Y696352D01*
X789941Y696477D01*
X789733Y696685D01*
X789649Y696977D01*
X789733Y697268D01*
X789983Y697518D01*
X790358Y697643D01*
X790774D01*
X791024Y697727D01*
X791233Y697935D01*
X791316Y698227D01*
X791191Y698518D01*
X790899Y698727D01*
X790566Y698810D01*
X790233Y698727D01*
X789941Y698518D01*
X789816Y698227D01*
X789899Y697935D01*
X790108Y697727D01*
X790358Y697643D01*
X790774D01*
X791149Y697518D01*
X791399Y697268D01*
X791483Y696977D01*
X791399Y696685D01*
X791191Y696477D01*
X790858Y696352D01*
X790566Y696310D01*
G01X787549D02*
X787466Y696852D01*
X787341Y697310D01*
X787174Y697727D01*
X786966Y698185D01*
X786633Y698810D01*
X788299D01*
G01X791266Y694143D02*
Y691643D01*
G01X792224Y694143D02*
X790308D01*
G01X788999Y691643D02*
Y694143D01*
X787999D01*
X787666Y694018D01*
X787416Y693726D01*
X787333Y693393D01*
X787416Y693060D01*
X787624Y692810D01*
X787999Y692685D01*
X788999D01*
G01X785066Y691643D02*
X784774Y691685D01*
X784441Y691810D01*
X784233Y692018D01*
X784149Y692310D01*
X784233Y692601D01*
X784483Y692851D01*
X784858Y692976D01*
X785274D01*
X785524Y693060D01*
X785733Y693268D01*
X785816Y693560D01*
X785691Y693851D01*
X785399Y694060D01*
X785066Y694143D01*
X784733Y694060D01*
X784441Y693851D01*
X784316Y693560D01*
X784399Y693268D01*
X784608Y693060D01*
X784858Y692976D01*
X785274D01*
X785649Y692851D01*
X785899Y692601D01*
X785983Y692310D01*
X785899Y692018D01*
X785691Y691810D01*
X785358Y691685D01*
X785066Y691643D01*
G01X782674Y691935D02*
X782383Y691726D01*
X782049Y691643D01*
X781716Y691726D01*
X781424Y691976D01*
X781216Y692351D01*
X781133Y692726D01*
Y693185D01*
X781216Y693560D01*
X781424Y693893D01*
X781674Y694060D01*
X781966Y694143D01*
X782299Y694060D01*
X782549Y693893D01*
X782716Y693643D01*
X782799Y693310D01*
X782716Y693018D01*
X782508Y692726D01*
X782258Y692560D01*
X781966Y692518D01*
X781633Y692601D01*
X781383Y692810D01*
X781133Y693185D01*
G01X794266Y703310D02*
Y700810D01*
G01X795224Y703310D02*
X793308D01*
G01X791999Y700810D02*
Y703310D01*
X790999D01*
X790666Y703185D01*
X790416Y702893D01*
X790333Y702560D01*
X790416Y702227D01*
X790624Y701977D01*
X790999Y701852D01*
X791999D01*
G01X788774Y701102D02*
X788483Y700893D01*
X788149Y700810D01*
X787816Y700893D01*
X787524Y701143D01*
X787316Y701518D01*
X787233Y701893D01*
Y702352D01*
X787316Y702727D01*
X787524Y703060D01*
X787774Y703227D01*
X788066Y703310D01*
X788399Y703227D01*
X788649Y703060D01*
X788816Y702810D01*
X788899Y702477D01*
X788816Y702185D01*
X788608Y701893D01*
X788358Y701727D01*
X788066Y701685D01*
X787733Y701768D01*
X787483Y701977D01*
X787233Y702352D01*
G01X784966Y700810D02*
Y703310D01*
X785466Y702810D01*
G01Y700810D02*
X784466D01*
G01X762266Y703143D02*
Y700643D01*
G01X763224Y703143D02*
X761308D01*
G01X759999Y700643D02*
Y703143D01*
X758999D01*
X758666Y703018D01*
X758416Y702726D01*
X758333Y702393D01*
X758416Y702060D01*
X758624Y701810D01*
X758999Y701685D01*
X759999D01*
G01X756774Y700935D02*
X756483Y700726D01*
X756149Y700643D01*
X755816Y700726D01*
X755524Y700976D01*
X755316Y701351D01*
X755233Y701726D01*
Y702185D01*
X755316Y702560D01*
X755524Y702893D01*
X755774Y703060D01*
X756066Y703143D01*
X756399Y703060D01*
X756649Y702893D01*
X756816Y702643D01*
X756899Y702310D01*
X756816Y702018D01*
X756608Y701726D01*
X756358Y701560D01*
X756066Y701518D01*
X755733Y701601D01*
X755483Y701810D01*
X755233Y702185D01*
G01X753674Y700935D02*
X753383Y700726D01*
X753049Y700643D01*
X752716Y700726D01*
X752424Y700976D01*
X752216Y701351D01*
X752133Y701726D01*
Y702185D01*
X752216Y702560D01*
X752424Y702893D01*
X752674Y703060D01*
X752966Y703143D01*
X753299Y703060D01*
X753549Y702893D01*
X753716Y702643D01*
X753799Y702310D01*
X753716Y702018D01*
X753508Y701726D01*
X753258Y701560D01*
X752966Y701518D01*
X752633Y701601D01*
X752383Y701810D01*
X752133Y702185D01*
G01X765316Y699310D02*
Y696810D01*
G01X766274Y699310D02*
X764358D01*
G01X763049Y696810D02*
Y699310D01*
X762049D01*
X761716Y699185D01*
X761466Y698893D01*
X761383Y698560D01*
X761466Y698227D01*
X761674Y697977D01*
X762049Y697852D01*
X763049D01*
G01X759116Y696810D02*
Y699310D01*
X759616Y698810D01*
G01Y696810D02*
X758616D01*
G01X756933Y697310D02*
X756683Y697018D01*
X756349Y696852D01*
X755974Y696810D01*
X755641Y696852D01*
X755308Y697060D01*
X755099Y697310D01*
X755058Y697560D01*
X755141Y697852D01*
X755433Y698060D01*
X755724Y698143D01*
X756099D01*
G01X755724D02*
X755474Y698268D01*
X755266Y698477D01*
X755183Y698727D01*
X755266Y698977D01*
X755474Y699185D01*
X755849Y699310D01*
X756224Y699268D01*
X756599Y699102D01*
G01X752916Y699310D02*
X753249Y699227D01*
X753499Y699018D01*
X753666Y698768D01*
X753791Y698435D01*
X753833Y698060D01*
X753791Y697685D01*
X753666Y697352D01*
X753499Y697102D01*
X753249Y696893D01*
X752916Y696810D01*
X752583Y696893D01*
X752333Y697102D01*
X752166Y697352D01*
X752041Y697685D01*
X751999Y698060D01*
X752041Y698435D01*
X752166Y698768D01*
X752333Y699018D01*
X752583Y699227D01*
X752916Y699310D01*
G01X767316Y663643D02*
Y661143D01*
G01X768274Y663643D02*
X766358D01*
G01X765049Y661143D02*
Y663643D01*
X764049D01*
X763716Y663518D01*
X763466Y663226D01*
X763383Y662893D01*
X763466Y662560D01*
X763674Y662310D01*
X764049Y662185D01*
X765049D01*
G01X761116Y661143D02*
Y663643D01*
X761616Y663143D01*
G01Y661143D02*
X760616D01*
G01X758016D02*
Y663643D01*
X758516Y663143D01*
G01Y661143D02*
X757516D01*
G01X754416D02*
Y663643D01*
X755958Y661851D01*
X753874D01*
G01X747766Y698310D02*
Y695810D01*
G01X748724Y698310D02*
X746808D01*
G01X745499Y695810D02*
Y698310D01*
X744499D01*
X744166Y698185D01*
X743916Y697893D01*
X743833Y697560D01*
X743916Y697227D01*
X744124Y696977D01*
X744499Y696852D01*
X745499D01*
G01X742274Y696102D02*
X741983Y695893D01*
X741649Y695810D01*
X741316Y695893D01*
X741024Y696143D01*
X740816Y696518D01*
X740733Y696893D01*
Y697352D01*
X740816Y697727D01*
X741024Y698060D01*
X741274Y698227D01*
X741566Y698310D01*
X741899Y698227D01*
X742149Y698060D01*
X742316Y697810D01*
X742399Y697477D01*
X742316Y697185D01*
X742108Y696893D01*
X741858Y696727D01*
X741566Y696685D01*
X741233Y696768D01*
X740983Y696977D01*
X740733Y697352D01*
G01X737966Y695810D02*
Y698310D01*
X739508Y696518D01*
X737424D01*
G01X750266Y694143D02*
Y691643D01*
G01X751224Y694143D02*
X749308D01*
G01X747999Y691643D02*
Y694143D01*
X746999D01*
X746666Y694018D01*
X746416Y693726D01*
X746333Y693393D01*
X746416Y693060D01*
X746624Y692810D01*
X746999Y692685D01*
X747999D01*
G01X744774Y691935D02*
X744483Y691726D01*
X744149Y691643D01*
X743816Y691726D01*
X743524Y691976D01*
X743316Y692351D01*
X743233Y692726D01*
Y693185D01*
X743316Y693560D01*
X743524Y693893D01*
X743774Y694060D01*
X744066Y694143D01*
X744399Y694060D01*
X744649Y693893D01*
X744816Y693643D01*
X744899Y693310D01*
X744816Y693018D01*
X744608Y692726D01*
X744358Y692560D01*
X744066Y692518D01*
X743733Y692601D01*
X743483Y692810D01*
X743233Y693185D01*
G01X741883Y692018D02*
X741633Y691810D01*
X741341Y691685D01*
X740966Y691643D01*
X740591Y691726D01*
X740299Y691893D01*
X740091Y692185D01*
X740049Y692518D01*
X740133Y692851D01*
X740341Y693060D01*
X740633Y693226D01*
X740924Y693268D01*
X741216Y693226D01*
X741591Y693060D01*
X741466Y694143D01*
X740341D01*
G01X766316Y668643D02*
Y666143D01*
G01X767274Y668643D02*
X765358D01*
G01X764049Y666143D02*
Y668643D01*
X763049D01*
X762716Y668518D01*
X762466Y668226D01*
X762383Y667893D01*
X762466Y667560D01*
X762674Y667310D01*
X763049Y667185D01*
X764049D01*
G01X760116Y666143D02*
Y668643D01*
X760616Y668143D01*
G01Y666143D02*
X759616D01*
G01X757016Y668643D02*
X757349Y668560D01*
X757599Y668351D01*
X757766Y668101D01*
X757891Y667768D01*
X757933Y667393D01*
X757891Y667018D01*
X757766Y666685D01*
X757599Y666435D01*
X757349Y666226D01*
X757016Y666143D01*
X756683Y666226D01*
X756433Y666435D01*
X756266Y666685D01*
X756141Y667018D01*
X756099Y667393D01*
X756141Y667768D01*
X756266Y668101D01*
X756433Y668351D01*
X756683Y668560D01*
X757016Y668643D01*
G01X754708Y668226D02*
X754458Y668476D01*
X754166Y668601D01*
X753833Y668643D01*
X753416Y668560D01*
X753124Y668351D01*
X753041Y668101D01*
X753083Y667851D01*
X753249Y667643D01*
X754083Y667226D01*
X754458Y666935D01*
X754708Y666518D01*
X754791Y666143D01*
X753041D01*
G01X740283Y673943D02*
X737783D01*
G01X740283Y672985D02*
Y674901D01*
G01X737783Y676210D02*
X740283D01*
Y677210D01*
X740158Y677543D01*
X739866Y677793D01*
X739533Y677876D01*
X739200Y677793D01*
X738950Y677585D01*
X738825Y677210D01*
Y676210D01*
G01X737783Y680143D02*
X740283D01*
X739783Y679643D01*
G01X737783D02*
Y680643D01*
G01Y683243D02*
X740283D01*
X739783Y682743D01*
G01X737783D02*
Y683743D01*
G01X740283Y686343D02*
X740200Y686010D01*
X739991Y685760D01*
X739741Y685593D01*
X739408Y685468D01*
X739033Y685426D01*
X738658Y685468D01*
X738325Y685593D01*
X738075Y685760D01*
X737866Y686010D01*
X737783Y686343D01*
X737866Y686676D01*
X738075Y686926D01*
X738325Y687093D01*
X738658Y687218D01*
X739033Y687260D01*
X739408Y687218D01*
X739741Y687093D01*
X739991Y686926D01*
X740200Y686676D01*
X740283Y686343D01*
G01X743208Y708310D02*
X743333Y708060D01*
X743416Y707768D01*
Y707435D01*
X743291Y707060D01*
X743083Y706768D01*
X742833Y706560D01*
X742416Y706393D01*
X742041Y706351D01*
X741666Y706435D01*
X741416Y706560D01*
X741166Y706810D01*
X740999Y707101D01*
X740916Y707393D01*
Y707685D01*
X740999Y707976D01*
X741124Y708226D01*
X741291Y708435D01*
G01X741416Y709576D02*
X741124Y709826D01*
X740958Y710160D01*
X740916Y710535D01*
X740958Y710868D01*
X741166Y711201D01*
X741416Y711410D01*
X741666Y711451D01*
X741958Y711368D01*
X742166Y711076D01*
X742249Y710785D01*
Y710410D01*
G01Y710785D02*
X742374Y711035D01*
X742583Y711243D01*
X742833Y711326D01*
X743083Y711243D01*
X743291Y711035D01*
X743416Y710660D01*
X743374Y710285D01*
X743208Y709910D01*
G01X741208Y712885D02*
X740999Y713176D01*
X740916Y713510D01*
X740999Y713843D01*
X741249Y714135D01*
X741624Y714343D01*
X741999Y714426D01*
X742458D01*
X742833Y714343D01*
X743166Y714135D01*
X743333Y713885D01*
X743416Y713593D01*
X743333Y713260D01*
X743166Y713010D01*
X742916Y712843D01*
X742583Y712760D01*
X742291Y712843D01*
X741999Y713051D01*
X741833Y713301D01*
X741791Y713593D01*
X741874Y713926D01*
X742083Y714176D01*
X742458Y714426D01*
G01X742999Y715901D02*
X743249Y716151D01*
X743374Y716443D01*
X743416Y716776D01*
X743333Y717193D01*
X743124Y717485D01*
X742874Y717568D01*
X742624Y717526D01*
X742416Y717360D01*
X741999Y716526D01*
X741708Y716151D01*
X741291Y715901D01*
X740916Y715818D01*
Y717568D01*
G01X739208Y708310D02*
X739333Y708060D01*
X739416Y707768D01*
Y707435D01*
X739291Y707060D01*
X739083Y706768D01*
X738833Y706560D01*
X738416Y706393D01*
X738041Y706351D01*
X737666Y706435D01*
X737416Y706560D01*
X737166Y706810D01*
X736999Y707101D01*
X736916Y707393D01*
Y707685D01*
X736999Y707976D01*
X737124Y708226D01*
X737291Y708435D01*
G01X737416Y709576D02*
X737124Y709826D01*
X736958Y710160D01*
X736916Y710535D01*
X736958Y710868D01*
X737166Y711201D01*
X737416Y711410D01*
X737666Y711451D01*
X737958Y711368D01*
X738166Y711076D01*
X738249Y710785D01*
Y710410D01*
G01Y710785D02*
X738374Y711035D01*
X738583Y711243D01*
X738833Y711326D01*
X739083Y711243D01*
X739291Y711035D01*
X739416Y710660D01*
X739374Y710285D01*
X739208Y709910D01*
G01X737208Y712885D02*
X736999Y713176D01*
X736916Y713510D01*
X736999Y713843D01*
X737249Y714135D01*
X737624Y714343D01*
X737999Y714426D01*
X738458D01*
X738833Y714343D01*
X739166Y714135D01*
X739333Y713885D01*
X739416Y713593D01*
X739333Y713260D01*
X739166Y713010D01*
X738916Y712843D01*
X738583Y712760D01*
X738291Y712843D01*
X737999Y713051D01*
X737833Y713301D01*
X737791Y713593D01*
X737874Y713926D01*
X738083Y714176D01*
X738458Y714426D01*
G01X737416Y715776D02*
X737124Y716026D01*
X736958Y716360D01*
X736916Y716735D01*
X736958Y717068D01*
X737166Y717401D01*
X737416Y717610D01*
X737666Y717651D01*
X737958Y717568D01*
X738166Y717276D01*
X738249Y716985D01*
Y716610D01*
G01Y716985D02*
X738374Y717235D01*
X738583Y717443D01*
X738833Y717526D01*
X739083Y717443D01*
X739291Y717235D01*
X739416Y716860D01*
X739374Y716485D01*
X739208Y716110D01*
G01X814821Y183400D02*
Y201687D01*
X822800D01*
Y222900D01*
X826300D01*
Y228700D01*
X830157D01*
G01X802492Y180209D02*
Y184209D01*
X809892D01*
G01X813062Y184583D02*
Y191583D01*
X799662D01*
Y184583D01*
X813062D01*
G01X815233Y213833D02*
X814700Y214183D01*
X814300Y214767D01*
X814033Y215583D01*
X814300Y216283D01*
X814833Y216750D01*
X815767Y217100D01*
X819367D01*
Y210100D01*
X814967D01*
X814033Y210567D01*
X813500Y211267D01*
X813233Y212083D01*
X813500Y212900D01*
X814300Y213600D01*
X815233Y213833D01*
X819367D01*
G01X832100Y237700D02*
Y234109D01*
G01X810228Y251664D02*
Y255664D01*
X817628D01*
G01X826800Y241300D02*
X830800D01*
Y233900D01*
G01X826700Y242200D02*
Y238200D01*
X819300D01*
G01X825500Y250200D02*
Y246200D01*
X818100D01*
G01X808100Y220500D02*
X804100D01*
Y227900D01*
G01Y220500D02*
X800100D01*
Y227900D01*
G01X820100Y220500D02*
X816100D01*
Y227900D01*
G01Y220500D02*
X812100D01*
Y227900D01*
G01X826668Y237964D02*
Y233964D01*
X819268D01*
G01X812100Y220500D02*
X808100D01*
Y227900D01*
G01X826700Y246200D02*
Y242200D01*
X819300D01*
G01X816400Y259800D02*
Y255800D01*
X809000D01*
G01X833683Y308567D02*
Y311067D01*
X832642D01*
X832308Y310942D01*
X832100Y310775D01*
X832017Y310442D01*
X832100Y310109D01*
X832350Y309900D01*
X832642Y309775D01*
X833683D01*
G01X832642D02*
X832017Y308567D01*
G01X830542Y309609D02*
X830250Y309900D01*
X830000Y310067D01*
X829667Y310150D01*
X829375Y310067D01*
X829167Y309900D01*
X829000Y309650D01*
X828958Y309359D01*
X829000Y309109D01*
X829167Y308859D01*
X829417Y308650D01*
X829708Y308567D01*
X830042Y308650D01*
X830333Y308900D01*
X830500Y309275D01*
X830542Y309692D01*
X830458Y310234D01*
X830333Y310525D01*
X830125Y310817D01*
X829833Y311025D01*
X829542Y311067D01*
X829250Y310984D01*
X829042Y310775D01*
G01X826650Y308567D02*
Y311067D01*
X827150Y310567D01*
G01Y308567D02*
X826150D01*
G01X824467Y308942D02*
X824217Y308734D01*
X823925Y308609D01*
X823550Y308567D01*
X823175Y308650D01*
X822883Y308817D01*
X822675Y309109D01*
X822633Y309442D01*
X822717Y309775D01*
X822925Y309984D01*
X823217Y310150D01*
X823508Y310192D01*
X823800Y310150D01*
X824175Y309984D01*
X824050Y311067D01*
X822925D01*
G01X819900Y312400D02*
Y308400D01*
X812500D01*
G01X833183Y313367D02*
Y315867D01*
X832142D01*
X831808Y315742D01*
X831600Y315575D01*
X831517Y315242D01*
X831600Y314909D01*
X831850Y314700D01*
X832142Y314575D01*
X833183D01*
G01X832142D02*
X831517Y313367D01*
G01X830167Y313867D02*
X829917Y313575D01*
X829583Y313409D01*
X829208Y313367D01*
X828875Y313409D01*
X828542Y313617D01*
X828333Y313867D01*
X828292Y314117D01*
X828375Y314409D01*
X828667Y314617D01*
X828958Y314700D01*
X829333D01*
G01X828958D02*
X828708Y314825D01*
X828500Y315034D01*
X828417Y315284D01*
X828500Y315534D01*
X828708Y315742D01*
X829083Y315867D01*
X829458Y315825D01*
X829833Y315659D01*
G01X825650Y313367D02*
Y315867D01*
X827192Y314075D01*
X825108D01*
G01X823758Y313659D02*
X823467Y313450D01*
X823133Y313367D01*
X822800Y313450D01*
X822508Y313700D01*
X822300Y314075D01*
X822217Y314450D01*
Y314909D01*
X822300Y315284D01*
X822508Y315617D01*
X822758Y315784D01*
X823050Y315867D01*
X823383Y315784D01*
X823633Y315617D01*
X823800Y315367D01*
X823883Y315034D01*
X823800Y314742D01*
X823592Y314450D01*
X823342Y314284D01*
X823050Y314242D01*
X822717Y314325D01*
X822467Y314534D01*
X822217Y314909D01*
G01X812500Y312600D02*
Y316600D01*
X819900D01*
G01X843459Y319167D02*
X843584Y318917D01*
X843667Y318625D01*
Y318292D01*
X843542Y317917D01*
X843334Y317625D01*
X843084Y317417D01*
X842667Y317250D01*
X842292Y317208D01*
X841917Y317292D01*
X841667Y317417D01*
X841417Y317667D01*
X841250Y317958D01*
X841167Y318250D01*
Y318542D01*
X841250Y318833D01*
X841375Y319083D01*
X841542Y319292D01*
G01X843250Y320558D02*
X843500Y320808D01*
X843625Y321100D01*
X843667Y321433D01*
X843584Y321850D01*
X843375Y322142D01*
X843125Y322225D01*
X842875Y322183D01*
X842667Y322017D01*
X842250Y321183D01*
X841959Y320808D01*
X841542Y320558D01*
X841167Y320475D01*
Y322225D01*
G01X841459Y323742D02*
X841250Y324033D01*
X841167Y324367D01*
X841250Y324700D01*
X841500Y324992D01*
X841875Y325200D01*
X842250Y325283D01*
X842709D01*
X843084Y325200D01*
X843417Y324992D01*
X843584Y324742D01*
X843667Y324450D01*
X843584Y324117D01*
X843417Y323867D01*
X843167Y323700D01*
X842834Y323617D01*
X842542Y323700D01*
X842250Y323908D01*
X842084Y324158D01*
X842042Y324450D01*
X842125Y324783D01*
X842334Y325033D01*
X842709Y325283D01*
G01X843667Y327550D02*
X843584Y327217D01*
X843375Y326967D01*
X843125Y326800D01*
X842792Y326675D01*
X842417Y326633D01*
X842042Y326675D01*
X841709Y326800D01*
X841459Y326967D01*
X841250Y327217D01*
X841167Y327550D01*
X841250Y327883D01*
X841459Y328133D01*
X841709Y328300D01*
X842042Y328425D01*
X842417Y328467D01*
X842792Y328425D01*
X843125Y328300D01*
X843375Y328133D01*
X843584Y327883D01*
X843667Y327550D01*
G01X848559Y319967D02*
X848684Y319717D01*
X848767Y319425D01*
Y319092D01*
X848642Y318717D01*
X848434Y318425D01*
X848184Y318217D01*
X847767Y318050D01*
X847392Y318008D01*
X847017Y318092D01*
X846767Y318217D01*
X846517Y318467D01*
X846350Y318758D01*
X846267Y319050D01*
Y319342D01*
X846350Y319633D01*
X846475Y319883D01*
X846642Y320092D01*
G01X848350Y321358D02*
X848600Y321608D01*
X848725Y321900D01*
X848767Y322233D01*
X848684Y322650D01*
X848475Y322942D01*
X848225Y323025D01*
X847975Y322983D01*
X847767Y322817D01*
X847350Y321983D01*
X847059Y321608D01*
X846642Y321358D01*
X846267Y321275D01*
Y323025D01*
G01Y325250D02*
X846309Y325542D01*
X846434Y325875D01*
X846642Y326083D01*
X846934Y326167D01*
X847225Y326083D01*
X847475Y325833D01*
X847600Y325458D01*
Y325042D01*
X847684Y324792D01*
X847892Y324583D01*
X848184Y324500D01*
X848475Y324625D01*
X848684Y324917D01*
X848767Y325250D01*
X848684Y325583D01*
X848475Y325875D01*
X848184Y326000D01*
X847892Y325917D01*
X847684Y325708D01*
X847600Y325458D01*
Y325042D01*
X847475Y324667D01*
X847225Y324417D01*
X846934Y324333D01*
X846642Y324417D01*
X846434Y324625D01*
X846309Y324958D01*
X846267Y325250D01*
G01X846559Y327642D02*
X846350Y327933D01*
X846267Y328267D01*
X846350Y328600D01*
X846600Y328892D01*
X846975Y329100D01*
X847350Y329183D01*
X847809D01*
X848184Y329100D01*
X848517Y328892D01*
X848684Y328642D01*
X848767Y328350D01*
X848684Y328017D01*
X848517Y327767D01*
X848267Y327600D01*
X847934Y327517D01*
X847642Y327600D01*
X847350Y327808D01*
X847184Y328058D01*
X847142Y328350D01*
X847225Y328683D01*
X847434Y328933D01*
X847809Y329183D01*
G01X827733Y290959D02*
X827983Y291084D01*
X828275Y291167D01*
X828608D01*
X828983Y291042D01*
X829275Y290834D01*
X829483Y290584D01*
X829650Y290167D01*
X829692Y289792D01*
X829608Y289417D01*
X829483Y289167D01*
X829233Y288917D01*
X828942Y288750D01*
X828650Y288667D01*
X828358D01*
X828067Y288750D01*
X827817Y288875D01*
X827608Y289042D01*
G01X826467Y289167D02*
X826217Y288875D01*
X825883Y288709D01*
X825508Y288667D01*
X825175Y288709D01*
X824842Y288917D01*
X824633Y289167D01*
X824592Y289417D01*
X824675Y289709D01*
X824967Y289917D01*
X825258Y290000D01*
X825633D01*
G01X825258D02*
X825008Y290125D01*
X824800Y290334D01*
X824717Y290584D01*
X824800Y290834D01*
X825008Y291042D01*
X825383Y291167D01*
X825758Y291125D01*
X826133Y290959D01*
G01X823367Y289042D02*
X823117Y288834D01*
X822825Y288709D01*
X822450Y288667D01*
X822075Y288750D01*
X821783Y288917D01*
X821575Y289209D01*
X821533Y289542D01*
X821617Y289875D01*
X821825Y290084D01*
X822117Y290250D01*
X822408Y290292D01*
X822700Y290250D01*
X823075Y290084D01*
X822950Y291167D01*
X821825D01*
G01X820267Y289167D02*
X820017Y288875D01*
X819683Y288709D01*
X819308Y288667D01*
X818975Y288709D01*
X818642Y288917D01*
X818433Y289167D01*
X818392Y289417D01*
X818475Y289709D01*
X818767Y289917D01*
X819058Y290000D01*
X819433D01*
G01X819058D02*
X818808Y290125D01*
X818600Y290334D01*
X818517Y290584D01*
X818600Y290834D01*
X818808Y291042D01*
X819183Y291167D01*
X819558Y291125D01*
X819933Y290959D01*
G01X823233Y296959D02*
X823483Y297084D01*
X823775Y297167D01*
X824108D01*
X824483Y297042D01*
X824775Y296834D01*
X824983Y296584D01*
X825150Y296167D01*
X825192Y295792D01*
X825108Y295417D01*
X824983Y295167D01*
X824733Y294917D01*
X824442Y294750D01*
X824150Y294667D01*
X823858D01*
X823567Y294750D01*
X823317Y294875D01*
X823108Y295042D01*
G01X821967Y295167D02*
X821717Y294875D01*
X821383Y294709D01*
X821008Y294667D01*
X820675Y294709D01*
X820342Y294917D01*
X820133Y295167D01*
X820092Y295417D01*
X820175Y295709D01*
X820467Y295917D01*
X820758Y296000D01*
X821133D01*
G01X820758D02*
X820508Y296125D01*
X820300Y296334D01*
X820217Y296584D01*
X820300Y296834D01*
X820508Y297042D01*
X820883Y297167D01*
X821258Y297125D01*
X821633Y296959D01*
G01X818033Y294667D02*
X817950Y295209D01*
X817825Y295667D01*
X817658Y296084D01*
X817450Y296542D01*
X817117Y297167D01*
X818783D01*
G01X814850Y294667D02*
X814558Y294709D01*
X814225Y294834D01*
X814017Y295042D01*
X813933Y295334D01*
X814017Y295625D01*
X814267Y295875D01*
X814642Y296000D01*
X815058D01*
X815308Y296084D01*
X815517Y296292D01*
X815600Y296584D01*
X815475Y296875D01*
X815183Y297084D01*
X814850Y297167D01*
X814517Y297084D01*
X814225Y296875D01*
X814100Y296584D01*
X814183Y296292D01*
X814392Y296084D01*
X814642Y296000D01*
X815058D01*
X815433Y295875D01*
X815683Y295625D01*
X815767Y295334D01*
X815683Y295042D01*
X815475Y294834D01*
X815142Y294709D01*
X814850Y294667D01*
G01X823733Y279959D02*
X823983Y280084D01*
X824275Y280167D01*
X824608D01*
X824983Y280042D01*
X825275Y279834D01*
X825483Y279584D01*
X825650Y279167D01*
X825692Y278792D01*
X825608Y278417D01*
X825483Y278167D01*
X825233Y277917D01*
X824942Y277750D01*
X824650Y277667D01*
X824358D01*
X824067Y277750D01*
X823817Y277875D01*
X823608Y278042D01*
G01X822467Y278167D02*
X822217Y277875D01*
X821883Y277709D01*
X821508Y277667D01*
X821175Y277709D01*
X820842Y277917D01*
X820633Y278167D01*
X820592Y278417D01*
X820675Y278709D01*
X820967Y278917D01*
X821258Y279000D01*
X821633D01*
G01X821258D02*
X821008Y279125D01*
X820800Y279334D01*
X820717Y279584D01*
X820800Y279834D01*
X821008Y280042D01*
X821383Y280167D01*
X821758Y280125D01*
X822133Y279959D01*
G01X818533Y277667D02*
X818450Y278209D01*
X818325Y278667D01*
X818158Y279084D01*
X817950Y279542D01*
X817617Y280167D01*
X819283D01*
G01X816058Y277959D02*
X815767Y277750D01*
X815433Y277667D01*
X815100Y277750D01*
X814808Y278000D01*
X814600Y278375D01*
X814517Y278750D01*
Y279209D01*
X814600Y279584D01*
X814808Y279917D01*
X815058Y280084D01*
X815350Y280167D01*
X815683Y280084D01*
X815933Y279917D01*
X816100Y279667D01*
X816183Y279334D01*
X816100Y279042D01*
X815892Y278750D01*
X815642Y278584D01*
X815350Y278542D01*
X815017Y278625D01*
X814767Y278834D01*
X814517Y279209D01*
G01X839759Y319467D02*
X839884Y319217D01*
X839967Y318925D01*
Y318592D01*
X839842Y318217D01*
X839634Y317925D01*
X839384Y317717D01*
X838967Y317550D01*
X838592Y317508D01*
X838217Y317592D01*
X837967Y317717D01*
X837717Y317967D01*
X837550Y318258D01*
X837467Y318550D01*
Y318842D01*
X837550Y319133D01*
X837675Y319383D01*
X837842Y319592D01*
G01X839550Y320858D02*
X839800Y321108D01*
X839925Y321400D01*
X839967Y321733D01*
X839884Y322150D01*
X839675Y322442D01*
X839425Y322525D01*
X839175Y322483D01*
X838967Y322317D01*
X838550Y321483D01*
X838259Y321108D01*
X837842Y320858D01*
X837467Y320775D01*
Y322525D01*
G01X837759Y324042D02*
X837550Y324333D01*
X837467Y324667D01*
X837550Y325000D01*
X837800Y325292D01*
X838175Y325500D01*
X838550Y325583D01*
X839009D01*
X839384Y325500D01*
X839717Y325292D01*
X839884Y325042D01*
X839967Y324750D01*
X839884Y324417D01*
X839717Y324167D01*
X839467Y324000D01*
X839134Y323917D01*
X838842Y324000D01*
X838550Y324208D01*
X838384Y324458D01*
X838342Y324750D01*
X838425Y325083D01*
X838634Y325333D01*
X839009Y325583D01*
G01X837467Y327850D02*
X839967D01*
X839467Y327350D01*
G01X837467D02*
Y328350D01*
G01X813459Y323867D02*
X813584Y323617D01*
X813667Y323325D01*
Y322992D01*
X813542Y322617D01*
X813334Y322325D01*
X813084Y322117D01*
X812667Y321950D01*
X812292Y321908D01*
X811917Y321992D01*
X811667Y322117D01*
X811417Y322367D01*
X811250Y322658D01*
X811167Y322950D01*
Y323242D01*
X811250Y323533D01*
X811375Y323783D01*
X811542Y323992D01*
G01X813250Y325258D02*
X813500Y325508D01*
X813625Y325800D01*
X813667Y326133D01*
X813584Y326550D01*
X813375Y326842D01*
X813125Y326925D01*
X812875Y326883D01*
X812667Y326717D01*
X812250Y325883D01*
X811959Y325508D01*
X811542Y325258D01*
X811167Y325175D01*
Y326925D01*
G01X811459Y328442D02*
X811250Y328733D01*
X811167Y329067D01*
X811250Y329400D01*
X811500Y329692D01*
X811875Y329900D01*
X812250Y329983D01*
X812709D01*
X813084Y329900D01*
X813417Y329692D01*
X813584Y329442D01*
X813667Y329150D01*
X813584Y328817D01*
X813417Y328567D01*
X813167Y328400D01*
X812834Y328317D01*
X812542Y328400D01*
X812250Y328608D01*
X812084Y328858D01*
X812042Y329150D01*
X812125Y329483D01*
X812334Y329733D01*
X812709Y329983D01*
G01X812209Y331458D02*
X812500Y331750D01*
X812667Y332000D01*
X812750Y332333D01*
X812667Y332625D01*
X812500Y332833D01*
X812250Y333000D01*
X811959Y333042D01*
X811709Y333000D01*
X811459Y332833D01*
X811250Y332583D01*
X811167Y332292D01*
X811250Y331958D01*
X811500Y331667D01*
X811875Y331500D01*
X812292Y331458D01*
X812834Y331542D01*
X813125Y331667D01*
X813417Y331875D01*
X813625Y332167D01*
X813667Y332458D01*
X813584Y332750D01*
X813375Y332958D01*
G01X817659Y323567D02*
X817784Y323317D01*
X817867Y323025D01*
Y322692D01*
X817742Y322317D01*
X817534Y322025D01*
X817284Y321817D01*
X816867Y321650D01*
X816492Y321608D01*
X816117Y321692D01*
X815867Y321817D01*
X815617Y322067D01*
X815450Y322358D01*
X815367Y322650D01*
Y322942D01*
X815450Y323233D01*
X815575Y323483D01*
X815742Y323692D01*
G01X817450Y324958D02*
X817700Y325208D01*
X817825Y325500D01*
X817867Y325833D01*
X817784Y326250D01*
X817575Y326542D01*
X817325Y326625D01*
X817075Y326583D01*
X816867Y326417D01*
X816450Y325583D01*
X816159Y325208D01*
X815742Y324958D01*
X815367Y324875D01*
Y326625D01*
G01X815659Y328142D02*
X815450Y328433D01*
X815367Y328767D01*
X815450Y329100D01*
X815700Y329392D01*
X816075Y329600D01*
X816450Y329683D01*
X816909D01*
X817284Y329600D01*
X817617Y329392D01*
X817784Y329142D01*
X817867Y328850D01*
X817784Y328517D01*
X817617Y328267D01*
X817367Y328100D01*
X817034Y328017D01*
X816742Y328100D01*
X816450Y328308D01*
X816284Y328558D01*
X816242Y328850D01*
X816325Y329183D01*
X816534Y329433D01*
X816909Y329683D01*
G01X815742Y331033D02*
X815534Y331283D01*
X815409Y331575D01*
X815367Y331950D01*
X815450Y332325D01*
X815617Y332617D01*
X815909Y332825D01*
X816242Y332867D01*
X816575Y332783D01*
X816784Y332575D01*
X816950Y332283D01*
X816992Y331992D01*
X816950Y331700D01*
X816784Y331325D01*
X817867Y331450D01*
Y332575D01*
G01X821859Y320067D02*
X821984Y319817D01*
X822067Y319525D01*
Y319192D01*
X821942Y318817D01*
X821734Y318525D01*
X821484Y318317D01*
X821067Y318150D01*
X820692Y318108D01*
X820317Y318192D01*
X820067Y318317D01*
X819817Y318567D01*
X819650Y318858D01*
X819567Y319150D01*
Y319442D01*
X819650Y319733D01*
X819775Y319983D01*
X819942Y320192D01*
G01X821650Y321458D02*
X821900Y321708D01*
X822025Y322000D01*
X822067Y322333D01*
X821984Y322750D01*
X821775Y323042D01*
X821525Y323125D01*
X821275Y323083D01*
X821067Y322917D01*
X820650Y322083D01*
X820359Y321708D01*
X819942Y321458D01*
X819567Y321375D01*
Y323125D01*
G01X819859Y324642D02*
X819650Y324933D01*
X819567Y325267D01*
X819650Y325600D01*
X819900Y325892D01*
X820275Y326100D01*
X820650Y326183D01*
X821109D01*
X821484Y326100D01*
X821817Y325892D01*
X821984Y325642D01*
X822067Y325350D01*
X821984Y325017D01*
X821817Y324767D01*
X821567Y324600D01*
X821234Y324517D01*
X820942Y324600D01*
X820650Y324808D01*
X820484Y325058D01*
X820442Y325350D01*
X820525Y325683D01*
X820734Y325933D01*
X821109Y326183D01*
G01X819567Y328950D02*
X822067D01*
X820275Y327408D01*
Y329492D01*
G01X830259Y320267D02*
X830384Y320017D01*
X830467Y319725D01*
Y319392D01*
X830342Y319017D01*
X830134Y318725D01*
X829884Y318517D01*
X829467Y318350D01*
X829092Y318308D01*
X828717Y318392D01*
X828467Y318517D01*
X828217Y318767D01*
X828050Y319058D01*
X827967Y319350D01*
Y319642D01*
X828050Y319933D01*
X828175Y320183D01*
X828342Y320392D01*
G01X830050Y321658D02*
X830300Y321908D01*
X830425Y322200D01*
X830467Y322533D01*
X830384Y322950D01*
X830175Y323242D01*
X829925Y323325D01*
X829675Y323283D01*
X829467Y323117D01*
X829050Y322283D01*
X828759Y321908D01*
X828342Y321658D01*
X827967Y321575D01*
Y323325D01*
G01X828259Y324842D02*
X828050Y325133D01*
X827967Y325467D01*
X828050Y325800D01*
X828300Y326092D01*
X828675Y326300D01*
X829050Y326383D01*
X829509D01*
X829884Y326300D01*
X830217Y326092D01*
X830384Y325842D01*
X830467Y325550D01*
X830384Y325217D01*
X830217Y324967D01*
X829967Y324800D01*
X829634Y324717D01*
X829342Y324800D01*
X829050Y325008D01*
X828884Y325258D01*
X828842Y325550D01*
X828925Y325883D01*
X829134Y326133D01*
X829509Y326383D01*
G01X828467Y327733D02*
X828175Y327983D01*
X828009Y328317D01*
X827967Y328692D01*
X828009Y329025D01*
X828217Y329358D01*
X828467Y329567D01*
X828717Y329608D01*
X829009Y329525D01*
X829217Y329233D01*
X829300Y328942D01*
Y328567D01*
G01Y328942D02*
X829425Y329192D01*
X829634Y329400D01*
X829884Y329483D01*
X830134Y329400D01*
X830342Y329192D01*
X830467Y328817D01*
X830425Y328442D01*
X830259Y328067D01*
G01X835259Y319667D02*
X835384Y319417D01*
X835467Y319125D01*
Y318792D01*
X835342Y318417D01*
X835134Y318125D01*
X834884Y317917D01*
X834467Y317750D01*
X834092Y317708D01*
X833717Y317792D01*
X833467Y317917D01*
X833217Y318167D01*
X833050Y318458D01*
X832967Y318750D01*
Y319042D01*
X833050Y319333D01*
X833175Y319583D01*
X833342Y319792D01*
G01X835050Y321058D02*
X835300Y321308D01*
X835425Y321600D01*
X835467Y321933D01*
X835384Y322350D01*
X835175Y322642D01*
X834925Y322725D01*
X834675Y322683D01*
X834467Y322517D01*
X834050Y321683D01*
X833759Y321308D01*
X833342Y321058D01*
X832967Y320975D01*
Y322725D01*
G01X833259Y324242D02*
X833050Y324533D01*
X832967Y324867D01*
X833050Y325200D01*
X833300Y325492D01*
X833675Y325700D01*
X834050Y325783D01*
X834509D01*
X834884Y325700D01*
X835217Y325492D01*
X835384Y325242D01*
X835467Y324950D01*
X835384Y324617D01*
X835217Y324367D01*
X834967Y324200D01*
X834634Y324117D01*
X834342Y324200D01*
X834050Y324408D01*
X833884Y324658D01*
X833842Y324950D01*
X833925Y325283D01*
X834134Y325533D01*
X834509Y325783D01*
G01X835050Y327258D02*
X835300Y327508D01*
X835425Y327800D01*
X835467Y328133D01*
X835384Y328550D01*
X835175Y328842D01*
X834925Y328925D01*
X834675Y328883D01*
X834467Y328717D01*
X834050Y327883D01*
X833759Y327508D01*
X833342Y327258D01*
X832967Y327175D01*
Y328925D01*
G01X819733Y273092D02*
X819983Y273217D01*
X820275Y273300D01*
X820608D01*
X820983Y273175D01*
X821275Y272967D01*
X821483Y272717D01*
X821650Y272300D01*
X821692Y271925D01*
X821608Y271550D01*
X821483Y271300D01*
X821233Y271050D01*
X820942Y270883D01*
X820650Y270800D01*
X820358D01*
X820067Y270883D01*
X819817Y271008D01*
X819608Y271175D01*
G01X818467Y271300D02*
X818217Y271008D01*
X817883Y270842D01*
X817508Y270800D01*
X817175Y270842D01*
X816842Y271050D01*
X816633Y271300D01*
X816592Y271550D01*
X816675Y271842D01*
X816967Y272050D01*
X817258Y272133D01*
X817633D01*
G01X817258D02*
X817008Y272258D01*
X816800Y272467D01*
X816717Y272717D01*
X816800Y272967D01*
X817008Y273175D01*
X817383Y273300D01*
X817758Y273258D01*
X818133Y273092D01*
G01X815367Y271175D02*
X815117Y270967D01*
X814825Y270842D01*
X814450Y270800D01*
X814075Y270883D01*
X813783Y271050D01*
X813575Y271342D01*
X813533Y271675D01*
X813617Y272008D01*
X813825Y272217D01*
X814117Y272383D01*
X814408Y272425D01*
X814700Y272383D01*
X815075Y272217D01*
X814950Y273300D01*
X813825D01*
G01X812142Y272883D02*
X811892Y273133D01*
X811600Y273258D01*
X811267Y273300D01*
X810850Y273217D01*
X810558Y273008D01*
X810475Y272758D01*
X810517Y272508D01*
X810683Y272300D01*
X811517Y271883D01*
X811892Y271592D01*
X812142Y271175D01*
X812225Y270800D01*
X810475D01*
G01X853733Y349459D02*
X853983Y349584D01*
X854275Y349667D01*
X854608D01*
X854983Y349542D01*
X855275Y349334D01*
X855483Y349084D01*
X855650Y348667D01*
X855692Y348292D01*
X855608Y347917D01*
X855483Y347667D01*
X855233Y347417D01*
X854942Y347250D01*
X854650Y347167D01*
X854358D01*
X854067Y347250D01*
X853817Y347375D01*
X853608Y347542D01*
G01X852467Y347667D02*
X852217Y347375D01*
X851883Y347209D01*
X851508Y347167D01*
X851175Y347209D01*
X850842Y347417D01*
X850633Y347667D01*
X850592Y347917D01*
X850675Y348209D01*
X850967Y348417D01*
X851258Y348500D01*
X851633D01*
G01X851258D02*
X851008Y348625D01*
X850800Y348834D01*
X850717Y349084D01*
X850800Y349334D01*
X851008Y349542D01*
X851383Y349667D01*
X851758Y349625D01*
X852133Y349459D01*
G01X849367Y347542D02*
X849117Y347334D01*
X848825Y347209D01*
X848450Y347167D01*
X848075Y347250D01*
X847783Y347417D01*
X847575Y347709D01*
X847533Y348042D01*
X847617Y348375D01*
X847825Y348584D01*
X848117Y348750D01*
X848408Y348792D01*
X848700Y348750D01*
X849075Y348584D01*
X848950Y349667D01*
X847825D01*
G01X845350Y347167D02*
Y349667D01*
X845850Y349167D01*
G01Y347167D02*
X844850D01*
G01X826839Y367943D02*
X826964Y367693D01*
X827047Y367401D01*
Y367068D01*
X826922Y366693D01*
X826714Y366401D01*
X826464Y366193D01*
X826047Y366026D01*
X825672Y365984D01*
X825297Y366068D01*
X825047Y366193D01*
X824797Y366443D01*
X824630Y366734D01*
X824547Y367026D01*
Y367318D01*
X824630Y367609D01*
X824755Y367859D01*
X824922Y368068D01*
G01X825047Y369209D02*
X824755Y369459D01*
X824589Y369793D01*
X824547Y370168D01*
X824589Y370501D01*
X824797Y370834D01*
X825047Y371043D01*
X825297Y371084D01*
X825589Y371001D01*
X825797Y370709D01*
X825880Y370418D01*
Y370043D01*
G01Y370418D02*
X826005Y370668D01*
X826214Y370876D01*
X826464Y370959D01*
X826714Y370876D01*
X826922Y370668D01*
X827047Y370293D01*
X827005Y369918D01*
X826839Y369543D01*
G01X824922Y372309D02*
X824714Y372559D01*
X824589Y372851D01*
X824547Y373226D01*
X824630Y373601D01*
X824797Y373893D01*
X825089Y374101D01*
X825422Y374143D01*
X825755Y374059D01*
X825964Y373851D01*
X826130Y373559D01*
X826172Y373268D01*
X826130Y372976D01*
X825964Y372601D01*
X827047Y372726D01*
Y373851D01*
G01X824547Y376243D02*
X825089Y376326D01*
X825547Y376451D01*
X825964Y376618D01*
X826422Y376826D01*
X827047Y377159D01*
Y375493D01*
G01X855483Y358667D02*
Y361167D01*
X854442D01*
X854108Y361042D01*
X853900Y360875D01*
X853817Y360542D01*
X853900Y360209D01*
X854150Y360000D01*
X854442Y359875D01*
X855483D01*
G01X854442D02*
X853817Y358667D01*
G01X852342Y359709D02*
X852050Y360000D01*
X851800Y360167D01*
X851467Y360250D01*
X851175Y360167D01*
X850967Y360000D01*
X850800Y359750D01*
X850758Y359459D01*
X850800Y359209D01*
X850967Y358959D01*
X851217Y358750D01*
X851508Y358667D01*
X851842Y358750D01*
X852133Y359000D01*
X852300Y359375D01*
X852342Y359792D01*
X852258Y360334D01*
X852133Y360625D01*
X851925Y360917D01*
X851633Y361125D01*
X851342Y361167D01*
X851050Y361084D01*
X850842Y360875D01*
G01X848450Y358667D02*
X848158Y358709D01*
X847825Y358834D01*
X847617Y359042D01*
X847533Y359334D01*
X847617Y359625D01*
X847867Y359875D01*
X848242Y360000D01*
X848658D01*
X848908Y360084D01*
X849117Y360292D01*
X849200Y360584D01*
X849075Y360875D01*
X848783Y361084D01*
X848450Y361167D01*
X848117Y361084D01*
X847825Y360875D01*
X847700Y360584D01*
X847783Y360292D01*
X847992Y360084D01*
X848242Y360000D01*
X848658D01*
X849033Y359875D01*
X849283Y359625D01*
X849367Y359334D01*
X849283Y359042D01*
X849075Y358834D01*
X848742Y358709D01*
X848450Y358667D01*
G01X844850D02*
Y361167D01*
X846392Y359375D01*
X844308D01*
G01X837700Y355000D02*
Y351000D01*
X830300D01*
G01X832548Y366193D02*
X835048D01*
Y367234D01*
X834923Y367568D01*
X834756Y367776D01*
X834423Y367859D01*
X834090Y367776D01*
X833881Y367526D01*
X833756Y367234D01*
Y366193D01*
G01Y367234D02*
X832548Y367859D01*
G01X833590Y369334D02*
X833881Y369626D01*
X834048Y369876D01*
X834131Y370209D01*
X834048Y370501D01*
X833881Y370709D01*
X833631Y370876D01*
X833340Y370918D01*
X833090Y370876D01*
X832840Y370709D01*
X832631Y370459D01*
X832548Y370168D01*
X832631Y369834D01*
X832881Y369543D01*
X833256Y369376D01*
X833673Y369334D01*
X834215Y369418D01*
X834506Y369543D01*
X834798Y369751D01*
X835006Y370043D01*
X835048Y370334D01*
X834965Y370626D01*
X834756Y370834D01*
G01X832548Y373226D02*
X832590Y373518D01*
X832715Y373851D01*
X832923Y374059D01*
X833215Y374143D01*
X833506Y374059D01*
X833756Y373809D01*
X833881Y373434D01*
Y373018D01*
X833965Y372768D01*
X834173Y372559D01*
X834465Y372476D01*
X834756Y372601D01*
X834965Y372893D01*
X835048Y373226D01*
X834965Y373559D01*
X834756Y373851D01*
X834465Y373976D01*
X834173Y373893D01*
X833965Y373684D01*
X833881Y373434D01*
Y373018D01*
X833756Y372643D01*
X833506Y372393D01*
X833215Y372309D01*
X832923Y372393D01*
X832715Y372601D01*
X832590Y372934D01*
X832548Y373226D01*
G01X832923Y375409D02*
X832715Y375659D01*
X832590Y375951D01*
X832548Y376326D01*
X832631Y376701D01*
X832798Y376993D01*
X833090Y377201D01*
X833423Y377243D01*
X833756Y377159D01*
X833965Y376951D01*
X834131Y376659D01*
X834173Y376368D01*
X834131Y376076D01*
X833965Y375701D01*
X835048Y375826D01*
Y376951D01*
G01X813726Y369256D02*
X817726D01*
Y361856D01*
G01X804059Y340967D02*
X804184Y340717D01*
X804267Y340425D01*
Y340092D01*
X804142Y339717D01*
X803934Y339425D01*
X803684Y339217D01*
X803267Y339050D01*
X802892Y339008D01*
X802517Y339092D01*
X802267Y339217D01*
X802017Y339467D01*
X801850Y339758D01*
X801767Y340050D01*
Y340342D01*
X801850Y340633D01*
X801975Y340883D01*
X802142Y341092D01*
G01X802267Y342233D02*
X801975Y342483D01*
X801809Y342817D01*
X801767Y343192D01*
X801809Y343525D01*
X802017Y343858D01*
X802267Y344067D01*
X802517Y344108D01*
X802809Y344025D01*
X803017Y343733D01*
X803100Y343442D01*
Y343067D01*
G01Y343442D02*
X803225Y343692D01*
X803434Y343900D01*
X803684Y343983D01*
X803934Y343900D01*
X804142Y343692D01*
X804267Y343317D01*
X804225Y342942D01*
X804059Y342567D01*
G01X804267Y346250D02*
X804184Y345917D01*
X803975Y345667D01*
X803725Y345500D01*
X803392Y345375D01*
X803017Y345333D01*
X802642Y345375D01*
X802309Y345500D01*
X802059Y345667D01*
X801850Y345917D01*
X801767Y346250D01*
X801850Y346583D01*
X802059Y346833D01*
X802309Y347000D01*
X802642Y347125D01*
X803017Y347167D01*
X803392Y347125D01*
X803725Y347000D01*
X803975Y346833D01*
X804184Y346583D01*
X804267Y346250D01*
G01Y349350D02*
X804184Y349017D01*
X803975Y348767D01*
X803725Y348600D01*
X803392Y348475D01*
X803017Y348433D01*
X802642Y348475D01*
X802309Y348600D01*
X802059Y348767D01*
X801850Y349017D01*
X801767Y349350D01*
X801850Y349683D01*
X802059Y349933D01*
X802309Y350100D01*
X802642Y350225D01*
X803017Y350267D01*
X803392Y350225D01*
X803725Y350100D01*
X803975Y349933D01*
X804184Y349683D01*
X804267Y349350D01*
G01X808059Y340967D02*
X808184Y340717D01*
X808267Y340425D01*
Y340092D01*
X808142Y339717D01*
X807934Y339425D01*
X807684Y339217D01*
X807267Y339050D01*
X806892Y339008D01*
X806517Y339092D01*
X806267Y339217D01*
X806017Y339467D01*
X805850Y339758D01*
X805767Y340050D01*
Y340342D01*
X805850Y340633D01*
X805975Y340883D01*
X806142Y341092D01*
G01X807850Y342358D02*
X808100Y342608D01*
X808225Y342900D01*
X808267Y343233D01*
X808184Y343650D01*
X807975Y343942D01*
X807725Y344025D01*
X807475Y343983D01*
X807267Y343817D01*
X806850Y342983D01*
X806559Y342608D01*
X806142Y342358D01*
X805767Y342275D01*
Y344025D01*
G01X806059Y345542D02*
X805850Y345833D01*
X805767Y346167D01*
X805850Y346500D01*
X806100Y346792D01*
X806475Y347000D01*
X806850Y347083D01*
X807309D01*
X807684Y347000D01*
X808017Y346792D01*
X808184Y346542D01*
X808267Y346250D01*
X808184Y345917D01*
X808017Y345667D01*
X807767Y345500D01*
X807434Y345417D01*
X807142Y345500D01*
X806850Y345708D01*
X806684Y345958D01*
X806642Y346250D01*
X806725Y346583D01*
X806934Y346833D01*
X807309Y347083D01*
G01X806059Y348642D02*
X805850Y348933D01*
X805767Y349267D01*
X805850Y349600D01*
X806100Y349892D01*
X806475Y350100D01*
X806850Y350183D01*
X807309D01*
X807684Y350100D01*
X808017Y349892D01*
X808184Y349642D01*
X808267Y349350D01*
X808184Y349017D01*
X808017Y348767D01*
X807767Y348600D01*
X807434Y348517D01*
X807142Y348600D01*
X806850Y348808D01*
X806684Y349058D01*
X806642Y349350D01*
X806725Y349683D01*
X806934Y349933D01*
X807309Y350183D01*
G01X812259Y340767D02*
X812384Y340517D01*
X812467Y340225D01*
Y339892D01*
X812342Y339517D01*
X812134Y339225D01*
X811884Y339017D01*
X811467Y338850D01*
X811092Y338808D01*
X810717Y338892D01*
X810467Y339017D01*
X810217Y339267D01*
X810050Y339558D01*
X809967Y339850D01*
Y340142D01*
X810050Y340433D01*
X810175Y340683D01*
X810342Y340892D01*
G01X812050Y342158D02*
X812300Y342408D01*
X812425Y342700D01*
X812467Y343033D01*
X812384Y343450D01*
X812175Y343742D01*
X811925Y343825D01*
X811675Y343783D01*
X811467Y343617D01*
X811050Y342783D01*
X810759Y342408D01*
X810342Y342158D01*
X809967Y342075D01*
Y343825D01*
G01X810259Y345342D02*
X810050Y345633D01*
X809967Y345967D01*
X810050Y346300D01*
X810300Y346592D01*
X810675Y346800D01*
X811050Y346883D01*
X811509D01*
X811884Y346800D01*
X812217Y346592D01*
X812384Y346342D01*
X812467Y346050D01*
X812384Y345717D01*
X812217Y345467D01*
X811967Y345300D01*
X811634Y345217D01*
X811342Y345300D01*
X811050Y345508D01*
X810884Y345758D01*
X810842Y346050D01*
X810925Y346383D01*
X811134Y346633D01*
X811509Y346883D01*
G01X809967Y349150D02*
X810009Y349442D01*
X810134Y349775D01*
X810342Y349983D01*
X810634Y350067D01*
X810925Y349983D01*
X811175Y349733D01*
X811300Y349358D01*
Y348942D01*
X811384Y348692D01*
X811592Y348483D01*
X811884Y348400D01*
X812175Y348525D01*
X812384Y348817D01*
X812467Y349150D01*
X812384Y349483D01*
X812175Y349775D01*
X811884Y349900D01*
X811592Y349817D01*
X811384Y349608D01*
X811300Y349358D01*
Y348942D01*
X811175Y348567D01*
X810925Y348317D01*
X810634Y348233D01*
X810342Y348317D01*
X810134Y348525D01*
X810009Y348858D01*
X809967Y349150D01*
G01X816059Y340867D02*
X816184Y340617D01*
X816267Y340325D01*
Y339992D01*
X816142Y339617D01*
X815934Y339325D01*
X815684Y339117D01*
X815267Y338950D01*
X814892Y338908D01*
X814517Y338992D01*
X814267Y339117D01*
X814017Y339367D01*
X813850Y339658D01*
X813767Y339950D01*
Y340242D01*
X813850Y340533D01*
X813975Y340783D01*
X814142Y340992D01*
G01X815850Y342258D02*
X816100Y342508D01*
X816225Y342800D01*
X816267Y343133D01*
X816184Y343550D01*
X815975Y343842D01*
X815725Y343925D01*
X815475Y343883D01*
X815267Y343717D01*
X814850Y342883D01*
X814559Y342508D01*
X814142Y342258D01*
X813767Y342175D01*
Y343925D01*
G01X814059Y345442D02*
X813850Y345733D01*
X813767Y346067D01*
X813850Y346400D01*
X814100Y346692D01*
X814475Y346900D01*
X814850Y346983D01*
X815309D01*
X815684Y346900D01*
X816017Y346692D01*
X816184Y346442D01*
X816267Y346150D01*
X816184Y345817D01*
X816017Y345567D01*
X815767Y345400D01*
X815434Y345317D01*
X815142Y345400D01*
X814850Y345608D01*
X814684Y345858D01*
X814642Y346150D01*
X814725Y346483D01*
X814934Y346733D01*
X815309Y346983D01*
G01X813767Y349167D02*
X814309Y349250D01*
X814767Y349375D01*
X815184Y349542D01*
X815642Y349750D01*
X816267Y350083D01*
Y348417D01*
G01X854233Y343959D02*
X854483Y344084D01*
X854775Y344167D01*
X855108D01*
X855483Y344042D01*
X855775Y343834D01*
X855983Y343584D01*
X856150Y343167D01*
X856192Y342792D01*
X856108Y342417D01*
X855983Y342167D01*
X855733Y341917D01*
X855442Y341750D01*
X855150Y341667D01*
X854858D01*
X854567Y341750D01*
X854317Y341875D01*
X854108Y342042D01*
G01X852967Y342167D02*
X852717Y341875D01*
X852383Y341709D01*
X852008Y341667D01*
X851675Y341709D01*
X851342Y341917D01*
X851133Y342167D01*
X851092Y342417D01*
X851175Y342709D01*
X851467Y342917D01*
X851758Y343000D01*
X852133D01*
G01X851758D02*
X851508Y343125D01*
X851300Y343334D01*
X851217Y343584D01*
X851300Y343834D01*
X851508Y344042D01*
X851883Y344167D01*
X852258Y344125D01*
X852633Y343959D01*
G01X849867Y342042D02*
X849617Y341834D01*
X849325Y341709D01*
X848950Y341667D01*
X848575Y341750D01*
X848283Y341917D01*
X848075Y342209D01*
X848033Y342542D01*
X848117Y342875D01*
X848325Y343084D01*
X848617Y343250D01*
X848908Y343292D01*
X849200Y343250D01*
X849575Y343084D01*
X849450Y344167D01*
X848325D01*
G01X845850D02*
X846183Y344084D01*
X846433Y343875D01*
X846600Y343625D01*
X846725Y343292D01*
X846767Y342917D01*
X846725Y342542D01*
X846600Y342209D01*
X846433Y341959D01*
X846183Y341750D01*
X845850Y341667D01*
X845517Y341750D01*
X845267Y341959D01*
X845100Y342209D01*
X844975Y342542D01*
X844933Y342917D01*
X844975Y343292D01*
X845100Y343625D01*
X845267Y343875D01*
X845517Y344084D01*
X845850Y344167D01*
G01X822840Y367943D02*
X822965Y367693D01*
X823048Y367401D01*
Y367068D01*
X822923Y366693D01*
X822715Y366401D01*
X822465Y366193D01*
X822048Y366026D01*
X821673Y365984D01*
X821298Y366068D01*
X821048Y366193D01*
X820798Y366443D01*
X820631Y366734D01*
X820548Y367026D01*
Y367318D01*
X820631Y367609D01*
X820756Y367859D01*
X820923Y368068D01*
G01X821048Y369209D02*
X820756Y369459D01*
X820590Y369793D01*
X820548Y370168D01*
X820590Y370501D01*
X820798Y370834D01*
X821048Y371043D01*
X821298Y371084D01*
X821590Y371001D01*
X821798Y370709D01*
X821881Y370418D01*
Y370043D01*
G01Y370418D02*
X822006Y370668D01*
X822215Y370876D01*
X822465Y370959D01*
X822715Y370876D01*
X822923Y370668D01*
X823048Y370293D01*
X823006Y369918D01*
X822840Y369543D01*
G01X820923Y372309D02*
X820715Y372559D01*
X820590Y372851D01*
X820548Y373226D01*
X820631Y373601D01*
X820798Y373893D01*
X821090Y374101D01*
X821423Y374143D01*
X821756Y374059D01*
X821965Y373851D01*
X822131Y373559D01*
X822173Y373268D01*
X822131Y372976D01*
X821965Y372601D01*
X823048Y372726D01*
Y373851D01*
G01X821590Y375534D02*
X821881Y375826D01*
X822048Y376076D01*
X822131Y376409D01*
X822048Y376701D01*
X821881Y376909D01*
X821631Y377076D01*
X821340Y377118D01*
X821090Y377076D01*
X820840Y376909D01*
X820631Y376659D01*
X820548Y376368D01*
X820631Y376034D01*
X820881Y375743D01*
X821256Y375576D01*
X821673Y375534D01*
X822215Y375618D01*
X822506Y375743D01*
X822798Y375951D01*
X823006Y376243D01*
X823048Y376534D01*
X822965Y376826D01*
X822756Y377034D01*
G01X855433Y356167D02*
Y353667D01*
X853767D01*
G01X851500D02*
Y356167D01*
X852000Y355667D01*
G01Y353667D02*
X851000D01*
G01X848400D02*
X848108Y353709D01*
X847775Y353834D01*
X847567Y354042D01*
X847483Y354334D01*
X847567Y354625D01*
X847817Y354875D01*
X848192Y355000D01*
X848608D01*
X848858Y355084D01*
X849067Y355292D01*
X849150Y355584D01*
X849025Y355875D01*
X848733Y356084D01*
X848400Y356167D01*
X848067Y356084D01*
X847775Y355875D01*
X847650Y355584D01*
X847733Y355292D01*
X847942Y355084D01*
X848192Y355000D01*
X848608D01*
X848983Y354875D01*
X849233Y354625D01*
X849317Y354334D01*
X849233Y354042D01*
X849025Y353834D01*
X848692Y353709D01*
X848400Y353667D01*
G01X827300Y350500D02*
Y343500D01*
X840700D01*
Y350500D01*
X827300D01*
G01X831048Y366243D02*
X828548D01*
Y367909D01*
G01Y370176D02*
X831048D01*
X830548Y369676D01*
G01X828548D02*
Y370676D01*
G01X828840Y372568D02*
X828631Y372859D01*
X828548Y373193D01*
X828631Y373526D01*
X828881Y373818D01*
X829256Y374026D01*
X829631Y374109D01*
X830090D01*
X830465Y374026D01*
X830798Y373818D01*
X830965Y373568D01*
X831048Y373276D01*
X830965Y372943D01*
X830798Y372693D01*
X830548Y372526D01*
X830215Y372443D01*
X829923Y372526D01*
X829631Y372734D01*
X829465Y372984D01*
X829423Y373276D01*
X829506Y373609D01*
X829715Y373859D01*
X830090Y374109D01*
G01X805826Y358756D02*
X812826D01*
Y372156D01*
X805826D01*
Y358756D01*
G01X889500Y599000D02*
X904600D01*
Y493300D01*
X844300D01*
Y523400D01*
X837800D01*
Y599000D01*
G01X854749Y527235D02*
X854999Y527360D01*
X855291Y527443D01*
X855624D01*
X855999Y527318D01*
X856291Y527110D01*
X856499Y526860D01*
X856666Y526443D01*
X856708Y526068D01*
X856624Y525693D01*
X856499Y525443D01*
X856249Y525193D01*
X855958Y525026D01*
X855666Y524943D01*
X855374D01*
X855083Y525026D01*
X854833Y525151D01*
X854624Y525318D01*
G01X852066Y524943D02*
Y527443D01*
X853608Y525651D01*
X851524D01*
G01X850383Y525443D02*
X850133Y525151D01*
X849799Y524985D01*
X849424Y524943D01*
X849091Y524985D01*
X848758Y525193D01*
X848549Y525443D01*
X848508Y525693D01*
X848591Y525985D01*
X848883Y526193D01*
X849174Y526276D01*
X849549D01*
G01X849174D02*
X848924Y526401D01*
X848716Y526610D01*
X848633Y526860D01*
X848716Y527110D01*
X848924Y527318D01*
X849299Y527443D01*
X849674Y527401D01*
X850049Y527235D01*
G01X846366Y524943D02*
X846074Y524985D01*
X845741Y525110D01*
X845533Y525318D01*
X845449Y525610D01*
X845533Y525901D01*
X845783Y526151D01*
X846158Y526276D01*
X846574D01*
X846824Y526360D01*
X847033Y526568D01*
X847116Y526860D01*
X846991Y527151D01*
X846699Y527360D01*
X846366Y527443D01*
X846033Y527360D01*
X845741Y527151D01*
X845616Y526860D01*
X845699Y526568D01*
X845908Y526360D01*
X846158Y526276D01*
X846574D01*
X846949Y526151D01*
X847199Y525901D01*
X847283Y525610D01*
X847199Y525318D01*
X846991Y525110D01*
X846658Y524985D01*
X846366Y524943D01*
G01X842733Y488459D02*
X842983Y488584D01*
X843275Y488667D01*
X843608D01*
X843983Y488542D01*
X844275Y488334D01*
X844483Y488084D01*
X844650Y487667D01*
X844692Y487292D01*
X844608Y486917D01*
X844483Y486667D01*
X844233Y486417D01*
X843942Y486250D01*
X843650Y486167D01*
X843358D01*
X843067Y486250D01*
X842817Y486375D01*
X842608Y486542D01*
G01X841342Y488250D02*
X841092Y488500D01*
X840800Y488625D01*
X840467Y488667D01*
X840050Y488584D01*
X839758Y488375D01*
X839675Y488125D01*
X839717Y487875D01*
X839883Y487667D01*
X840717Y487250D01*
X841092Y486959D01*
X841342Y486542D01*
X841425Y486167D01*
X839675D01*
G01X836950D02*
Y488667D01*
X838492Y486875D01*
X836408D01*
G01X834433Y486167D02*
X834350Y486709D01*
X834225Y487167D01*
X834058Y487584D01*
X833850Y488042D01*
X833517Y488667D01*
X835183D01*
G01X855949Y505735D02*
X856199Y505860D01*
X856491Y505943D01*
X856824D01*
X857199Y505818D01*
X857491Y505610D01*
X857699Y505360D01*
X857866Y504943D01*
X857908Y504568D01*
X857824Y504193D01*
X857699Y503943D01*
X857449Y503693D01*
X857158Y503526D01*
X856866Y503443D01*
X856574D01*
X856283Y503526D01*
X856033Y503651D01*
X855824Y503818D01*
G01X854683Y503943D02*
X854433Y503651D01*
X854099Y503485D01*
X853724Y503443D01*
X853391Y503485D01*
X853058Y503693D01*
X852849Y503943D01*
X852808Y504193D01*
X852891Y504485D01*
X853183Y504693D01*
X853474Y504776D01*
X853849D01*
G01X853474D02*
X853224Y504901D01*
X853016Y505110D01*
X852933Y505360D01*
X853016Y505610D01*
X853224Y505818D01*
X853599Y505943D01*
X853974Y505901D01*
X854349Y505735D01*
G01X850166Y503443D02*
Y505943D01*
X851708Y504151D01*
X849624D01*
G01X847649Y503443D02*
X847566Y503985D01*
X847441Y504443D01*
X847274Y504860D01*
X847066Y505318D01*
X846733Y505943D01*
X848399D01*
G01X870449Y505735D02*
X870699Y505860D01*
X870991Y505943D01*
X871324D01*
X871699Y505818D01*
X871991Y505610D01*
X872199Y505360D01*
X872366Y504943D01*
X872408Y504568D01*
X872324Y504193D01*
X872199Y503943D01*
X871949Y503693D01*
X871658Y503526D01*
X871366Y503443D01*
X871074D01*
X870783Y503526D01*
X870533Y503651D01*
X870324Y503818D01*
G01X869183Y503943D02*
X868933Y503651D01*
X868599Y503485D01*
X868224Y503443D01*
X867891Y503485D01*
X867558Y503693D01*
X867349Y503943D01*
X867308Y504193D01*
X867391Y504485D01*
X867683Y504693D01*
X867974Y504776D01*
X868349D01*
G01X867974D02*
X867724Y504901D01*
X867516Y505110D01*
X867433Y505360D01*
X867516Y505610D01*
X867724Y505818D01*
X868099Y505943D01*
X868474Y505901D01*
X868849Y505735D01*
G01X866083Y503943D02*
X865833Y503651D01*
X865499Y503485D01*
X865124Y503443D01*
X864791Y503485D01*
X864458Y503693D01*
X864249Y503943D01*
X864208Y504193D01*
X864291Y504485D01*
X864583Y504693D01*
X864874Y504776D01*
X865249D01*
G01X864874D02*
X864624Y504901D01*
X864416Y505110D01*
X864333Y505360D01*
X864416Y505610D01*
X864624Y505818D01*
X864999Y505943D01*
X865374Y505901D01*
X865749Y505735D01*
G01X862983Y503818D02*
X862733Y503610D01*
X862441Y503485D01*
X862066Y503443D01*
X861691Y503526D01*
X861399Y503693D01*
X861191Y503985D01*
X861149Y504318D01*
X861233Y504651D01*
X861441Y504860D01*
X861733Y505026D01*
X862024Y505068D01*
X862316Y505026D01*
X862691Y504860D01*
X862566Y505943D01*
X861441D01*
G01X842208Y526510D02*
X842333Y526260D01*
X842416Y525968D01*
Y525635D01*
X842291Y525260D01*
X842083Y524968D01*
X841833Y524760D01*
X841416Y524593D01*
X841041Y524551D01*
X840666Y524635D01*
X840416Y524760D01*
X840166Y525010D01*
X839999Y525301D01*
X839916Y525593D01*
Y525885D01*
X839999Y526176D01*
X840124Y526426D01*
X840291Y526635D01*
G01X840416Y527776D02*
X840124Y528026D01*
X839958Y528360D01*
X839916Y528735D01*
X839958Y529068D01*
X840166Y529401D01*
X840416Y529610D01*
X840666Y529651D01*
X840958Y529568D01*
X841166Y529276D01*
X841249Y528985D01*
Y528610D01*
G01Y528985D02*
X841374Y529235D01*
X841583Y529443D01*
X841833Y529526D01*
X842083Y529443D01*
X842291Y529235D01*
X842416Y528860D01*
X842374Y528485D01*
X842208Y528110D01*
G01X839916Y531793D02*
X839958Y532085D01*
X840083Y532418D01*
X840291Y532626D01*
X840583Y532710D01*
X840874Y532626D01*
X841124Y532376D01*
X841249Y532001D01*
Y531585D01*
X841333Y531335D01*
X841541Y531126D01*
X841833Y531043D01*
X842124Y531168D01*
X842333Y531460D01*
X842416Y531793D01*
X842333Y532126D01*
X842124Y532418D01*
X841833Y532543D01*
X841541Y532460D01*
X841333Y532251D01*
X841249Y532001D01*
Y531585D01*
X841124Y531210D01*
X840874Y530960D01*
X840583Y530876D01*
X840291Y530960D01*
X840083Y531168D01*
X839958Y531501D01*
X839916Y531793D01*
G01X840958Y534101D02*
X841249Y534393D01*
X841416Y534643D01*
X841499Y534976D01*
X841416Y535268D01*
X841249Y535476D01*
X840999Y535643D01*
X840708Y535685D01*
X840458Y535643D01*
X840208Y535476D01*
X839999Y535226D01*
X839916Y534935D01*
X839999Y534601D01*
X840249Y534310D01*
X840624Y534143D01*
X841041Y534101D01*
X841583Y534185D01*
X841874Y534310D01*
X842166Y534518D01*
X842374Y534810D01*
X842416Y535101D01*
X842333Y535393D01*
X842124Y535601D01*
G01X857699Y495443D02*
Y497943D01*
X856658D01*
X856324Y497818D01*
X856116Y497651D01*
X856033Y497318D01*
X856116Y496985D01*
X856366Y496776D01*
X856658Y496651D01*
X857699D01*
G01X856658D02*
X856033Y495443D01*
G01X854558Y496485D02*
X854266Y496776D01*
X854016Y496943D01*
X853683Y497026D01*
X853391Y496943D01*
X853183Y496776D01*
X853016Y496526D01*
X852974Y496235D01*
X853016Y495985D01*
X853183Y495735D01*
X853433Y495526D01*
X853724Y495443D01*
X854058Y495526D01*
X854349Y495776D01*
X854516Y496151D01*
X854558Y496568D01*
X854474Y497110D01*
X854349Y497401D01*
X854141Y497693D01*
X853849Y497901D01*
X853558Y497943D01*
X853266Y497860D01*
X853058Y497651D01*
G01X850666Y495443D02*
X850374Y495485D01*
X850041Y495610D01*
X849833Y495818D01*
X849749Y496110D01*
X849833Y496401D01*
X850083Y496651D01*
X850458Y496776D01*
X850874D01*
X851124Y496860D01*
X851333Y497068D01*
X851416Y497360D01*
X851291Y497651D01*
X850999Y497860D01*
X850666Y497943D01*
X850333Y497860D01*
X850041Y497651D01*
X849916Y497360D01*
X849999Y497068D01*
X850208Y496860D01*
X850458Y496776D01*
X850874D01*
X851249Y496651D01*
X851499Y496401D01*
X851583Y496110D01*
X851499Y495818D01*
X851291Y495610D01*
X850958Y495485D01*
X850666Y495443D01*
G01X848483Y495943D02*
X848233Y495651D01*
X847899Y495485D01*
X847524Y495443D01*
X847191Y495485D01*
X846858Y495693D01*
X846649Y495943D01*
X846608Y496193D01*
X846691Y496485D01*
X846983Y496693D01*
X847274Y496776D01*
X847649D01*
G01X847274D02*
X847024Y496901D01*
X846816Y497110D01*
X846733Y497360D01*
X846816Y497610D01*
X847024Y497818D01*
X847399Y497943D01*
X847774Y497901D01*
X848149Y497735D01*
G01X872199Y495443D02*
Y497943D01*
X871158D01*
X870824Y497818D01*
X870616Y497651D01*
X870533Y497318D01*
X870616Y496985D01*
X870866Y496776D01*
X871158Y496651D01*
X872199D01*
G01X871158D02*
X870533Y495443D01*
G01X869058Y496485D02*
X868766Y496776D01*
X868516Y496943D01*
X868183Y497026D01*
X867891Y496943D01*
X867683Y496776D01*
X867516Y496526D01*
X867474Y496235D01*
X867516Y495985D01*
X867683Y495735D01*
X867933Y495526D01*
X868224Y495443D01*
X868558Y495526D01*
X868849Y495776D01*
X869016Y496151D01*
X869058Y496568D01*
X868974Y497110D01*
X868849Y497401D01*
X868641Y497693D01*
X868349Y497901D01*
X868058Y497943D01*
X867766Y497860D01*
X867558Y497651D01*
G01X865166Y495443D02*
X864874Y495485D01*
X864541Y495610D01*
X864333Y495818D01*
X864249Y496110D01*
X864333Y496401D01*
X864583Y496651D01*
X864958Y496776D01*
X865374D01*
X865624Y496860D01*
X865833Y497068D01*
X865916Y497360D01*
X865791Y497651D01*
X865499Y497860D01*
X865166Y497943D01*
X864833Y497860D01*
X864541Y497651D01*
X864416Y497360D01*
X864499Y497068D01*
X864708Y496860D01*
X864958Y496776D01*
X865374D01*
X865749Y496651D01*
X865999Y496401D01*
X866083Y496110D01*
X865999Y495818D01*
X865791Y495610D01*
X865458Y495485D01*
X865166Y495443D01*
G01X862066Y497943D02*
X862399Y497860D01*
X862649Y497651D01*
X862816Y497401D01*
X862941Y497068D01*
X862983Y496693D01*
X862941Y496318D01*
X862816Y495985D01*
X862649Y495735D01*
X862399Y495526D01*
X862066Y495443D01*
X861733Y495526D01*
X861483Y495735D01*
X861316Y495985D01*
X861191Y496318D01*
X861149Y496693D01*
X861191Y497068D01*
X861316Y497401D01*
X861483Y497651D01*
X861733Y497860D01*
X862066Y497943D01*
G01X855949Y513735D02*
X856199Y513860D01*
X856491Y513943D01*
X856824D01*
X857199Y513818D01*
X857491Y513610D01*
X857699Y513360D01*
X857866Y512943D01*
X857908Y512568D01*
X857824Y512193D01*
X857699Y511943D01*
X857449Y511693D01*
X857158Y511526D01*
X856866Y511443D01*
X856574D01*
X856283Y511526D01*
X856033Y511651D01*
X855824Y511818D01*
G01X854683Y511943D02*
X854433Y511651D01*
X854099Y511485D01*
X853724Y511443D01*
X853391Y511485D01*
X853058Y511693D01*
X852849Y511943D01*
X852808Y512193D01*
X852891Y512485D01*
X853183Y512693D01*
X853474Y512776D01*
X853849D01*
G01X853474D02*
X853224Y512901D01*
X853016Y513110D01*
X852933Y513360D01*
X853016Y513610D01*
X853224Y513818D01*
X853599Y513943D01*
X853974Y513901D01*
X854349Y513735D01*
G01X850166Y511443D02*
Y513943D01*
X851708Y512151D01*
X849624D01*
G01X848274Y511735D02*
X847983Y511526D01*
X847649Y511443D01*
X847316Y511526D01*
X847024Y511776D01*
X846816Y512151D01*
X846733Y512526D01*
Y512985D01*
X846816Y513360D01*
X847024Y513693D01*
X847274Y513860D01*
X847566Y513943D01*
X847899Y513860D01*
X848149Y513693D01*
X848316Y513443D01*
X848399Y513110D01*
X848316Y512818D01*
X848108Y512526D01*
X847858Y512360D01*
X847566Y512318D01*
X847233Y512401D01*
X846983Y512610D01*
X846733Y512985D01*
G01X870449Y513735D02*
X870699Y513860D01*
X870991Y513943D01*
X871324D01*
X871699Y513818D01*
X871991Y513610D01*
X872199Y513360D01*
X872366Y512943D01*
X872408Y512568D01*
X872324Y512193D01*
X872199Y511943D01*
X871949Y511693D01*
X871658Y511526D01*
X871366Y511443D01*
X871074D01*
X870783Y511526D01*
X870533Y511651D01*
X870324Y511818D01*
G01X869183Y511943D02*
X868933Y511651D01*
X868599Y511485D01*
X868224Y511443D01*
X867891Y511485D01*
X867558Y511693D01*
X867349Y511943D01*
X867308Y512193D01*
X867391Y512485D01*
X867683Y512693D01*
X867974Y512776D01*
X868349D01*
G01X867974D02*
X867724Y512901D01*
X867516Y513110D01*
X867433Y513360D01*
X867516Y513610D01*
X867724Y513818D01*
X868099Y513943D01*
X868474Y513901D01*
X868849Y513735D01*
G01X866083Y511943D02*
X865833Y511651D01*
X865499Y511485D01*
X865124Y511443D01*
X864791Y511485D01*
X864458Y511693D01*
X864249Y511943D01*
X864208Y512193D01*
X864291Y512485D01*
X864583Y512693D01*
X864874Y512776D01*
X865249D01*
G01X864874D02*
X864624Y512901D01*
X864416Y513110D01*
X864333Y513360D01*
X864416Y513610D01*
X864624Y513818D01*
X864999Y513943D01*
X865374Y513901D01*
X865749Y513735D01*
G01X862858Y512485D02*
X862566Y512776D01*
X862316Y512943D01*
X861983Y513026D01*
X861691Y512943D01*
X861483Y512776D01*
X861316Y512526D01*
X861274Y512235D01*
X861316Y511985D01*
X861483Y511735D01*
X861733Y511526D01*
X862024Y511443D01*
X862358Y511526D01*
X862649Y511776D01*
X862816Y512151D01*
X862858Y512568D01*
X862774Y513110D01*
X862649Y513401D01*
X862441Y513693D01*
X862149Y513901D01*
X861858Y513943D01*
X861566Y513860D01*
X861358Y513651D01*
G01X870449Y509735D02*
X870699Y509860D01*
X870991Y509943D01*
X871324D01*
X871699Y509818D01*
X871991Y509610D01*
X872199Y509360D01*
X872366Y508943D01*
X872408Y508568D01*
X872324Y508193D01*
X872199Y507943D01*
X871949Y507693D01*
X871658Y507526D01*
X871366Y507443D01*
X871074D01*
X870783Y507526D01*
X870533Y507651D01*
X870324Y507818D01*
G01X869183Y507943D02*
X868933Y507651D01*
X868599Y507485D01*
X868224Y507443D01*
X867891Y507485D01*
X867558Y507693D01*
X867349Y507943D01*
X867308Y508193D01*
X867391Y508485D01*
X867683Y508693D01*
X867974Y508776D01*
X868349D01*
G01X867974D02*
X867724Y508901D01*
X867516Y509110D01*
X867433Y509360D01*
X867516Y509610D01*
X867724Y509818D01*
X868099Y509943D01*
X868474Y509901D01*
X868849Y509735D01*
G01X866083Y507943D02*
X865833Y507651D01*
X865499Y507485D01*
X865124Y507443D01*
X864791Y507485D01*
X864458Y507693D01*
X864249Y507943D01*
X864208Y508193D01*
X864291Y508485D01*
X864583Y508693D01*
X864874Y508776D01*
X865249D01*
G01X864874D02*
X864624Y508901D01*
X864416Y509110D01*
X864333Y509360D01*
X864416Y509610D01*
X864624Y509818D01*
X864999Y509943D01*
X865374Y509901D01*
X865749Y509735D01*
G01X861566Y507443D02*
Y509943D01*
X863108Y508151D01*
X861024D01*
G01X855949Y509735D02*
X856199Y509860D01*
X856491Y509943D01*
X856824D01*
X857199Y509818D01*
X857491Y509610D01*
X857699Y509360D01*
X857866Y508943D01*
X857908Y508568D01*
X857824Y508193D01*
X857699Y507943D01*
X857449Y507693D01*
X857158Y507526D01*
X856866Y507443D01*
X856574D01*
X856283Y507526D01*
X856033Y507651D01*
X855824Y507818D01*
G01X854683Y507943D02*
X854433Y507651D01*
X854099Y507485D01*
X853724Y507443D01*
X853391Y507485D01*
X853058Y507693D01*
X852849Y507943D01*
X852808Y508193D01*
X852891Y508485D01*
X853183Y508693D01*
X853474Y508776D01*
X853849D01*
G01X853474D02*
X853224Y508901D01*
X853016Y509110D01*
X852933Y509360D01*
X853016Y509610D01*
X853224Y509818D01*
X853599Y509943D01*
X853974Y509901D01*
X854349Y509735D01*
G01X850166Y507443D02*
Y509943D01*
X851708Y508151D01*
X849624D01*
G01X848358Y508485D02*
X848066Y508776D01*
X847816Y508943D01*
X847483Y509026D01*
X847191Y508943D01*
X846983Y508776D01*
X846816Y508526D01*
X846774Y508235D01*
X846816Y507985D01*
X846983Y507735D01*
X847233Y507526D01*
X847524Y507443D01*
X847858Y507526D01*
X848149Y507776D01*
X848316Y508151D01*
X848358Y508568D01*
X848274Y509110D01*
X848149Y509401D01*
X847941Y509693D01*
X847649Y509901D01*
X847358Y509943D01*
X847066Y509860D01*
X846858Y509651D01*
G01X857699Y501943D02*
Y499443D01*
X856033D01*
G01X853766D02*
Y501943D01*
X854266Y501443D01*
G01Y499443D02*
X853266D01*
G01X850749D02*
X850666Y499985D01*
X850541Y500443D01*
X850374Y500860D01*
X850166Y501318D01*
X849833Y501943D01*
X851499D01*
G01X872199D02*
Y499443D01*
X870533D01*
G01X868266D02*
Y501943D01*
X868766Y501443D01*
G01Y499443D02*
X867766D01*
G01X864666D02*
Y501943D01*
X866208Y500151D01*
X864124D01*
G01X855949Y517735D02*
X856199Y517860D01*
X856491Y517943D01*
X856824D01*
X857199Y517818D01*
X857491Y517610D01*
X857699Y517360D01*
X857866Y516943D01*
X857908Y516568D01*
X857824Y516193D01*
X857699Y515943D01*
X857449Y515693D01*
X857158Y515526D01*
X856866Y515443D01*
X856574D01*
X856283Y515526D01*
X856033Y515651D01*
X855824Y515818D01*
G01X854683Y515943D02*
X854433Y515651D01*
X854099Y515485D01*
X853724Y515443D01*
X853391Y515485D01*
X853058Y515693D01*
X852849Y515943D01*
X852808Y516193D01*
X852891Y516485D01*
X853183Y516693D01*
X853474Y516776D01*
X853849D01*
G01X853474D02*
X853224Y516901D01*
X853016Y517110D01*
X852933Y517360D01*
X853016Y517610D01*
X853224Y517818D01*
X853599Y517943D01*
X853974Y517901D01*
X854349Y517735D01*
G01X850166Y515443D02*
Y517943D01*
X851708Y516151D01*
X849624D01*
G01X847566Y515443D02*
X847274Y515485D01*
X846941Y515610D01*
X846733Y515818D01*
X846649Y516110D01*
X846733Y516401D01*
X846983Y516651D01*
X847358Y516776D01*
X847774D01*
X848024Y516860D01*
X848233Y517068D01*
X848316Y517360D01*
X848191Y517651D01*
X847899Y517860D01*
X847566Y517943D01*
X847233Y517860D01*
X846941Y517651D01*
X846816Y517360D01*
X846899Y517068D01*
X847108Y516860D01*
X847358Y516776D01*
X847774D01*
X848149Y516651D01*
X848399Y516401D01*
X848483Y516110D01*
X848399Y515818D01*
X848191Y515610D01*
X847858Y515485D01*
X847566Y515443D01*
G01X870449Y517735D02*
X870699Y517860D01*
X870991Y517943D01*
X871324D01*
X871699Y517818D01*
X871991Y517610D01*
X872199Y517360D01*
X872366Y516943D01*
X872408Y516568D01*
X872324Y516193D01*
X872199Y515943D01*
X871949Y515693D01*
X871658Y515526D01*
X871366Y515443D01*
X871074D01*
X870783Y515526D01*
X870533Y515651D01*
X870324Y515818D01*
G01X869183Y515943D02*
X868933Y515651D01*
X868599Y515485D01*
X868224Y515443D01*
X867891Y515485D01*
X867558Y515693D01*
X867349Y515943D01*
X867308Y516193D01*
X867391Y516485D01*
X867683Y516693D01*
X867974Y516776D01*
X868349D01*
G01X867974D02*
X867724Y516901D01*
X867516Y517110D01*
X867433Y517360D01*
X867516Y517610D01*
X867724Y517818D01*
X868099Y517943D01*
X868474Y517901D01*
X868849Y517735D01*
G01X866083Y515943D02*
X865833Y515651D01*
X865499Y515485D01*
X865124Y515443D01*
X864791Y515485D01*
X864458Y515693D01*
X864249Y515943D01*
X864208Y516193D01*
X864291Y516485D01*
X864583Y516693D01*
X864874Y516776D01*
X865249D01*
G01X864874D02*
X864624Y516901D01*
X864416Y517110D01*
X864333Y517360D01*
X864416Y517610D01*
X864624Y517818D01*
X864999Y517943D01*
X865374Y517901D01*
X865749Y517735D01*
G01X862149Y515443D02*
X862066Y515985D01*
X861941Y516443D01*
X861774Y516860D01*
X861566Y517318D01*
X861233Y517943D01*
X862899D01*
G01X846249Y581676D02*
X845716Y582026D01*
X845316Y582610D01*
X845049Y583426D01*
X845316Y584126D01*
X845849Y584593D01*
X846783Y584943D01*
X850383D01*
Y577943D01*
X845983D01*
X845049Y578410D01*
X844516Y579110D01*
X844249Y579926D01*
X844516Y580743D01*
X845316Y581443D01*
X846249Y581676D01*
X850383D01*
G01X859008Y570510D02*
X859133Y570260D01*
X859216Y569968D01*
Y569635D01*
X859091Y569260D01*
X858883Y568968D01*
X858633Y568760D01*
X858216Y568593D01*
X857841Y568551D01*
X857466Y568635D01*
X857216Y568760D01*
X856966Y569010D01*
X856799Y569301D01*
X856716Y569593D01*
Y569885D01*
X856799Y570176D01*
X856924Y570426D01*
X857091Y570635D01*
G01X856716Y573193D02*
X859216D01*
X857424Y571651D01*
Y573735D01*
G01X857216Y574876D02*
X856924Y575126D01*
X856758Y575460D01*
X856716Y575835D01*
X856758Y576168D01*
X856966Y576501D01*
X857216Y576710D01*
X857466Y576751D01*
X857758Y576668D01*
X857966Y576376D01*
X858049Y576085D01*
Y575710D01*
G01Y576085D02*
X858174Y576335D01*
X858383Y576543D01*
X858633Y576626D01*
X858883Y576543D01*
X859091Y576335D01*
X859216Y575960D01*
X859174Y575585D01*
X859008Y575210D01*
G01X857008Y578185D02*
X856799Y578476D01*
X856716Y578810D01*
X856799Y579143D01*
X857049Y579435D01*
X857424Y579643D01*
X857799Y579726D01*
X858258D01*
X858633Y579643D01*
X858966Y579435D01*
X859133Y579185D01*
X859216Y578893D01*
X859133Y578560D01*
X858966Y578310D01*
X858716Y578143D01*
X858383Y578060D01*
X858091Y578143D01*
X857799Y578351D01*
X857633Y578601D01*
X857591Y578893D01*
X857674Y579226D01*
X857883Y579476D01*
X858258Y579726D01*
G01X858149Y554435D02*
X858399Y554560D01*
X858691Y554643D01*
X859024D01*
X859399Y554518D01*
X859691Y554310D01*
X859899Y554060D01*
X860066Y553643D01*
X860108Y553268D01*
X860024Y552893D01*
X859899Y552643D01*
X859649Y552393D01*
X859358Y552226D01*
X859066Y552143D01*
X858774D01*
X858483Y552226D01*
X858233Y552351D01*
X858024Y552518D01*
G01X855466Y552143D02*
Y554643D01*
X857008Y552851D01*
X854924D01*
G01X852366Y552143D02*
Y554643D01*
X853908Y552851D01*
X851824D01*
G01X849766Y554643D02*
X850099Y554560D01*
X850349Y554351D01*
X850516Y554101D01*
X850641Y553768D01*
X850683Y553393D01*
X850641Y553018D01*
X850516Y552685D01*
X850349Y552435D01*
X850099Y552226D01*
X849766Y552143D01*
X849433Y552226D01*
X849183Y552435D01*
X849016Y552685D01*
X848891Y553018D01*
X848849Y553393D01*
X848891Y553768D01*
X849016Y554101D01*
X849183Y554351D01*
X849433Y554560D01*
X849766Y554643D01*
G01X865008Y570510D02*
X865133Y570260D01*
X865216Y569968D01*
Y569635D01*
X865091Y569260D01*
X864883Y568968D01*
X864633Y568760D01*
X864216Y568593D01*
X863841Y568551D01*
X863466Y568635D01*
X863216Y568760D01*
X862966Y569010D01*
X862799Y569301D01*
X862716Y569593D01*
Y569885D01*
X862799Y570176D01*
X862924Y570426D01*
X863091Y570635D01*
G01X862716Y573193D02*
X865216D01*
X863424Y571651D01*
Y573735D01*
G01X863091Y574876D02*
X862883Y575126D01*
X862758Y575418D01*
X862716Y575793D01*
X862799Y576168D01*
X862966Y576460D01*
X863258Y576668D01*
X863591Y576710D01*
X863924Y576626D01*
X864133Y576418D01*
X864299Y576126D01*
X864341Y575835D01*
X864299Y575543D01*
X864133Y575168D01*
X865216Y575293D01*
Y576418D01*
G01X862716Y579393D02*
X865216D01*
X863424Y577851D01*
Y579935D01*
G01X865708Y554110D02*
X865833Y553860D01*
X865916Y553568D01*
Y553235D01*
X865791Y552860D01*
X865583Y552568D01*
X865333Y552360D01*
X864916Y552193D01*
X864541Y552151D01*
X864166Y552235D01*
X863916Y552360D01*
X863666Y552610D01*
X863499Y552901D01*
X863416Y553193D01*
Y553485D01*
X863499Y553776D01*
X863624Y554026D01*
X863791Y554235D01*
G01X863416Y556793D02*
X865916D01*
X864124Y555251D01*
Y557335D01*
G01X863791Y558476D02*
X863583Y558726D01*
X863458Y559018D01*
X863416Y559393D01*
X863499Y559768D01*
X863666Y560060D01*
X863958Y560268D01*
X864291Y560310D01*
X864624Y560226D01*
X864833Y560018D01*
X864999Y559726D01*
X865041Y559435D01*
X864999Y559143D01*
X864833Y558768D01*
X865916Y558893D01*
Y560018D01*
G01X863791Y561576D02*
X863583Y561826D01*
X863458Y562118D01*
X863416Y562493D01*
X863499Y562868D01*
X863666Y563160D01*
X863958Y563368D01*
X864291Y563410D01*
X864624Y563326D01*
X864833Y563118D01*
X864999Y562826D01*
X865041Y562535D01*
X864999Y562243D01*
X864833Y561868D01*
X865916Y561993D01*
Y563118D01*
G01X871749Y588235D02*
X871999Y588360D01*
X872291Y588443D01*
X872624D01*
X872999Y588318D01*
X873291Y588110D01*
X873499Y587860D01*
X873666Y587443D01*
X873708Y587068D01*
X873624Y586693D01*
X873499Y586443D01*
X873249Y586193D01*
X872958Y586026D01*
X872666Y585943D01*
X872374D01*
X872083Y586026D01*
X871833Y586151D01*
X871624Y586318D01*
G01X869066Y585943D02*
Y588443D01*
X870608Y586651D01*
X868524D01*
G01X867383Y586318D02*
X867133Y586110D01*
X866841Y585985D01*
X866466Y585943D01*
X866091Y586026D01*
X865799Y586193D01*
X865591Y586485D01*
X865549Y586818D01*
X865633Y587151D01*
X865841Y587360D01*
X866133Y587526D01*
X866424Y587568D01*
X866716Y587526D01*
X867091Y587360D01*
X866966Y588443D01*
X865841D01*
G01X864158Y586985D02*
X863866Y587276D01*
X863616Y587443D01*
X863283Y587526D01*
X862991Y587443D01*
X862783Y587276D01*
X862616Y587026D01*
X862574Y586735D01*
X862616Y586485D01*
X862783Y586235D01*
X863033Y586026D01*
X863324Y585943D01*
X863658Y586026D01*
X863949Y586276D01*
X864116Y586651D01*
X864158Y587068D01*
X864074Y587610D01*
X863949Y587901D01*
X863741Y588193D01*
X863449Y588401D01*
X863158Y588443D01*
X862866Y588360D01*
X862658Y588151D01*
G01X858149Y542435D02*
X858399Y542560D01*
X858691Y542643D01*
X859024D01*
X859399Y542518D01*
X859691Y542310D01*
X859899Y542060D01*
X860066Y541643D01*
X860108Y541268D01*
X860024Y540893D01*
X859899Y540643D01*
X859649Y540393D01*
X859358Y540226D01*
X859066Y540143D01*
X858774D01*
X858483Y540226D01*
X858233Y540351D01*
X858024Y540518D01*
G01X855466Y540143D02*
Y542643D01*
X857008Y540851D01*
X854924D01*
G01X852366Y540143D02*
Y542643D01*
X853908Y540851D01*
X851824D01*
G01X849766Y540143D02*
Y542643D01*
X850266Y542143D01*
G01Y540143D02*
X849266D01*
G01X854749Y531235D02*
X854999Y531360D01*
X855291Y531443D01*
X855624D01*
X855999Y531318D01*
X856291Y531110D01*
X856499Y530860D01*
X856666Y530443D01*
X856708Y530068D01*
X856624Y529693D01*
X856499Y529443D01*
X856249Y529193D01*
X855958Y529026D01*
X855666Y528943D01*
X855374D01*
X855083Y529026D01*
X854833Y529151D01*
X854624Y529318D01*
G01X852066Y528943D02*
Y531443D01*
X853608Y529651D01*
X851524D01*
G01X850383Y529443D02*
X850133Y529151D01*
X849799Y528985D01*
X849424Y528943D01*
X849091Y528985D01*
X848758Y529193D01*
X848549Y529443D01*
X848508Y529693D01*
X848591Y529985D01*
X848883Y530193D01*
X849174Y530276D01*
X849549D01*
G01X849174D02*
X848924Y530401D01*
X848716Y530610D01*
X848633Y530860D01*
X848716Y531110D01*
X848924Y531318D01*
X849299Y531443D01*
X849674Y531401D01*
X850049Y531235D01*
G01X847283Y529318D02*
X847033Y529110D01*
X846741Y528985D01*
X846366Y528943D01*
X845991Y529026D01*
X845699Y529193D01*
X845491Y529485D01*
X845449Y529818D01*
X845533Y530151D01*
X845741Y530360D01*
X846033Y530526D01*
X846324Y530568D01*
X846616Y530526D01*
X846991Y530360D01*
X846866Y531443D01*
X845741D01*
G01X867349Y531235D02*
X867599Y531360D01*
X867891Y531443D01*
X868224D01*
X868599Y531318D01*
X868891Y531110D01*
X869099Y530860D01*
X869266Y530443D01*
X869308Y530068D01*
X869224Y529693D01*
X869099Y529443D01*
X868849Y529193D01*
X868558Y529026D01*
X868266Y528943D01*
X867974D01*
X867683Y529026D01*
X867433Y529151D01*
X867224Y529318D01*
G01X864666Y528943D02*
Y531443D01*
X866208Y529651D01*
X864124D01*
G01X862983Y529443D02*
X862733Y529151D01*
X862399Y528985D01*
X862024Y528943D01*
X861691Y528985D01*
X861358Y529193D01*
X861149Y529443D01*
X861108Y529693D01*
X861191Y529985D01*
X861483Y530193D01*
X861774Y530276D01*
X862149D01*
G01X861774D02*
X861524Y530401D01*
X861316Y530610D01*
X861233Y530860D01*
X861316Y531110D01*
X861524Y531318D01*
X861899Y531443D01*
X862274Y531401D01*
X862649Y531235D01*
G01X859758Y529985D02*
X859466Y530276D01*
X859216Y530443D01*
X858883Y530526D01*
X858591Y530443D01*
X858383Y530276D01*
X858216Y530026D01*
X858174Y529735D01*
X858216Y529485D01*
X858383Y529235D01*
X858633Y529026D01*
X858924Y528943D01*
X859258Y529026D01*
X859549Y529276D01*
X859716Y529651D01*
X859758Y530068D01*
X859674Y530610D01*
X859549Y530901D01*
X859341Y531193D01*
X859049Y531401D01*
X858758Y531443D01*
X858466Y531360D01*
X858258Y531151D01*
G01X858149Y550435D02*
X858399Y550560D01*
X858691Y550643D01*
X859024D01*
X859399Y550518D01*
X859691Y550310D01*
X859899Y550060D01*
X860066Y549643D01*
X860108Y549268D01*
X860024Y548893D01*
X859899Y548643D01*
X859649Y548393D01*
X859358Y548226D01*
X859066Y548143D01*
X858774D01*
X858483Y548226D01*
X858233Y548351D01*
X858024Y548518D01*
G01X855466Y548143D02*
Y550643D01*
X857008Y548851D01*
X854924D01*
G01X852366Y548143D02*
Y550643D01*
X853908Y548851D01*
X851824D01*
G01X850683Y548643D02*
X850433Y548351D01*
X850099Y548185D01*
X849724Y548143D01*
X849391Y548185D01*
X849058Y548393D01*
X848849Y548643D01*
X848808Y548893D01*
X848891Y549185D01*
X849183Y549393D01*
X849474Y549476D01*
X849849D01*
G01X849474D02*
X849224Y549601D01*
X849016Y549810D01*
X848933Y550060D01*
X849016Y550310D01*
X849224Y550518D01*
X849599Y550643D01*
X849974Y550601D01*
X850349Y550435D01*
G01X858149Y546435D02*
X858399Y546560D01*
X858691Y546643D01*
X859024D01*
X859399Y546518D01*
X859691Y546310D01*
X859899Y546060D01*
X860066Y545643D01*
X860108Y545268D01*
X860024Y544893D01*
X859899Y544643D01*
X859649Y544393D01*
X859358Y544226D01*
X859066Y544143D01*
X858774D01*
X858483Y544226D01*
X858233Y544351D01*
X858024Y544518D01*
G01X855466Y544143D02*
Y546643D01*
X857008Y544851D01*
X854924D01*
G01X852366Y544143D02*
Y546643D01*
X853908Y544851D01*
X851824D01*
G01X850683Y544518D02*
X850433Y544310D01*
X850141Y544185D01*
X849766Y544143D01*
X849391Y544226D01*
X849099Y544393D01*
X848891Y544685D01*
X848849Y545018D01*
X848933Y545351D01*
X849141Y545560D01*
X849433Y545726D01*
X849724Y545768D01*
X850016Y545726D01*
X850391Y545560D01*
X850266Y546643D01*
X849141D01*
G01X865916Y534643D02*
X863416D01*
G01X865916Y533685D02*
Y535601D01*
G01X863416Y536910D02*
X865916D01*
Y537910D01*
X865791Y538243D01*
X865499Y538493D01*
X865166Y538576D01*
X864833Y538493D01*
X864583Y538285D01*
X864458Y537910D01*
Y536910D01*
G01X863416Y540843D02*
X865916D01*
X865416Y540343D01*
G01X863416D02*
Y541343D01*
G01Y543943D02*
X865916D01*
X865416Y543443D01*
G01X863416D02*
Y544443D01*
G01Y546960D02*
X863958Y547043D01*
X864416Y547168D01*
X864833Y547335D01*
X865291Y547543D01*
X865916Y547876D01*
Y546210D01*
G01X858916Y583543D02*
X856416D01*
G01X858916Y582585D02*
Y584501D01*
G01X856416Y585810D02*
X858916D01*
Y586810D01*
X858791Y587143D01*
X858499Y587393D01*
X858166Y587476D01*
X857833Y587393D01*
X857583Y587185D01*
X857458Y586810D01*
Y585810D01*
G01X856416Y589743D02*
X858916D01*
X858416Y589243D01*
G01X856416D02*
Y590243D01*
G01X856916Y591926D02*
X856624Y592176D01*
X856458Y592510D01*
X856416Y592885D01*
X856458Y593218D01*
X856666Y593551D01*
X856916Y593760D01*
X857166Y593801D01*
X857458Y593718D01*
X857666Y593426D01*
X857749Y593135D01*
Y592760D01*
G01Y593135D02*
X857874Y593385D01*
X858083Y593593D01*
X858333Y593676D01*
X858583Y593593D01*
X858791Y593385D01*
X858916Y593010D01*
X858874Y592635D01*
X858708Y592260D01*
G01X856416Y596443D02*
X858916D01*
X857124Y594901D01*
Y596985D01*
G01X824749Y659843D02*
X821416Y666843D01*
X818083Y659843D01*
G01X819283Y662293D02*
X823549D01*
G01X827849Y649135D02*
X828099Y649260D01*
X828391Y649343D01*
X828724D01*
X829099Y649218D01*
X829391Y649010D01*
X829599Y648760D01*
X829766Y648343D01*
X829808Y647968D01*
X829724Y647593D01*
X829599Y647343D01*
X829349Y647093D01*
X829058Y646926D01*
X828766Y646843D01*
X828474D01*
X828183Y646926D01*
X827933Y647051D01*
X827724Y647218D01*
G01X825166Y646843D02*
Y649343D01*
X826708Y647551D01*
X824624D01*
G01X823358Y648926D02*
X823108Y649176D01*
X822816Y649301D01*
X822483Y649343D01*
X822066Y649260D01*
X821774Y649051D01*
X821691Y648801D01*
X821733Y648551D01*
X821899Y648343D01*
X822733Y647926D01*
X823108Y647635D01*
X823358Y647218D01*
X823441Y646843D01*
X821691D01*
G01X819549D02*
X819466Y647385D01*
X819341Y647843D01*
X819174Y648260D01*
X818966Y648718D01*
X818633Y649343D01*
X820299D01*
G01X870149Y618635D02*
X870399Y618760D01*
X870691Y618843D01*
X871024D01*
X871399Y618718D01*
X871691Y618510D01*
X871899Y618260D01*
X872066Y617843D01*
X872108Y617468D01*
X872024Y617093D01*
X871899Y616843D01*
X871649Y616593D01*
X871358Y616426D01*
X871066Y616343D01*
X870774D01*
X870483Y616426D01*
X870233Y616551D01*
X870024Y616718D01*
G01X867466Y616343D02*
Y618843D01*
X869008Y617051D01*
X866924D01*
G01X865658Y618426D02*
X865408Y618676D01*
X865116Y618801D01*
X864783Y618843D01*
X864366Y618760D01*
X864074Y618551D01*
X863991Y618301D01*
X864033Y618051D01*
X864199Y617843D01*
X865033Y617426D01*
X865408Y617135D01*
X865658Y616718D01*
X865741Y616343D01*
X863991D01*
G01X861766D02*
X861474Y616385D01*
X861141Y616510D01*
X860933Y616718D01*
X860849Y617010D01*
X860933Y617301D01*
X861183Y617551D01*
X861558Y617676D01*
X861974D01*
X862224Y617760D01*
X862433Y617968D01*
X862516Y618260D01*
X862391Y618551D01*
X862099Y618760D01*
X861766Y618843D01*
X861433Y618760D01*
X861141Y618551D01*
X861016Y618260D01*
X861099Y617968D01*
X861308Y617760D01*
X861558Y617676D01*
X861974D01*
X862349Y617551D01*
X862599Y617301D01*
X862683Y617010D01*
X862599Y616718D01*
X862391Y616510D01*
X862058Y616385D01*
X861766Y616343D01*
G01X827849Y645135D02*
X828099Y645260D01*
X828391Y645343D01*
X828724D01*
X829099Y645218D01*
X829391Y645010D01*
X829599Y644760D01*
X829766Y644343D01*
X829808Y643968D01*
X829724Y643593D01*
X829599Y643343D01*
X829349Y643093D01*
X829058Y642926D01*
X828766Y642843D01*
X828474D01*
X828183Y642926D01*
X827933Y643051D01*
X827724Y643218D01*
G01X825166Y642843D02*
Y645343D01*
X826708Y643551D01*
X824624D01*
G01X823358Y644926D02*
X823108Y645176D01*
X822816Y645301D01*
X822483Y645343D01*
X822066Y645260D01*
X821774Y645051D01*
X821691Y644801D01*
X821733Y644551D01*
X821899Y644343D01*
X822733Y643926D01*
X823108Y643635D01*
X823358Y643218D01*
X823441Y642843D01*
X821691D01*
G01X818966D02*
Y645343D01*
X820508Y643551D01*
X818424D01*
G01X814049Y645335D02*
X814299Y645460D01*
X814591Y645543D01*
X814924D01*
X815299Y645418D01*
X815591Y645210D01*
X815799Y644960D01*
X815966Y644543D01*
X816008Y644168D01*
X815924Y643793D01*
X815799Y643543D01*
X815549Y643293D01*
X815258Y643126D01*
X814966Y643043D01*
X814674D01*
X814383Y643126D01*
X814133Y643251D01*
X813924Y643418D01*
G01X811366Y643043D02*
Y645543D01*
X812908Y643751D01*
X810824D01*
G01X809558Y645126D02*
X809308Y645376D01*
X809016Y645501D01*
X808683Y645543D01*
X808266Y645460D01*
X807974Y645251D01*
X807891Y645001D01*
X807933Y644751D01*
X808099Y644543D01*
X808933Y644126D01*
X809308Y643835D01*
X809558Y643418D01*
X809641Y643043D01*
X807891D01*
G01X806583Y643418D02*
X806333Y643210D01*
X806041Y643085D01*
X805666Y643043D01*
X805291Y643126D01*
X804999Y643293D01*
X804791Y643585D01*
X804749Y643918D01*
X804833Y644251D01*
X805041Y644460D01*
X805333Y644626D01*
X805624Y644668D01*
X805916Y644626D01*
X806291Y644460D01*
X806166Y645543D01*
X805041D01*
G01X814049Y649335D02*
X814299Y649460D01*
X814591Y649543D01*
X814924D01*
X815299Y649418D01*
X815591Y649210D01*
X815799Y648960D01*
X815966Y648543D01*
X816008Y648168D01*
X815924Y647793D01*
X815799Y647543D01*
X815549Y647293D01*
X815258Y647126D01*
X814966Y647043D01*
X814674D01*
X814383Y647126D01*
X814133Y647251D01*
X813924Y647418D01*
G01X811366Y647043D02*
Y649543D01*
X812908Y647751D01*
X810824D01*
G01X809558Y649126D02*
X809308Y649376D01*
X809016Y649501D01*
X808683Y649543D01*
X808266Y649460D01*
X807974Y649251D01*
X807891Y649001D01*
X807933Y648751D01*
X808099Y648543D01*
X808933Y648126D01*
X809308Y647835D01*
X809558Y647418D01*
X809641Y647043D01*
X807891D01*
G01X806583Y647543D02*
X806333Y647251D01*
X805999Y647085D01*
X805624Y647043D01*
X805291Y647085D01*
X804958Y647293D01*
X804749Y647543D01*
X804708Y647793D01*
X804791Y648085D01*
X805083Y648293D01*
X805374Y648376D01*
X805749D01*
G01X805374D02*
X805124Y648501D01*
X804916Y648710D01*
X804833Y648960D01*
X804916Y649210D01*
X805124Y649418D01*
X805499Y649543D01*
X805874Y649501D01*
X806249Y649335D01*
G01X834108Y649010D02*
X834233Y648760D01*
X834316Y648468D01*
Y648135D01*
X834191Y647760D01*
X833983Y647468D01*
X833733Y647260D01*
X833316Y647093D01*
X832941Y647051D01*
X832566Y647135D01*
X832316Y647260D01*
X832066Y647510D01*
X831899Y647801D01*
X831816Y648093D01*
Y648385D01*
X831899Y648676D01*
X832024Y648926D01*
X832191Y649135D01*
G01X832316Y650276D02*
X832024Y650526D01*
X831858Y650860D01*
X831816Y651235D01*
X831858Y651568D01*
X832066Y651901D01*
X832316Y652110D01*
X832566Y652151D01*
X832858Y652068D01*
X833066Y651776D01*
X833149Y651485D01*
Y651110D01*
G01Y651485D02*
X833274Y651735D01*
X833483Y651943D01*
X833733Y652026D01*
X833983Y651943D01*
X834191Y651735D01*
X834316Y651360D01*
X834274Y650985D01*
X834108Y650610D01*
G01X831816Y654293D02*
X831858Y654585D01*
X831983Y654918D01*
X832191Y655126D01*
X832483Y655210D01*
X832774Y655126D01*
X833024Y654876D01*
X833149Y654501D01*
Y654085D01*
X833233Y653835D01*
X833441Y653626D01*
X833733Y653543D01*
X834024Y653668D01*
X834233Y653960D01*
X834316Y654293D01*
X834233Y654626D01*
X834024Y654918D01*
X833733Y655043D01*
X833441Y654960D01*
X833233Y654751D01*
X833149Y654501D01*
Y654085D01*
X833024Y653710D01*
X832774Y653460D01*
X832483Y653376D01*
X832191Y653460D01*
X831983Y653668D01*
X831858Y654001D01*
X831816Y654293D01*
G01Y657893D02*
X834316D01*
X832524Y656351D01*
Y658435D01*
G01X870149Y622635D02*
X870399Y622760D01*
X870691Y622843D01*
X871024D01*
X871399Y622718D01*
X871691Y622510D01*
X871899Y622260D01*
X872066Y621843D01*
X872108Y621468D01*
X872024Y621093D01*
X871899Y620843D01*
X871649Y620593D01*
X871358Y620426D01*
X871066Y620343D01*
X870774D01*
X870483Y620426D01*
X870233Y620551D01*
X870024Y620718D01*
G01X868883Y620843D02*
X868633Y620551D01*
X868299Y620385D01*
X867924Y620343D01*
X867591Y620385D01*
X867258Y620593D01*
X867049Y620843D01*
X867008Y621093D01*
X867091Y621385D01*
X867383Y621593D01*
X867674Y621676D01*
X868049D01*
G01X867674D02*
X867424Y621801D01*
X867216Y622010D01*
X867133Y622260D01*
X867216Y622510D01*
X867424Y622718D01*
X867799Y622843D01*
X868174Y622801D01*
X868549Y622635D01*
G01X864866Y620343D02*
X864574Y620385D01*
X864241Y620510D01*
X864033Y620718D01*
X863949Y621010D01*
X864033Y621301D01*
X864283Y621551D01*
X864658Y621676D01*
X865074D01*
X865324Y621760D01*
X865533Y621968D01*
X865616Y622260D01*
X865491Y622551D01*
X865199Y622760D01*
X864866Y622843D01*
X864533Y622760D01*
X864241Y622551D01*
X864116Y622260D01*
X864199Y621968D01*
X864408Y621760D01*
X864658Y621676D01*
X865074D01*
X865449Y621551D01*
X865699Y621301D01*
X865783Y621010D01*
X865699Y620718D01*
X865491Y620510D01*
X865158Y620385D01*
X864866Y620343D01*
G01X862683Y620718D02*
X862433Y620510D01*
X862141Y620385D01*
X861766Y620343D01*
X861391Y620426D01*
X861099Y620593D01*
X860891Y620885D01*
X860849Y621218D01*
X860933Y621551D01*
X861141Y621760D01*
X861433Y621926D01*
X861724Y621968D01*
X862016Y621926D01*
X862391Y621760D01*
X862266Y622843D01*
X861141D01*
G01X829908Y604710D02*
X830033Y604460D01*
X830116Y604168D01*
Y603835D01*
X829991Y603460D01*
X829783Y603168D01*
X829533Y602960D01*
X829116Y602793D01*
X828741Y602751D01*
X828366Y602835D01*
X828116Y602960D01*
X827866Y603210D01*
X827699Y603501D01*
X827616Y603793D01*
Y604085D01*
X827699Y604376D01*
X827824Y604626D01*
X827991Y604835D01*
G01X828116Y605976D02*
X827824Y606226D01*
X827658Y606560D01*
X827616Y606935D01*
X827658Y607268D01*
X827866Y607601D01*
X828116Y607810D01*
X828366Y607851D01*
X828658Y607768D01*
X828866Y607476D01*
X828949Y607185D01*
Y606810D01*
G01Y607185D02*
X829074Y607435D01*
X829283Y607643D01*
X829533Y607726D01*
X829783Y607643D01*
X829991Y607435D01*
X830116Y607060D01*
X830074Y606685D01*
X829908Y606310D01*
G01X827616Y609993D02*
X827658Y610285D01*
X827783Y610618D01*
X827991Y610826D01*
X828283Y610910D01*
X828574Y610826D01*
X828824Y610576D01*
X828949Y610201D01*
Y609785D01*
X829033Y609535D01*
X829241Y609326D01*
X829533Y609243D01*
X829824Y609368D01*
X830033Y609660D01*
X830116Y609993D01*
X830033Y610326D01*
X829824Y610618D01*
X829533Y610743D01*
X829241Y610660D01*
X829033Y610451D01*
X828949Y610201D01*
Y609785D01*
X828824Y609410D01*
X828574Y609160D01*
X828283Y609076D01*
X827991Y609160D01*
X827783Y609368D01*
X827658Y609701D01*
X827616Y609993D01*
G01Y613093D02*
X827658Y613385D01*
X827783Y613718D01*
X827991Y613926D01*
X828283Y614010D01*
X828574Y613926D01*
X828824Y613676D01*
X828949Y613301D01*
Y612885D01*
X829033Y612635D01*
X829241Y612426D01*
X829533Y612343D01*
X829824Y612468D01*
X830033Y612760D01*
X830116Y613093D01*
X830033Y613426D01*
X829824Y613718D01*
X829533Y613843D01*
X829241Y613760D01*
X829033Y613551D01*
X828949Y613301D01*
Y612885D01*
X828824Y612510D01*
X828574Y612260D01*
X828283Y612176D01*
X827991Y612260D01*
X827783Y612468D01*
X827658Y612801D01*
X827616Y613093D01*
G01X841349Y645035D02*
X841599Y645160D01*
X841891Y645243D01*
X842224D01*
X842599Y645118D01*
X842891Y644910D01*
X843099Y644660D01*
X843266Y644243D01*
X843308Y643868D01*
X843224Y643493D01*
X843099Y643243D01*
X842849Y642993D01*
X842558Y642826D01*
X842266Y642743D01*
X841974D01*
X841683Y642826D01*
X841433Y642951D01*
X841224Y643118D01*
G01X840083Y643243D02*
X839833Y642951D01*
X839499Y642785D01*
X839124Y642743D01*
X838791Y642785D01*
X838458Y642993D01*
X838249Y643243D01*
X838208Y643493D01*
X838291Y643785D01*
X838583Y643993D01*
X838874Y644076D01*
X839249D01*
G01X838874D02*
X838624Y644201D01*
X838416Y644410D01*
X838333Y644660D01*
X838416Y644910D01*
X838624Y645118D01*
X838999Y645243D01*
X839374Y645201D01*
X839749Y645035D01*
G01X836774Y643035D02*
X836483Y642826D01*
X836149Y642743D01*
X835816Y642826D01*
X835524Y643076D01*
X835316Y643451D01*
X835233Y643826D01*
Y644285D01*
X835316Y644660D01*
X835524Y644993D01*
X835774Y645160D01*
X836066Y645243D01*
X836399Y645160D01*
X836649Y644993D01*
X836816Y644743D01*
X836899Y644410D01*
X836816Y644118D01*
X836608Y643826D01*
X836358Y643660D01*
X836066Y643618D01*
X835733Y643701D01*
X835483Y643910D01*
X835233Y644285D01*
G01X832966Y645243D02*
X833299Y645160D01*
X833549Y644951D01*
X833716Y644701D01*
X833841Y644368D01*
X833883Y643993D01*
X833841Y643618D01*
X833716Y643285D01*
X833549Y643035D01*
X833299Y642826D01*
X832966Y642743D01*
X832633Y642826D01*
X832383Y643035D01*
X832216Y643285D01*
X832091Y643618D01*
X832049Y643993D01*
X832091Y644368D01*
X832216Y644701D01*
X832383Y644951D01*
X832633Y645160D01*
X832966Y645243D01*
G01X870149Y626635D02*
X870399Y626760D01*
X870691Y626843D01*
X871024D01*
X871399Y626718D01*
X871691Y626510D01*
X871899Y626260D01*
X872066Y625843D01*
X872108Y625468D01*
X872024Y625093D01*
X871899Y624843D01*
X871649Y624593D01*
X871358Y624426D01*
X871066Y624343D01*
X870774D01*
X870483Y624426D01*
X870233Y624551D01*
X870024Y624718D01*
G01X868883Y624843D02*
X868633Y624551D01*
X868299Y624385D01*
X867924Y624343D01*
X867591Y624385D01*
X867258Y624593D01*
X867049Y624843D01*
X867008Y625093D01*
X867091Y625385D01*
X867383Y625593D01*
X867674Y625676D01*
X868049D01*
G01X867674D02*
X867424Y625801D01*
X867216Y626010D01*
X867133Y626260D01*
X867216Y626510D01*
X867424Y626718D01*
X867799Y626843D01*
X868174Y626801D01*
X868549Y626635D01*
G01X865574Y624635D02*
X865283Y624426D01*
X864949Y624343D01*
X864616Y624426D01*
X864324Y624676D01*
X864116Y625051D01*
X864033Y625426D01*
Y625885D01*
X864116Y626260D01*
X864324Y626593D01*
X864574Y626760D01*
X864866Y626843D01*
X865199Y626760D01*
X865449Y626593D01*
X865616Y626343D01*
X865699Y626010D01*
X865616Y625718D01*
X865408Y625426D01*
X865158Y625260D01*
X864866Y625218D01*
X864533Y625301D01*
X864283Y625510D01*
X864033Y625885D01*
G01X861766Y624343D02*
Y626843D01*
X862266Y626343D01*
G01Y624343D02*
X861266D01*
G01X870149Y630635D02*
X870399Y630760D01*
X870691Y630843D01*
X871024D01*
X871399Y630718D01*
X871691Y630510D01*
X871899Y630260D01*
X872066Y629843D01*
X872108Y629468D01*
X872024Y629093D01*
X871899Y628843D01*
X871649Y628593D01*
X871358Y628426D01*
X871066Y628343D01*
X870774D01*
X870483Y628426D01*
X870233Y628551D01*
X870024Y628718D01*
G01X868883Y628843D02*
X868633Y628551D01*
X868299Y628385D01*
X867924Y628343D01*
X867591Y628385D01*
X867258Y628593D01*
X867049Y628843D01*
X867008Y629093D01*
X867091Y629385D01*
X867383Y629593D01*
X867674Y629676D01*
X868049D01*
G01X867674D02*
X867424Y629801D01*
X867216Y630010D01*
X867133Y630260D01*
X867216Y630510D01*
X867424Y630718D01*
X867799Y630843D01*
X868174Y630801D01*
X868549Y630635D01*
G01X865574Y628635D02*
X865283Y628426D01*
X864949Y628343D01*
X864616Y628426D01*
X864324Y628676D01*
X864116Y629051D01*
X864033Y629426D01*
Y629885D01*
X864116Y630260D01*
X864324Y630593D01*
X864574Y630760D01*
X864866Y630843D01*
X865199Y630760D01*
X865449Y630593D01*
X865616Y630343D01*
X865699Y630010D01*
X865616Y629718D01*
X865408Y629426D01*
X865158Y629260D01*
X864866Y629218D01*
X864533Y629301D01*
X864283Y629510D01*
X864033Y629885D01*
G01X862683Y628718D02*
X862433Y628510D01*
X862141Y628385D01*
X861766Y628343D01*
X861391Y628426D01*
X861099Y628593D01*
X860891Y628885D01*
X860849Y629218D01*
X860933Y629551D01*
X861141Y629760D01*
X861433Y629926D01*
X861724Y629968D01*
X862016Y629926D01*
X862391Y629760D01*
X862266Y630843D01*
X861141D01*
G01X806608Y654510D02*
X806733Y654260D01*
X806816Y653968D01*
Y653635D01*
X806691Y653260D01*
X806483Y652968D01*
X806233Y652760D01*
X805816Y652593D01*
X805441Y652551D01*
X805066Y652635D01*
X804816Y652760D01*
X804566Y653010D01*
X804399Y653301D01*
X804316Y653593D01*
Y653885D01*
X804399Y654176D01*
X804524Y654426D01*
X804691Y654635D01*
G01X804816Y655776D02*
X804524Y656026D01*
X804358Y656360D01*
X804316Y656735D01*
X804358Y657068D01*
X804566Y657401D01*
X804816Y657610D01*
X805066Y657651D01*
X805358Y657568D01*
X805566Y657276D01*
X805649Y656985D01*
Y656610D01*
G01Y656985D02*
X805774Y657235D01*
X805983Y657443D01*
X806233Y657526D01*
X806483Y657443D01*
X806691Y657235D01*
X806816Y656860D01*
X806774Y656485D01*
X806608Y656110D01*
G01X804316Y659710D02*
X804858Y659793D01*
X805316Y659918D01*
X805733Y660085D01*
X806191Y660293D01*
X806816Y660626D01*
Y658960D01*
G01X804316Y662893D02*
X806816D01*
X806316Y662393D01*
G01X804316D02*
Y663393D01*
G01X802608Y654510D02*
X802733Y654260D01*
X802816Y653968D01*
Y653635D01*
X802691Y653260D01*
X802483Y652968D01*
X802233Y652760D01*
X801816Y652593D01*
X801441Y652551D01*
X801066Y652635D01*
X800816Y652760D01*
X800566Y653010D01*
X800399Y653301D01*
X800316Y653593D01*
Y653885D01*
X800399Y654176D01*
X800524Y654426D01*
X800691Y654635D01*
G01X800816Y655776D02*
X800524Y656026D01*
X800358Y656360D01*
X800316Y656735D01*
X800358Y657068D01*
X800566Y657401D01*
X800816Y657610D01*
X801066Y657651D01*
X801358Y657568D01*
X801566Y657276D01*
X801649Y656985D01*
Y656610D01*
G01Y656985D02*
X801774Y657235D01*
X801983Y657443D01*
X802233Y657526D01*
X802483Y657443D01*
X802691Y657235D01*
X802816Y656860D01*
X802774Y656485D01*
X802608Y656110D01*
G01X801358Y659001D02*
X801649Y659293D01*
X801816Y659543D01*
X801899Y659876D01*
X801816Y660168D01*
X801649Y660376D01*
X801399Y660543D01*
X801108Y660585D01*
X800858Y660543D01*
X800608Y660376D01*
X800399Y660126D01*
X800316Y659835D01*
X800399Y659501D01*
X800649Y659210D01*
X801024Y659043D01*
X801441Y659001D01*
X801983Y659085D01*
X802274Y659210D01*
X802566Y659418D01*
X802774Y659710D01*
X802816Y660001D01*
X802733Y660293D01*
X802524Y660501D01*
G01X801358Y662101D02*
X801649Y662393D01*
X801816Y662643D01*
X801899Y662976D01*
X801816Y663268D01*
X801649Y663476D01*
X801399Y663643D01*
X801108Y663685D01*
X800858Y663643D01*
X800608Y663476D01*
X800399Y663226D01*
X800316Y662935D01*
X800399Y662601D01*
X800649Y662310D01*
X801024Y662143D01*
X801441Y662101D01*
X801983Y662185D01*
X802274Y662310D01*
X802566Y662518D01*
X802774Y662810D01*
X802816Y663101D01*
X802733Y663393D01*
X802524Y663601D01*
G01X863849Y657535D02*
X864099Y657660D01*
X864391Y657743D01*
X864724D01*
X865099Y657618D01*
X865391Y657410D01*
X865599Y657160D01*
X865766Y656743D01*
X865808Y656368D01*
X865724Y655993D01*
X865599Y655743D01*
X865349Y655493D01*
X865058Y655326D01*
X864766Y655243D01*
X864474D01*
X864183Y655326D01*
X863933Y655451D01*
X863724Y655618D01*
G01X862583Y655743D02*
X862333Y655451D01*
X861999Y655285D01*
X861624Y655243D01*
X861291Y655285D01*
X860958Y655493D01*
X860749Y655743D01*
X860708Y655993D01*
X860791Y656285D01*
X861083Y656493D01*
X861374Y656576D01*
X861749D01*
G01X861374D02*
X861124Y656701D01*
X860916Y656910D01*
X860833Y657160D01*
X860916Y657410D01*
X861124Y657618D01*
X861499Y657743D01*
X861874Y657701D01*
X862249Y657535D01*
G01X858566Y655243D02*
X858274Y655285D01*
X857941Y655410D01*
X857733Y655618D01*
X857649Y655910D01*
X857733Y656201D01*
X857983Y656451D01*
X858358Y656576D01*
X858774D01*
X859024Y656660D01*
X859233Y656868D01*
X859316Y657160D01*
X859191Y657451D01*
X858899Y657660D01*
X858566Y657743D01*
X858233Y657660D01*
X857941Y657451D01*
X857816Y657160D01*
X857899Y656868D01*
X858108Y656660D01*
X858358Y656576D01*
X858774D01*
X859149Y656451D01*
X859399Y656201D01*
X859483Y655910D01*
X859399Y655618D01*
X859191Y655410D01*
X858858Y655285D01*
X858566Y655243D01*
G01X855466Y657743D02*
X855799Y657660D01*
X856049Y657451D01*
X856216Y657201D01*
X856341Y656868D01*
X856383Y656493D01*
X856341Y656118D01*
X856216Y655785D01*
X856049Y655535D01*
X855799Y655326D01*
X855466Y655243D01*
X855133Y655326D01*
X854883Y655535D01*
X854716Y655785D01*
X854591Y656118D01*
X854549Y656493D01*
X854591Y656868D01*
X854716Y657201D01*
X854883Y657451D01*
X855133Y657660D01*
X855466Y657743D01*
G01X856108Y644510D02*
X856233Y644260D01*
X856316Y643968D01*
Y643635D01*
X856191Y643260D01*
X855983Y642968D01*
X855733Y642760D01*
X855316Y642593D01*
X854941Y642551D01*
X854566Y642635D01*
X854316Y642760D01*
X854066Y643010D01*
X853899Y643301D01*
X853816Y643593D01*
Y643885D01*
X853899Y644176D01*
X854024Y644426D01*
X854191Y644635D01*
G01X854316Y645776D02*
X854024Y646026D01*
X853858Y646360D01*
X853816Y646735D01*
X853858Y647068D01*
X854066Y647401D01*
X854316Y647610D01*
X854566Y647651D01*
X854858Y647568D01*
X855066Y647276D01*
X855149Y646985D01*
Y646610D01*
G01Y646985D02*
X855274Y647235D01*
X855483Y647443D01*
X855733Y647526D01*
X855983Y647443D01*
X856191Y647235D01*
X856316Y646860D01*
X856274Y646485D01*
X856108Y646110D01*
G01X853816Y649793D02*
X853858Y650085D01*
X853983Y650418D01*
X854191Y650626D01*
X854483Y650710D01*
X854774Y650626D01*
X855024Y650376D01*
X855149Y650001D01*
Y649585D01*
X855233Y649335D01*
X855441Y649126D01*
X855733Y649043D01*
X856024Y649168D01*
X856233Y649460D01*
X856316Y649793D01*
X856233Y650126D01*
X856024Y650418D01*
X855733Y650543D01*
X855441Y650460D01*
X855233Y650251D01*
X855149Y650001D01*
Y649585D01*
X855024Y649210D01*
X854774Y648960D01*
X854483Y648876D01*
X854191Y648960D01*
X853983Y649168D01*
X853858Y649501D01*
X853816Y649793D01*
G01Y652893D02*
X856316D01*
X855816Y652393D01*
G01X853816D02*
Y653393D01*
G01X814149Y634535D02*
X814399Y634660D01*
X814691Y634743D01*
X815024D01*
X815399Y634618D01*
X815691Y634410D01*
X815899Y634160D01*
X816066Y633743D01*
X816108Y633368D01*
X816024Y632993D01*
X815899Y632743D01*
X815649Y632493D01*
X815358Y632326D01*
X815066Y632243D01*
X814774D01*
X814483Y632326D01*
X814233Y632451D01*
X814024Y632618D01*
G01X812883Y632743D02*
X812633Y632451D01*
X812299Y632285D01*
X811924Y632243D01*
X811591Y632285D01*
X811258Y632493D01*
X811049Y632743D01*
X811008Y632993D01*
X811091Y633285D01*
X811383Y633493D01*
X811674Y633576D01*
X812049D01*
G01X811674D02*
X811424Y633701D01*
X811216Y633910D01*
X811133Y634160D01*
X811216Y634410D01*
X811424Y634618D01*
X811799Y634743D01*
X812174Y634701D01*
X812549Y634535D01*
G01X809574Y632535D02*
X809283Y632326D01*
X808949Y632243D01*
X808616Y632326D01*
X808324Y632576D01*
X808116Y632951D01*
X808033Y633326D01*
Y633785D01*
X808116Y634160D01*
X808324Y634493D01*
X808574Y634660D01*
X808866Y634743D01*
X809199Y634660D01*
X809449Y634493D01*
X809616Y634243D01*
X809699Y633910D01*
X809616Y633618D01*
X809408Y633326D01*
X809158Y633160D01*
X808866Y633118D01*
X808533Y633201D01*
X808283Y633410D01*
X808033Y633785D01*
G01X806558Y633285D02*
X806266Y633576D01*
X806016Y633743D01*
X805683Y633826D01*
X805391Y633743D01*
X805183Y633576D01*
X805016Y633326D01*
X804974Y633035D01*
X805016Y632785D01*
X805183Y632535D01*
X805433Y632326D01*
X805724Y632243D01*
X806058Y632326D01*
X806349Y632576D01*
X806516Y632951D01*
X806558Y633368D01*
X806474Y633910D01*
X806349Y634201D01*
X806141Y634493D01*
X805849Y634701D01*
X805558Y634743D01*
X805266Y634660D01*
X805058Y634451D01*
G01X863008Y634910D02*
X863133Y634660D01*
X863216Y634368D01*
Y634035D01*
X863091Y633660D01*
X862883Y633368D01*
X862633Y633160D01*
X862216Y632993D01*
X861841Y632951D01*
X861466Y633035D01*
X861216Y633160D01*
X860966Y633410D01*
X860799Y633701D01*
X860716Y633993D01*
Y634285D01*
X860799Y634576D01*
X860924Y634826D01*
X861091Y635035D01*
G01X861216Y636176D02*
X860924Y636426D01*
X860758Y636760D01*
X860716Y637135D01*
X860758Y637468D01*
X860966Y637801D01*
X861216Y638010D01*
X861466Y638051D01*
X861758Y637968D01*
X861966Y637676D01*
X862049Y637385D01*
Y637010D01*
G01Y637385D02*
X862174Y637635D01*
X862383Y637843D01*
X862633Y637926D01*
X862883Y637843D01*
X863091Y637635D01*
X863216Y637260D01*
X863174Y636885D01*
X863008Y636510D01*
G01X861008Y639485D02*
X860799Y639776D01*
X860716Y640110D01*
X860799Y640443D01*
X861049Y640735D01*
X861424Y640943D01*
X861799Y641026D01*
X862258D01*
X862633Y640943D01*
X862966Y640735D01*
X863133Y640485D01*
X863216Y640193D01*
X863133Y639860D01*
X862966Y639610D01*
X862716Y639443D01*
X862383Y639360D01*
X862091Y639443D01*
X861799Y639651D01*
X861633Y639901D01*
X861591Y640193D01*
X861674Y640526D01*
X861883Y640776D01*
X862258Y641026D01*
G01X860716Y643210D02*
X861258Y643293D01*
X861716Y643418D01*
X862133Y643585D01*
X862591Y643793D01*
X863216Y644126D01*
Y642460D01*
G01X814149Y626535D02*
X814399Y626660D01*
X814691Y626743D01*
X815024D01*
X815399Y626618D01*
X815691Y626410D01*
X815899Y626160D01*
X816066Y625743D01*
X816108Y625368D01*
X816024Y624993D01*
X815899Y624743D01*
X815649Y624493D01*
X815358Y624326D01*
X815066Y624243D01*
X814774D01*
X814483Y624326D01*
X814233Y624451D01*
X814024Y624618D01*
G01X812883Y624743D02*
X812633Y624451D01*
X812299Y624285D01*
X811924Y624243D01*
X811591Y624285D01*
X811258Y624493D01*
X811049Y624743D01*
X811008Y624993D01*
X811091Y625285D01*
X811383Y625493D01*
X811674Y625576D01*
X812049D01*
G01X811674D02*
X811424Y625701D01*
X811216Y625910D01*
X811133Y626160D01*
X811216Y626410D01*
X811424Y626618D01*
X811799Y626743D01*
X812174Y626701D01*
X812549Y626535D01*
G01X809574Y624535D02*
X809283Y624326D01*
X808949Y624243D01*
X808616Y624326D01*
X808324Y624576D01*
X808116Y624951D01*
X808033Y625326D01*
Y625785D01*
X808116Y626160D01*
X808324Y626493D01*
X808574Y626660D01*
X808866Y626743D01*
X809199Y626660D01*
X809449Y626493D01*
X809616Y626243D01*
X809699Y625910D01*
X809616Y625618D01*
X809408Y625326D01*
X809158Y625160D01*
X808866Y625118D01*
X808533Y625201D01*
X808283Y625410D01*
X808033Y625785D01*
G01X805766Y624243D02*
X805474Y624285D01*
X805141Y624410D01*
X804933Y624618D01*
X804849Y624910D01*
X804933Y625201D01*
X805183Y625451D01*
X805558Y625576D01*
X805974D01*
X806224Y625660D01*
X806433Y625868D01*
X806516Y626160D01*
X806391Y626451D01*
X806099Y626660D01*
X805766Y626743D01*
X805433Y626660D01*
X805141Y626451D01*
X805016Y626160D01*
X805099Y625868D01*
X805308Y625660D01*
X805558Y625576D01*
X805974D01*
X806349Y625451D01*
X806599Y625201D01*
X806683Y624910D01*
X806599Y624618D01*
X806391Y624410D01*
X806058Y624285D01*
X805766Y624243D01*
G01X842249Y634435D02*
X842499Y634560D01*
X842791Y634643D01*
X843124D01*
X843499Y634518D01*
X843791Y634310D01*
X843999Y634060D01*
X844166Y633643D01*
X844208Y633268D01*
X844124Y632893D01*
X843999Y632643D01*
X843749Y632393D01*
X843458Y632226D01*
X843166Y632143D01*
X842874D01*
X842583Y632226D01*
X842333Y632351D01*
X842124Y632518D01*
G01X839566Y632143D02*
Y634643D01*
X841108Y632851D01*
X839024D01*
G01X836966Y634643D02*
X837299Y634560D01*
X837549Y634351D01*
X837716Y634101D01*
X837841Y633768D01*
X837883Y633393D01*
X837841Y633018D01*
X837716Y632685D01*
X837549Y632435D01*
X837299Y632226D01*
X836966Y632143D01*
X836633Y632226D01*
X836383Y632435D01*
X836216Y632685D01*
X836091Y633018D01*
X836049Y633393D01*
X836091Y633768D01*
X836216Y634101D01*
X836383Y634351D01*
X836633Y634560D01*
X836966Y634643D01*
G01X833866D02*
X834199Y634560D01*
X834449Y634351D01*
X834616Y634101D01*
X834741Y633768D01*
X834783Y633393D01*
X834741Y633018D01*
X834616Y632685D01*
X834449Y632435D01*
X834199Y632226D01*
X833866Y632143D01*
X833533Y632226D01*
X833283Y632435D01*
X833116Y632685D01*
X832991Y633018D01*
X832949Y633393D01*
X832991Y633768D01*
X833116Y634101D01*
X833283Y634351D01*
X833533Y634560D01*
X833866Y634643D01*
G01X842249Y638435D02*
X842499Y638560D01*
X842791Y638643D01*
X843124D01*
X843499Y638518D01*
X843791Y638310D01*
X843999Y638060D01*
X844166Y637643D01*
X844208Y637268D01*
X844124Y636893D01*
X843999Y636643D01*
X843749Y636393D01*
X843458Y636226D01*
X843166Y636143D01*
X842874D01*
X842583Y636226D01*
X842333Y636351D01*
X842124Y636518D01*
G01X839566Y636143D02*
Y638643D01*
X841108Y636851D01*
X839024D01*
G01X836966Y638643D02*
X837299Y638560D01*
X837549Y638351D01*
X837716Y638101D01*
X837841Y637768D01*
X837883Y637393D01*
X837841Y637018D01*
X837716Y636685D01*
X837549Y636435D01*
X837299Y636226D01*
X836966Y636143D01*
X836633Y636226D01*
X836383Y636435D01*
X836216Y636685D01*
X836091Y637018D01*
X836049Y637393D01*
X836091Y637768D01*
X836216Y638101D01*
X836383Y638351D01*
X836633Y638560D01*
X836966Y638643D01*
G01X833866Y636143D02*
Y638643D01*
X834366Y638143D01*
G01Y636143D02*
X833366D01*
G01X856449Y634135D02*
X856699Y634260D01*
X856991Y634343D01*
X857324D01*
X857699Y634218D01*
X857991Y634010D01*
X858199Y633760D01*
X858366Y633343D01*
X858408Y632968D01*
X858324Y632593D01*
X858199Y632343D01*
X857949Y632093D01*
X857658Y631926D01*
X857366Y631843D01*
X857074D01*
X856783Y631926D01*
X856533Y632051D01*
X856324Y632218D01*
G01X853766Y631843D02*
Y634343D01*
X855308Y632551D01*
X853224D01*
G01X851166Y634343D02*
X851499Y634260D01*
X851749Y634051D01*
X851916Y633801D01*
X852041Y633468D01*
X852083Y633093D01*
X852041Y632718D01*
X851916Y632385D01*
X851749Y632135D01*
X851499Y631926D01*
X851166Y631843D01*
X850833Y631926D01*
X850583Y632135D01*
X850416Y632385D01*
X850291Y632718D01*
X850249Y633093D01*
X850291Y633468D01*
X850416Y633801D01*
X850583Y634051D01*
X850833Y634260D01*
X851166Y634343D01*
G01X848858Y633926D02*
X848608Y634176D01*
X848316Y634301D01*
X847983Y634343D01*
X847566Y634260D01*
X847274Y634051D01*
X847191Y633801D01*
X847233Y633551D01*
X847399Y633343D01*
X848233Y632926D01*
X848608Y632635D01*
X848858Y632218D01*
X848941Y631843D01*
X847191D01*
G01X842249Y626435D02*
X842499Y626560D01*
X842791Y626643D01*
X843124D01*
X843499Y626518D01*
X843791Y626310D01*
X843999Y626060D01*
X844166Y625643D01*
X844208Y625268D01*
X844124Y624893D01*
X843999Y624643D01*
X843749Y624393D01*
X843458Y624226D01*
X843166Y624143D01*
X842874D01*
X842583Y624226D01*
X842333Y624351D01*
X842124Y624518D01*
G01X839566Y624143D02*
Y626643D01*
X841108Y624851D01*
X839024D01*
G01X836966Y626643D02*
X837299Y626560D01*
X837549Y626351D01*
X837716Y626101D01*
X837841Y625768D01*
X837883Y625393D01*
X837841Y625018D01*
X837716Y624685D01*
X837549Y624435D01*
X837299Y624226D01*
X836966Y624143D01*
X836633Y624226D01*
X836383Y624435D01*
X836216Y624685D01*
X836091Y625018D01*
X836049Y625393D01*
X836091Y625768D01*
X836216Y626101D01*
X836383Y626351D01*
X836633Y626560D01*
X836966Y626643D01*
G01X834783Y624643D02*
X834533Y624351D01*
X834199Y624185D01*
X833824Y624143D01*
X833491Y624185D01*
X833158Y624393D01*
X832949Y624643D01*
X832908Y624893D01*
X832991Y625185D01*
X833283Y625393D01*
X833574Y625476D01*
X833949D01*
G01X833574D02*
X833324Y625601D01*
X833116Y625810D01*
X833033Y626060D01*
X833116Y626310D01*
X833324Y626518D01*
X833699Y626643D01*
X834074Y626601D01*
X834449Y626435D01*
G01X856449Y638135D02*
X856699Y638260D01*
X856991Y638343D01*
X857324D01*
X857699Y638218D01*
X857991Y638010D01*
X858199Y637760D01*
X858366Y637343D01*
X858408Y636968D01*
X858324Y636593D01*
X858199Y636343D01*
X857949Y636093D01*
X857658Y635926D01*
X857366Y635843D01*
X857074D01*
X856783Y635926D01*
X856533Y636051D01*
X856324Y636218D01*
G01X853766Y635843D02*
Y638343D01*
X855308Y636551D01*
X853224D01*
G01X851166Y638343D02*
X851499Y638260D01*
X851749Y638051D01*
X851916Y637801D01*
X852041Y637468D01*
X852083Y637093D01*
X852041Y636718D01*
X851916Y636385D01*
X851749Y636135D01*
X851499Y635926D01*
X851166Y635843D01*
X850833Y635926D01*
X850583Y636135D01*
X850416Y636385D01*
X850291Y636718D01*
X850249Y637093D01*
X850291Y637468D01*
X850416Y637801D01*
X850583Y638051D01*
X850833Y638260D01*
X851166Y638343D01*
G01X848983Y636218D02*
X848733Y636010D01*
X848441Y635885D01*
X848066Y635843D01*
X847691Y635926D01*
X847399Y636093D01*
X847191Y636385D01*
X847149Y636718D01*
X847233Y637051D01*
X847441Y637260D01*
X847733Y637426D01*
X848024Y637468D01*
X848316Y637426D01*
X848691Y637260D01*
X848566Y638343D01*
X847441D01*
G01X828249Y638335D02*
X828499Y638460D01*
X828791Y638543D01*
X829124D01*
X829499Y638418D01*
X829791Y638210D01*
X829999Y637960D01*
X830166Y637543D01*
X830208Y637168D01*
X830124Y636793D01*
X829999Y636543D01*
X829749Y636293D01*
X829458Y636126D01*
X829166Y636043D01*
X828874D01*
X828583Y636126D01*
X828333Y636251D01*
X828124Y636418D01*
G01X825566Y636043D02*
Y638543D01*
X827108Y636751D01*
X825024D01*
G01X822966Y638543D02*
X823299Y638460D01*
X823549Y638251D01*
X823716Y638001D01*
X823841Y637668D01*
X823883Y637293D01*
X823841Y636918D01*
X823716Y636585D01*
X823549Y636335D01*
X823299Y636126D01*
X822966Y636043D01*
X822633Y636126D01*
X822383Y636335D01*
X822216Y636585D01*
X822091Y636918D01*
X822049Y637293D01*
X822091Y637668D01*
X822216Y638001D01*
X822383Y638251D01*
X822633Y638460D01*
X822966Y638543D01*
G01X820658Y637085D02*
X820366Y637376D01*
X820116Y637543D01*
X819783Y637626D01*
X819491Y637543D01*
X819283Y637376D01*
X819116Y637126D01*
X819074Y636835D01*
X819116Y636585D01*
X819283Y636335D01*
X819533Y636126D01*
X819824Y636043D01*
X820158Y636126D01*
X820449Y636376D01*
X820616Y636751D01*
X820658Y637168D01*
X820574Y637710D01*
X820449Y638001D01*
X820241Y638293D01*
X819949Y638501D01*
X819658Y638543D01*
X819366Y638460D01*
X819158Y638251D01*
G01X842249Y630435D02*
X842499Y630560D01*
X842791Y630643D01*
X843124D01*
X843499Y630518D01*
X843791Y630310D01*
X843999Y630060D01*
X844166Y629643D01*
X844208Y629268D01*
X844124Y628893D01*
X843999Y628643D01*
X843749Y628393D01*
X843458Y628226D01*
X843166Y628143D01*
X842874D01*
X842583Y628226D01*
X842333Y628351D01*
X842124Y628518D01*
G01X839566Y628143D02*
Y630643D01*
X841108Y628851D01*
X839024D01*
G01X836966Y630643D02*
X837299Y630560D01*
X837549Y630351D01*
X837716Y630101D01*
X837841Y629768D01*
X837883Y629393D01*
X837841Y629018D01*
X837716Y628685D01*
X837549Y628435D01*
X837299Y628226D01*
X836966Y628143D01*
X836633Y628226D01*
X836383Y628435D01*
X836216Y628685D01*
X836091Y629018D01*
X836049Y629393D01*
X836091Y629768D01*
X836216Y630101D01*
X836383Y630351D01*
X836633Y630560D01*
X836966Y630643D01*
G01X833949Y628143D02*
X833866Y628685D01*
X833741Y629143D01*
X833574Y629560D01*
X833366Y630018D01*
X833033Y630643D01*
X834699D01*
G01X828249Y618335D02*
X828499Y618460D01*
X828791Y618543D01*
X829124D01*
X829499Y618418D01*
X829791Y618210D01*
X829999Y617960D01*
X830166Y617543D01*
X830208Y617168D01*
X830124Y616793D01*
X829999Y616543D01*
X829749Y616293D01*
X829458Y616126D01*
X829166Y616043D01*
X828874D01*
X828583Y616126D01*
X828333Y616251D01*
X828124Y616418D01*
G01X825566Y616043D02*
Y618543D01*
X827108Y616751D01*
X825024D01*
G01X822966Y618543D02*
X823299Y618460D01*
X823549Y618251D01*
X823716Y618001D01*
X823841Y617668D01*
X823883Y617293D01*
X823841Y616918D01*
X823716Y616585D01*
X823549Y616335D01*
X823299Y616126D01*
X822966Y616043D01*
X822633Y616126D01*
X822383Y616335D01*
X822216Y616585D01*
X822091Y616918D01*
X822049Y617293D01*
X822091Y617668D01*
X822216Y618001D01*
X822383Y618251D01*
X822633Y618460D01*
X822966Y618543D01*
G01X819866Y616043D02*
X819574Y616085D01*
X819241Y616210D01*
X819033Y616418D01*
X818949Y616710D01*
X819033Y617001D01*
X819283Y617251D01*
X819658Y617376D01*
X820074D01*
X820324Y617460D01*
X820533Y617668D01*
X820616Y617960D01*
X820491Y618251D01*
X820199Y618460D01*
X819866Y618543D01*
X819533Y618460D01*
X819241Y618251D01*
X819116Y617960D01*
X819199Y617668D01*
X819408Y617460D01*
X819658Y617376D01*
X820074D01*
X820449Y617251D01*
X820699Y617001D01*
X820783Y616710D01*
X820699Y616418D01*
X820491Y616210D01*
X820158Y616085D01*
X819866Y616043D01*
G01X856449Y626135D02*
X856699Y626260D01*
X856991Y626343D01*
X857324D01*
X857699Y626218D01*
X857991Y626010D01*
X858199Y625760D01*
X858366Y625343D01*
X858408Y624968D01*
X858324Y624593D01*
X858199Y624343D01*
X857949Y624093D01*
X857658Y623926D01*
X857366Y623843D01*
X857074D01*
X856783Y623926D01*
X856533Y624051D01*
X856324Y624218D01*
G01X853766Y623843D02*
Y626343D01*
X855308Y624551D01*
X853224D01*
G01X851166Y626343D02*
X851499Y626260D01*
X851749Y626051D01*
X851916Y625801D01*
X852041Y625468D01*
X852083Y625093D01*
X852041Y624718D01*
X851916Y624385D01*
X851749Y624135D01*
X851499Y623926D01*
X851166Y623843D01*
X850833Y623926D01*
X850583Y624135D01*
X850416Y624385D01*
X850291Y624718D01*
X850249Y625093D01*
X850291Y625468D01*
X850416Y625801D01*
X850583Y626051D01*
X850833Y626260D01*
X851166Y626343D01*
G01X848774Y624135D02*
X848483Y623926D01*
X848149Y623843D01*
X847816Y623926D01*
X847524Y624176D01*
X847316Y624551D01*
X847233Y624926D01*
Y625385D01*
X847316Y625760D01*
X847524Y626093D01*
X847774Y626260D01*
X848066Y626343D01*
X848399Y626260D01*
X848649Y626093D01*
X848816Y625843D01*
X848899Y625510D01*
X848816Y625218D01*
X848608Y624926D01*
X848358Y624760D01*
X848066Y624718D01*
X847733Y624801D01*
X847483Y625010D01*
X847233Y625385D01*
G01X828249Y622335D02*
X828499Y622460D01*
X828791Y622543D01*
X829124D01*
X829499Y622418D01*
X829791Y622210D01*
X829999Y621960D01*
X830166Y621543D01*
X830208Y621168D01*
X830124Y620793D01*
X829999Y620543D01*
X829749Y620293D01*
X829458Y620126D01*
X829166Y620043D01*
X828874D01*
X828583Y620126D01*
X828333Y620251D01*
X828124Y620418D01*
G01X825566Y620043D02*
Y622543D01*
X827108Y620751D01*
X825024D01*
G01X822966Y620043D02*
Y622543D01*
X823466Y622043D01*
G01Y620043D02*
X822466D01*
G01X819866Y622543D02*
X820199Y622460D01*
X820449Y622251D01*
X820616Y622001D01*
X820741Y621668D01*
X820783Y621293D01*
X820741Y620918D01*
X820616Y620585D01*
X820449Y620335D01*
X820199Y620126D01*
X819866Y620043D01*
X819533Y620126D01*
X819283Y620335D01*
X819116Y620585D01*
X818991Y620918D01*
X818949Y621293D01*
X818991Y621668D01*
X819116Y622001D01*
X819283Y622251D01*
X819533Y622460D01*
X819866Y622543D01*
G01X814149Y630535D02*
X814399Y630660D01*
X814691Y630743D01*
X815024D01*
X815399Y630618D01*
X815691Y630410D01*
X815899Y630160D01*
X816066Y629743D01*
X816108Y629368D01*
X816024Y628993D01*
X815899Y628743D01*
X815649Y628493D01*
X815358Y628326D01*
X815066Y628243D01*
X814774D01*
X814483Y628326D01*
X814233Y628451D01*
X814024Y628618D01*
G01X811466Y628243D02*
Y630743D01*
X813008Y628951D01*
X810924D01*
G01X808866Y628243D02*
Y630743D01*
X809366Y630243D01*
G01Y628243D02*
X808366D01*
G01X806683Y628743D02*
X806433Y628451D01*
X806099Y628285D01*
X805724Y628243D01*
X805391Y628285D01*
X805058Y628493D01*
X804849Y628743D01*
X804808Y628993D01*
X804891Y629285D01*
X805183Y629493D01*
X805474Y629576D01*
X805849D01*
G01X805474D02*
X805224Y629701D01*
X805016Y629910D01*
X804933Y630160D01*
X805016Y630410D01*
X805224Y630618D01*
X805599Y630743D01*
X805974Y630701D01*
X806349Y630535D01*
G01X814149Y622535D02*
X814399Y622660D01*
X814691Y622743D01*
X815024D01*
X815399Y622618D01*
X815691Y622410D01*
X815899Y622160D01*
X816066Y621743D01*
X816108Y621368D01*
X816024Y620993D01*
X815899Y620743D01*
X815649Y620493D01*
X815358Y620326D01*
X815066Y620243D01*
X814774D01*
X814483Y620326D01*
X814233Y620451D01*
X814024Y620618D01*
G01X811466Y620243D02*
Y622743D01*
X813008Y620951D01*
X810924D01*
G01X808866Y620243D02*
Y622743D01*
X809366Y622243D01*
G01Y620243D02*
X808366D01*
G01X805266D02*
Y622743D01*
X806808Y620951D01*
X804724D01*
G01X814149Y618535D02*
X814399Y618660D01*
X814691Y618743D01*
X815024D01*
X815399Y618618D01*
X815691Y618410D01*
X815899Y618160D01*
X816066Y617743D01*
X816108Y617368D01*
X816024Y616993D01*
X815899Y616743D01*
X815649Y616493D01*
X815358Y616326D01*
X815066Y616243D01*
X814774D01*
X814483Y616326D01*
X814233Y616451D01*
X814024Y616618D01*
G01X811466Y616243D02*
Y618743D01*
X813008Y616951D01*
X810924D01*
G01X808866Y616243D02*
Y618743D01*
X809366Y618243D01*
G01Y616243D02*
X808366D01*
G01X806683Y616618D02*
X806433Y616410D01*
X806141Y616285D01*
X805766Y616243D01*
X805391Y616326D01*
X805099Y616493D01*
X804891Y616785D01*
X804849Y617118D01*
X804933Y617451D01*
X805141Y617660D01*
X805433Y617826D01*
X805724Y617868D01*
X806016Y617826D01*
X806391Y617660D01*
X806266Y618743D01*
X805141D01*
G01X828249Y634335D02*
X828499Y634460D01*
X828791Y634543D01*
X829124D01*
X829499Y634418D01*
X829791Y634210D01*
X829999Y633960D01*
X830166Y633543D01*
X830208Y633168D01*
X830124Y632793D01*
X829999Y632543D01*
X829749Y632293D01*
X829458Y632126D01*
X829166Y632043D01*
X828874D01*
X828583Y632126D01*
X828333Y632251D01*
X828124Y632418D01*
G01X825566Y632043D02*
Y634543D01*
X827108Y632751D01*
X825024D01*
G01X822966Y632043D02*
Y634543D01*
X823466Y634043D01*
G01Y632043D02*
X822466D01*
G01X820658Y633085D02*
X820366Y633376D01*
X820116Y633543D01*
X819783Y633626D01*
X819491Y633543D01*
X819283Y633376D01*
X819116Y633126D01*
X819074Y632835D01*
X819116Y632585D01*
X819283Y632335D01*
X819533Y632126D01*
X819824Y632043D01*
X820158Y632126D01*
X820449Y632376D01*
X820616Y632751D01*
X820658Y633168D01*
X820574Y633710D01*
X820449Y634001D01*
X820241Y634293D01*
X819949Y634501D01*
X819658Y634543D01*
X819366Y634460D01*
X819158Y634251D01*
G01X814149Y638535D02*
X814399Y638660D01*
X814691Y638743D01*
X815024D01*
X815399Y638618D01*
X815691Y638410D01*
X815899Y638160D01*
X816066Y637743D01*
X816108Y637368D01*
X816024Y636993D01*
X815899Y636743D01*
X815649Y636493D01*
X815358Y636326D01*
X815066Y636243D01*
X814774D01*
X814483Y636326D01*
X814233Y636451D01*
X814024Y636618D01*
G01X811466Y636243D02*
Y638743D01*
X813008Y636951D01*
X810924D01*
G01X808866Y636243D02*
Y638743D01*
X809366Y638243D01*
G01Y636243D02*
X808366D01*
G01X805849D02*
X805766Y636785D01*
X805641Y637243D01*
X805474Y637660D01*
X805266Y638118D01*
X804933Y638743D01*
X806599D01*
G01X828249Y626335D02*
X828499Y626460D01*
X828791Y626543D01*
X829124D01*
X829499Y626418D01*
X829791Y626210D01*
X829999Y625960D01*
X830166Y625543D01*
X830208Y625168D01*
X830124Y624793D01*
X829999Y624543D01*
X829749Y624293D01*
X829458Y624126D01*
X829166Y624043D01*
X828874D01*
X828583Y624126D01*
X828333Y624251D01*
X828124Y624418D01*
G01X825566Y624043D02*
Y626543D01*
X827108Y624751D01*
X825024D01*
G01X822966Y624043D02*
Y626543D01*
X823466Y626043D01*
G01Y624043D02*
X822466D01*
G01X819866D02*
X819574Y624085D01*
X819241Y624210D01*
X819033Y624418D01*
X818949Y624710D01*
X819033Y625001D01*
X819283Y625251D01*
X819658Y625376D01*
X820074D01*
X820324Y625460D01*
X820533Y625668D01*
X820616Y625960D01*
X820491Y626251D01*
X820199Y626460D01*
X819866Y626543D01*
X819533Y626460D01*
X819241Y626251D01*
X819116Y625960D01*
X819199Y625668D01*
X819408Y625460D01*
X819658Y625376D01*
X820074D01*
X820449Y625251D01*
X820699Y625001D01*
X820783Y624710D01*
X820699Y624418D01*
X820491Y624210D01*
X820158Y624085D01*
X819866Y624043D01*
G01X828249Y630335D02*
X828499Y630460D01*
X828791Y630543D01*
X829124D01*
X829499Y630418D01*
X829791Y630210D01*
X829999Y629960D01*
X830166Y629543D01*
X830208Y629168D01*
X830124Y628793D01*
X829999Y628543D01*
X829749Y628293D01*
X829458Y628126D01*
X829166Y628043D01*
X828874D01*
X828583Y628126D01*
X828333Y628251D01*
X828124Y628418D01*
G01X825566Y628043D02*
Y630543D01*
X827108Y628751D01*
X825024D01*
G01X822966Y628043D02*
Y630543D01*
X823466Y630043D01*
G01Y628043D02*
X822466D01*
G01X820574Y628335D02*
X820283Y628126D01*
X819949Y628043D01*
X819616Y628126D01*
X819324Y628376D01*
X819116Y628751D01*
X819033Y629126D01*
Y629585D01*
X819116Y629960D01*
X819324Y630293D01*
X819574Y630460D01*
X819866Y630543D01*
X820199Y630460D01*
X820449Y630293D01*
X820616Y630043D01*
X820699Y629710D01*
X820616Y629418D01*
X820408Y629126D01*
X820158Y628960D01*
X819866Y628918D01*
X819533Y629001D01*
X819283Y629210D01*
X819033Y629585D01*
G01X842249Y618435D02*
X842499Y618560D01*
X842791Y618643D01*
X843124D01*
X843499Y618518D01*
X843791Y618310D01*
X843999Y618060D01*
X844166Y617643D01*
X844208Y617268D01*
X844124Y616893D01*
X843999Y616643D01*
X843749Y616393D01*
X843458Y616226D01*
X843166Y616143D01*
X842874D01*
X842583Y616226D01*
X842333Y616351D01*
X842124Y616518D01*
G01X839566Y616143D02*
Y618643D01*
X841108Y616851D01*
X839024D01*
G01X837758Y618226D02*
X837508Y618476D01*
X837216Y618601D01*
X836883Y618643D01*
X836466Y618560D01*
X836174Y618351D01*
X836091Y618101D01*
X836133Y617851D01*
X836299Y617643D01*
X837133Y617226D01*
X837508Y616935D01*
X837758Y616518D01*
X837841Y616143D01*
X836091D01*
G01X833866Y618643D02*
X834199Y618560D01*
X834449Y618351D01*
X834616Y618101D01*
X834741Y617768D01*
X834783Y617393D01*
X834741Y617018D01*
X834616Y616685D01*
X834449Y616435D01*
X834199Y616226D01*
X833866Y616143D01*
X833533Y616226D01*
X833283Y616435D01*
X833116Y616685D01*
X832991Y617018D01*
X832949Y617393D01*
X832991Y617768D01*
X833116Y618101D01*
X833283Y618351D01*
X833533Y618560D01*
X833866Y618643D01*
G01X842249Y622435D02*
X842499Y622560D01*
X842791Y622643D01*
X843124D01*
X843499Y622518D01*
X843791Y622310D01*
X843999Y622060D01*
X844166Y621643D01*
X844208Y621268D01*
X844124Y620893D01*
X843999Y620643D01*
X843749Y620393D01*
X843458Y620226D01*
X843166Y620143D01*
X842874D01*
X842583Y620226D01*
X842333Y620351D01*
X842124Y620518D01*
G01X839566Y620143D02*
Y622643D01*
X841108Y620851D01*
X839024D01*
G01X837758Y622226D02*
X837508Y622476D01*
X837216Y622601D01*
X836883Y622643D01*
X836466Y622560D01*
X836174Y622351D01*
X836091Y622101D01*
X836133Y621851D01*
X836299Y621643D01*
X837133Y621226D01*
X837508Y620935D01*
X837758Y620518D01*
X837841Y620143D01*
X836091D01*
G01X833866D02*
Y622643D01*
X834366Y622143D01*
G01Y620143D02*
X833366D01*
G01X856449Y630135D02*
X856699Y630260D01*
X856991Y630343D01*
X857324D01*
X857699Y630218D01*
X857991Y630010D01*
X858199Y629760D01*
X858366Y629343D01*
X858408Y628968D01*
X858324Y628593D01*
X858199Y628343D01*
X857949Y628093D01*
X857658Y627926D01*
X857366Y627843D01*
X857074D01*
X856783Y627926D01*
X856533Y628051D01*
X856324Y628218D01*
G01X853766Y627843D02*
Y630343D01*
X855308Y628551D01*
X853224D01*
G01X851958Y629926D02*
X851708Y630176D01*
X851416Y630301D01*
X851083Y630343D01*
X850666Y630260D01*
X850374Y630051D01*
X850291Y629801D01*
X850333Y629551D01*
X850499Y629343D01*
X851333Y628926D01*
X851708Y628635D01*
X851958Y628218D01*
X852041Y627843D01*
X850291D01*
G01X848858Y629926D02*
X848608Y630176D01*
X848316Y630301D01*
X847983Y630343D01*
X847566Y630260D01*
X847274Y630051D01*
X847191Y629801D01*
X847233Y629551D01*
X847399Y629343D01*
X848233Y628926D01*
X848608Y628635D01*
X848858Y628218D01*
X848941Y627843D01*
X847191D01*
G01X852108Y644510D02*
X852233Y644260D01*
X852316Y643968D01*
Y643635D01*
X852191Y643260D01*
X851983Y642968D01*
X851733Y642760D01*
X851316Y642593D01*
X850941Y642551D01*
X850566Y642635D01*
X850316Y642760D01*
X850066Y643010D01*
X849899Y643301D01*
X849816Y643593D01*
Y643885D01*
X849899Y644176D01*
X850024Y644426D01*
X850191Y644635D01*
G01X850316Y645776D02*
X850024Y646026D01*
X849858Y646360D01*
X849816Y646735D01*
X849858Y647068D01*
X850066Y647401D01*
X850316Y647610D01*
X850566Y647651D01*
X850858Y647568D01*
X851066Y647276D01*
X851149Y646985D01*
Y646610D01*
G01Y646985D02*
X851274Y647235D01*
X851483Y647443D01*
X851733Y647526D01*
X851983Y647443D01*
X852191Y647235D01*
X852316Y646860D01*
X852274Y646485D01*
X852108Y646110D01*
G01X849816Y649710D02*
X850358Y649793D01*
X850816Y649918D01*
X851233Y650085D01*
X851691Y650293D01*
X852316Y650626D01*
Y648960D01*
G01X850191Y651976D02*
X849983Y652226D01*
X849858Y652518D01*
X849816Y652893D01*
X849899Y653268D01*
X850066Y653560D01*
X850358Y653768D01*
X850691Y653810D01*
X851024Y653726D01*
X851233Y653518D01*
X851399Y653226D01*
X851441Y652935D01*
X851399Y652643D01*
X851233Y652268D01*
X852316Y652393D01*
Y653518D01*
G01X863849Y661535D02*
X864099Y661660D01*
X864391Y661743D01*
X864724D01*
X865099Y661618D01*
X865391Y661410D01*
X865599Y661160D01*
X865766Y660743D01*
X865808Y660368D01*
X865724Y659993D01*
X865599Y659743D01*
X865349Y659493D01*
X865058Y659326D01*
X864766Y659243D01*
X864474D01*
X864183Y659326D01*
X863933Y659451D01*
X863724Y659618D01*
G01X862583Y659743D02*
X862333Y659451D01*
X861999Y659285D01*
X861624Y659243D01*
X861291Y659285D01*
X860958Y659493D01*
X860749Y659743D01*
X860708Y659993D01*
X860791Y660285D01*
X861083Y660493D01*
X861374Y660576D01*
X861749D01*
G01X861374D02*
X861124Y660701D01*
X860916Y660910D01*
X860833Y661160D01*
X860916Y661410D01*
X861124Y661618D01*
X861499Y661743D01*
X861874Y661701D01*
X862249Y661535D01*
G01X859483Y659618D02*
X859233Y659410D01*
X858941Y659285D01*
X858566Y659243D01*
X858191Y659326D01*
X857899Y659493D01*
X857691Y659785D01*
X857649Y660118D01*
X857733Y660451D01*
X857941Y660660D01*
X858233Y660826D01*
X858524Y660868D01*
X858816Y660826D01*
X859191Y660660D01*
X859066Y661743D01*
X857941D01*
G01X854966Y659243D02*
Y661743D01*
X856508Y659951D01*
X854424D01*
G01X817449Y677235D02*
X817699Y677360D01*
X817991Y677443D01*
X818324D01*
X818699Y677318D01*
X818991Y677110D01*
X819199Y676860D01*
X819366Y676443D01*
X819408Y676068D01*
X819324Y675693D01*
X819199Y675443D01*
X818949Y675193D01*
X818658Y675026D01*
X818366Y674943D01*
X818074D01*
X817783Y675026D01*
X817533Y675151D01*
X817324Y675318D01*
G01X816183Y675443D02*
X815933Y675151D01*
X815599Y674985D01*
X815224Y674943D01*
X814891Y674985D01*
X814558Y675193D01*
X814349Y675443D01*
X814308Y675693D01*
X814391Y675985D01*
X814683Y676193D01*
X814974Y676276D01*
X815349D01*
G01X814974D02*
X814724Y676401D01*
X814516Y676610D01*
X814433Y676860D01*
X814516Y677110D01*
X814724Y677318D01*
X815099Y677443D01*
X815474Y677401D01*
X815849Y677235D01*
G01X812958Y675985D02*
X812666Y676276D01*
X812416Y676443D01*
X812083Y676526D01*
X811791Y676443D01*
X811583Y676276D01*
X811416Y676026D01*
X811374Y675735D01*
X811416Y675485D01*
X811583Y675235D01*
X811833Y675026D01*
X812124Y674943D01*
X812458Y675026D01*
X812749Y675276D01*
X812916Y675651D01*
X812958Y676068D01*
X812874Y676610D01*
X812749Y676901D01*
X812541Y677193D01*
X812249Y677401D01*
X811958Y677443D01*
X811666Y677360D01*
X811458Y677151D01*
G01X809149Y674943D02*
X809066Y675485D01*
X808941Y675943D01*
X808774Y676360D01*
X808566Y676818D01*
X808233Y677443D01*
X809899D01*
G01X849749Y665635D02*
X849999Y665760D01*
X850291Y665843D01*
X850624D01*
X850999Y665718D01*
X851291Y665510D01*
X851499Y665260D01*
X851666Y664843D01*
X851708Y664468D01*
X851624Y664093D01*
X851499Y663843D01*
X851249Y663593D01*
X850958Y663426D01*
X850666Y663343D01*
X850374D01*
X850083Y663426D01*
X849833Y663551D01*
X849624Y663718D01*
G01X848483Y663843D02*
X848233Y663551D01*
X847899Y663385D01*
X847524Y663343D01*
X847191Y663385D01*
X846858Y663593D01*
X846649Y663843D01*
X846608Y664093D01*
X846691Y664385D01*
X846983Y664593D01*
X847274Y664676D01*
X847649D01*
G01X847274D02*
X847024Y664801D01*
X846816Y665010D01*
X846733Y665260D01*
X846816Y665510D01*
X847024Y665718D01*
X847399Y665843D01*
X847774Y665801D01*
X848149Y665635D01*
G01X845258Y664385D02*
X844966Y664676D01*
X844716Y664843D01*
X844383Y664926D01*
X844091Y664843D01*
X843883Y664676D01*
X843716Y664426D01*
X843674Y664135D01*
X843716Y663885D01*
X843883Y663635D01*
X844133Y663426D01*
X844424Y663343D01*
X844758Y663426D01*
X845049Y663676D01*
X845216Y664051D01*
X845258Y664468D01*
X845174Y665010D01*
X845049Y665301D01*
X844841Y665593D01*
X844549Y665801D01*
X844258Y665843D01*
X843966Y665760D01*
X843758Y665551D01*
G01X841366Y663343D02*
X841074Y663385D01*
X840741Y663510D01*
X840533Y663718D01*
X840449Y664010D01*
X840533Y664301D01*
X840783Y664551D01*
X841158Y664676D01*
X841574D01*
X841824Y664760D01*
X842033Y664968D01*
X842116Y665260D01*
X841991Y665551D01*
X841699Y665760D01*
X841366Y665843D01*
X841033Y665760D01*
X840741Y665551D01*
X840616Y665260D01*
X840699Y664968D01*
X840908Y664760D01*
X841158Y664676D01*
X841574D01*
X841949Y664551D01*
X842199Y664301D01*
X842283Y664010D01*
X842199Y663718D01*
X841991Y663510D01*
X841658Y663385D01*
X841366Y663343D01*
G01X849749Y669635D02*
X849999Y669760D01*
X850291Y669843D01*
X850624D01*
X850999Y669718D01*
X851291Y669510D01*
X851499Y669260D01*
X851666Y668843D01*
X851708Y668468D01*
X851624Y668093D01*
X851499Y667843D01*
X851249Y667593D01*
X850958Y667426D01*
X850666Y667343D01*
X850374D01*
X850083Y667426D01*
X849833Y667551D01*
X849624Y667718D01*
G01X848483Y667843D02*
X848233Y667551D01*
X847899Y667385D01*
X847524Y667343D01*
X847191Y667385D01*
X846858Y667593D01*
X846649Y667843D01*
X846608Y668093D01*
X846691Y668385D01*
X846983Y668593D01*
X847274Y668676D01*
X847649D01*
G01X847274D02*
X847024Y668801D01*
X846816Y669010D01*
X846733Y669260D01*
X846816Y669510D01*
X847024Y669718D01*
X847399Y669843D01*
X847774Y669801D01*
X848149Y669635D01*
G01X845258Y668385D02*
X844966Y668676D01*
X844716Y668843D01*
X844383Y668926D01*
X844091Y668843D01*
X843883Y668676D01*
X843716Y668426D01*
X843674Y668135D01*
X843716Y667885D01*
X843883Y667635D01*
X844133Y667426D01*
X844424Y667343D01*
X844758Y667426D01*
X845049Y667676D01*
X845216Y668051D01*
X845258Y668468D01*
X845174Y669010D01*
X845049Y669301D01*
X844841Y669593D01*
X844549Y669801D01*
X844258Y669843D01*
X843966Y669760D01*
X843758Y669551D01*
G01X842074Y667635D02*
X841783Y667426D01*
X841449Y667343D01*
X841116Y667426D01*
X840824Y667676D01*
X840616Y668051D01*
X840533Y668426D01*
Y668885D01*
X840616Y669260D01*
X840824Y669593D01*
X841074Y669760D01*
X841366Y669843D01*
X841699Y669760D01*
X841949Y669593D01*
X842116Y669343D01*
X842199Y669010D01*
X842116Y668718D01*
X841908Y668426D01*
X841658Y668260D01*
X841366Y668218D01*
X841033Y668301D01*
X840783Y668510D01*
X840533Y668885D01*
G01X863549Y669435D02*
X863799Y669560D01*
X864091Y669643D01*
X864424D01*
X864799Y669518D01*
X865091Y669310D01*
X865299Y669060D01*
X865466Y668643D01*
X865508Y668268D01*
X865424Y667893D01*
X865299Y667643D01*
X865049Y667393D01*
X864758Y667226D01*
X864466Y667143D01*
X864174D01*
X863883Y667226D01*
X863633Y667351D01*
X863424Y667518D01*
G01X862283Y667643D02*
X862033Y667351D01*
X861699Y667185D01*
X861324Y667143D01*
X860991Y667185D01*
X860658Y667393D01*
X860449Y667643D01*
X860408Y667893D01*
X860491Y668185D01*
X860783Y668393D01*
X861074Y668476D01*
X861449D01*
G01X861074D02*
X860824Y668601D01*
X860616Y668810D01*
X860533Y669060D01*
X860616Y669310D01*
X860824Y669518D01*
X861199Y669643D01*
X861574Y669601D01*
X861949Y669435D01*
G01X859183Y667518D02*
X858933Y667310D01*
X858641Y667185D01*
X858266Y667143D01*
X857891Y667226D01*
X857599Y667393D01*
X857391Y667685D01*
X857349Y668018D01*
X857433Y668351D01*
X857641Y668560D01*
X857933Y668726D01*
X858224Y668768D01*
X858516Y668726D01*
X858891Y668560D01*
X858766Y669643D01*
X857641D01*
G01X856083Y667518D02*
X855833Y667310D01*
X855541Y667185D01*
X855166Y667143D01*
X854791Y667226D01*
X854499Y667393D01*
X854291Y667685D01*
X854249Y668018D01*
X854333Y668351D01*
X854541Y668560D01*
X854833Y668726D01*
X855124Y668768D01*
X855416Y668726D01*
X855791Y668560D01*
X855666Y669643D01*
X854541D01*
G01X815208Y682810D02*
X815333Y682560D01*
X815416Y682268D01*
Y681935D01*
X815291Y681560D01*
X815083Y681268D01*
X814833Y681060D01*
X814416Y680893D01*
X814041Y680851D01*
X813666Y680935D01*
X813416Y681060D01*
X813166Y681310D01*
X812999Y681601D01*
X812916Y681893D01*
Y682185D01*
X812999Y682476D01*
X813124Y682726D01*
X813291Y682935D01*
G01X813416Y684076D02*
X813124Y684326D01*
X812958Y684660D01*
X812916Y685035D01*
X812958Y685368D01*
X813166Y685701D01*
X813416Y685910D01*
X813666Y685951D01*
X813958Y685868D01*
X814166Y685576D01*
X814249Y685285D01*
Y684910D01*
G01Y685285D02*
X814374Y685535D01*
X814583Y685743D01*
X814833Y685826D01*
X815083Y685743D01*
X815291Y685535D01*
X815416Y685160D01*
X815374Y684785D01*
X815208Y684410D01*
G01X813291Y687176D02*
X813083Y687426D01*
X812958Y687718D01*
X812916Y688093D01*
X812999Y688468D01*
X813166Y688760D01*
X813458Y688968D01*
X813791Y689010D01*
X814124Y688926D01*
X814333Y688718D01*
X814499Y688426D01*
X814541Y688135D01*
X814499Y687843D01*
X814333Y687468D01*
X815416Y687593D01*
Y688718D01*
G01X813208Y690485D02*
X812999Y690776D01*
X812916Y691110D01*
X812999Y691443D01*
X813249Y691735D01*
X813624Y691943D01*
X813999Y692026D01*
X814458D01*
X814833Y691943D01*
X815166Y691735D01*
X815333Y691485D01*
X815416Y691193D01*
X815333Y690860D01*
X815166Y690610D01*
X814916Y690443D01*
X814583Y690360D01*
X814291Y690443D01*
X813999Y690651D01*
X813833Y690901D01*
X813791Y691193D01*
X813874Y691526D01*
X814083Y691776D01*
X814458Y692026D01*
G01X845249Y677535D02*
X845499Y677660D01*
X845791Y677743D01*
X846124D01*
X846499Y677618D01*
X846791Y677410D01*
X846999Y677160D01*
X847166Y676743D01*
X847208Y676368D01*
X847124Y675993D01*
X846999Y675743D01*
X846749Y675493D01*
X846458Y675326D01*
X846166Y675243D01*
X845874D01*
X845583Y675326D01*
X845333Y675451D01*
X845124Y675618D01*
G01X843983Y675743D02*
X843733Y675451D01*
X843399Y675285D01*
X843024Y675243D01*
X842691Y675285D01*
X842358Y675493D01*
X842149Y675743D01*
X842108Y675993D01*
X842191Y676285D01*
X842483Y676493D01*
X842774Y676576D01*
X843149D01*
G01X842774D02*
X842524Y676701D01*
X842316Y676910D01*
X842233Y677160D01*
X842316Y677410D01*
X842524Y677618D01*
X842899Y677743D01*
X843274Y677701D01*
X843649Y677535D01*
G01X840758Y676285D02*
X840466Y676576D01*
X840216Y676743D01*
X839883Y676826D01*
X839591Y676743D01*
X839383Y676576D01*
X839216Y676326D01*
X839174Y676035D01*
X839216Y675785D01*
X839383Y675535D01*
X839633Y675326D01*
X839924Y675243D01*
X840258Y675326D01*
X840549Y675576D01*
X840716Y675951D01*
X840758Y676368D01*
X840674Y676910D01*
X840549Y677201D01*
X840341Y677493D01*
X840049Y677701D01*
X839758Y677743D01*
X839466Y677660D01*
X839258Y677451D01*
G01X836866Y677743D02*
X837199Y677660D01*
X837449Y677451D01*
X837616Y677201D01*
X837741Y676868D01*
X837783Y676493D01*
X837741Y676118D01*
X837616Y675785D01*
X837449Y675535D01*
X837199Y675326D01*
X836866Y675243D01*
X836533Y675326D01*
X836283Y675535D01*
X836116Y675785D01*
X835991Y676118D01*
X835949Y676493D01*
X835991Y676868D01*
X836116Y677201D01*
X836283Y677451D01*
X836533Y677660D01*
X836866Y677743D01*
G01X863549Y677435D02*
X863799Y677560D01*
X864091Y677643D01*
X864424D01*
X864799Y677518D01*
X865091Y677310D01*
X865299Y677060D01*
X865466Y676643D01*
X865508Y676268D01*
X865424Y675893D01*
X865299Y675643D01*
X865049Y675393D01*
X864758Y675226D01*
X864466Y675143D01*
X864174D01*
X863883Y675226D01*
X863633Y675351D01*
X863424Y675518D01*
G01X862283Y675643D02*
X862033Y675351D01*
X861699Y675185D01*
X861324Y675143D01*
X860991Y675185D01*
X860658Y675393D01*
X860449Y675643D01*
X860408Y675893D01*
X860491Y676185D01*
X860783Y676393D01*
X861074Y676476D01*
X861449D01*
G01X861074D02*
X860824Y676601D01*
X860616Y676810D01*
X860533Y677060D01*
X860616Y677310D01*
X860824Y677518D01*
X861199Y677643D01*
X861574Y677601D01*
X861949Y677435D01*
G01X859058Y676185D02*
X858766Y676476D01*
X858516Y676643D01*
X858183Y676726D01*
X857891Y676643D01*
X857683Y676476D01*
X857516Y676226D01*
X857474Y675935D01*
X857516Y675685D01*
X857683Y675435D01*
X857933Y675226D01*
X858224Y675143D01*
X858558Y675226D01*
X858849Y675476D01*
X859016Y675851D01*
X859058Y676268D01*
X858974Y676810D01*
X858849Y677101D01*
X858641Y677393D01*
X858349Y677601D01*
X858058Y677643D01*
X857766Y677560D01*
X857558Y677351D01*
G01X855166Y675143D02*
Y677643D01*
X855666Y677143D01*
G01Y675143D02*
X854666D01*
G01X863549Y673435D02*
X863799Y673560D01*
X864091Y673643D01*
X864424D01*
X864799Y673518D01*
X865091Y673310D01*
X865299Y673060D01*
X865466Y672643D01*
X865508Y672268D01*
X865424Y671893D01*
X865299Y671643D01*
X865049Y671393D01*
X864758Y671226D01*
X864466Y671143D01*
X864174D01*
X863883Y671226D01*
X863633Y671351D01*
X863424Y671518D01*
G01X862283Y671643D02*
X862033Y671351D01*
X861699Y671185D01*
X861324Y671143D01*
X860991Y671185D01*
X860658Y671393D01*
X860449Y671643D01*
X860408Y671893D01*
X860491Y672185D01*
X860783Y672393D01*
X861074Y672476D01*
X861449D01*
G01X861074D02*
X860824Y672601D01*
X860616Y672810D01*
X860533Y673060D01*
X860616Y673310D01*
X860824Y673518D01*
X861199Y673643D01*
X861574Y673601D01*
X861949Y673435D01*
G01X858266Y671143D02*
X857974Y671185D01*
X857641Y671310D01*
X857433Y671518D01*
X857349Y671810D01*
X857433Y672101D01*
X857683Y672351D01*
X858058Y672476D01*
X858474D01*
X858724Y672560D01*
X858933Y672768D01*
X859016Y673060D01*
X858891Y673351D01*
X858599Y673560D01*
X858266Y673643D01*
X857933Y673560D01*
X857641Y673351D01*
X857516Y673060D01*
X857599Y672768D01*
X857808Y672560D01*
X858058Y672476D01*
X858474D01*
X858849Y672351D01*
X859099Y672101D01*
X859183Y671810D01*
X859099Y671518D01*
X858891Y671310D01*
X858558Y671185D01*
X858266Y671143D01*
G01X855958Y673226D02*
X855708Y673476D01*
X855416Y673601D01*
X855083Y673643D01*
X854666Y673560D01*
X854374Y673351D01*
X854291Y673101D01*
X854333Y672851D01*
X854499Y672643D01*
X855333Y672226D01*
X855708Y671935D01*
X855958Y671518D01*
X856041Y671143D01*
X854291D01*
G01X849749Y661635D02*
X849999Y661760D01*
X850291Y661843D01*
X850624D01*
X850999Y661718D01*
X851291Y661510D01*
X851499Y661260D01*
X851666Y660843D01*
X851708Y660468D01*
X851624Y660093D01*
X851499Y659843D01*
X851249Y659593D01*
X850958Y659426D01*
X850666Y659343D01*
X850374D01*
X850083Y659426D01*
X849833Y659551D01*
X849624Y659718D01*
G01X848483Y659843D02*
X848233Y659551D01*
X847899Y659385D01*
X847524Y659343D01*
X847191Y659385D01*
X846858Y659593D01*
X846649Y659843D01*
X846608Y660093D01*
X846691Y660385D01*
X846983Y660593D01*
X847274Y660676D01*
X847649D01*
G01X847274D02*
X847024Y660801D01*
X846816Y661010D01*
X846733Y661260D01*
X846816Y661510D01*
X847024Y661718D01*
X847399Y661843D01*
X847774Y661801D01*
X848149Y661635D01*
G01X844466Y659343D02*
X844174Y659385D01*
X843841Y659510D01*
X843633Y659718D01*
X843549Y660010D01*
X843633Y660301D01*
X843883Y660551D01*
X844258Y660676D01*
X844674D01*
X844924Y660760D01*
X845133Y660968D01*
X845216Y661260D01*
X845091Y661551D01*
X844799Y661760D01*
X844466Y661843D01*
X844133Y661760D01*
X843841Y661551D01*
X843716Y661260D01*
X843799Y660968D01*
X844008Y660760D01*
X844258Y660676D01*
X844674D01*
X845049Y660551D01*
X845299Y660301D01*
X845383Y660010D01*
X845299Y659718D01*
X845091Y659510D01*
X844758Y659385D01*
X844466Y659343D01*
G01X842283Y659843D02*
X842033Y659551D01*
X841699Y659385D01*
X841324Y659343D01*
X840991Y659385D01*
X840658Y659593D01*
X840449Y659843D01*
X840408Y660093D01*
X840491Y660385D01*
X840783Y660593D01*
X841074Y660676D01*
X841449D01*
G01X841074D02*
X840824Y660801D01*
X840616Y661010D01*
X840533Y661260D01*
X840616Y661510D01*
X840824Y661718D01*
X841199Y661843D01*
X841574Y661801D01*
X841949Y661635D01*
G01X838208Y664610D02*
X838333Y664360D01*
X838416Y664068D01*
Y663735D01*
X838291Y663360D01*
X838083Y663068D01*
X837833Y662860D01*
X837416Y662693D01*
X837041Y662651D01*
X836666Y662735D01*
X836416Y662860D01*
X836166Y663110D01*
X835999Y663401D01*
X835916Y663693D01*
Y663985D01*
X835999Y664276D01*
X836124Y664526D01*
X836291Y664735D01*
G01X836416Y665876D02*
X836124Y666126D01*
X835958Y666460D01*
X835916Y666835D01*
X835958Y667168D01*
X836166Y667501D01*
X836416Y667710D01*
X836666Y667751D01*
X836958Y667668D01*
X837166Y667376D01*
X837249Y667085D01*
Y666710D01*
G01Y667085D02*
X837374Y667335D01*
X837583Y667543D01*
X837833Y667626D01*
X838083Y667543D01*
X838291Y667335D01*
X838416Y666960D01*
X838374Y666585D01*
X838208Y666210D01*
G01X836958Y669101D02*
X837249Y669393D01*
X837416Y669643D01*
X837499Y669976D01*
X837416Y670268D01*
X837249Y670476D01*
X836999Y670643D01*
X836708Y670685D01*
X836458Y670643D01*
X836208Y670476D01*
X835999Y670226D01*
X835916Y669935D01*
X835999Y669601D01*
X836249Y669310D01*
X836624Y669143D01*
X837041Y669101D01*
X837583Y669185D01*
X837874Y669310D01*
X838166Y669518D01*
X838374Y669810D01*
X838416Y670101D01*
X838333Y670393D01*
X838124Y670601D01*
G01X835916Y673493D02*
X838416D01*
X836624Y671951D01*
Y674035D01*
G01X830749Y677235D02*
X830999Y677360D01*
X831291Y677443D01*
X831624D01*
X831999Y677318D01*
X832291Y677110D01*
X832499Y676860D01*
X832666Y676443D01*
X832708Y676068D01*
X832624Y675693D01*
X832499Y675443D01*
X832249Y675193D01*
X831958Y675026D01*
X831666Y674943D01*
X831374D01*
X831083Y675026D01*
X830833Y675151D01*
X830624Y675318D01*
G01X829483Y675443D02*
X829233Y675151D01*
X828899Y674985D01*
X828524Y674943D01*
X828191Y674985D01*
X827858Y675193D01*
X827649Y675443D01*
X827608Y675693D01*
X827691Y675985D01*
X827983Y676193D01*
X828274Y676276D01*
X828649D01*
G01X828274D02*
X828024Y676401D01*
X827816Y676610D01*
X827733Y676860D01*
X827816Y677110D01*
X828024Y677318D01*
X828399Y677443D01*
X828774Y677401D01*
X829149Y677235D01*
G01X826383Y675318D02*
X826133Y675110D01*
X825841Y674985D01*
X825466Y674943D01*
X825091Y675026D01*
X824799Y675193D01*
X824591Y675485D01*
X824549Y675818D01*
X824633Y676151D01*
X824841Y676360D01*
X825133Y676526D01*
X825424Y676568D01*
X825716Y676526D01*
X826091Y676360D01*
X825966Y677443D01*
X824841D01*
G01X822366Y674943D02*
X822074Y674985D01*
X821741Y675110D01*
X821533Y675318D01*
X821449Y675610D01*
X821533Y675901D01*
X821783Y676151D01*
X822158Y676276D01*
X822574D01*
X822824Y676360D01*
X823033Y676568D01*
X823116Y676860D01*
X822991Y677151D01*
X822699Y677360D01*
X822366Y677443D01*
X822033Y677360D01*
X821741Y677151D01*
X821616Y676860D01*
X821699Y676568D01*
X821908Y676360D01*
X822158Y676276D01*
X822574D01*
X822949Y676151D01*
X823199Y675901D01*
X823283Y675610D01*
X823199Y675318D01*
X822991Y675110D01*
X822658Y674985D01*
X822366Y674943D01*
G01X882108Y522310D02*
X882233Y522060D01*
X882316Y521768D01*
Y521435D01*
X882191Y521060D01*
X881983Y520768D01*
X881733Y520560D01*
X881316Y520393D01*
X880941Y520351D01*
X880566Y520435D01*
X880316Y520560D01*
X880066Y520810D01*
X879899Y521101D01*
X879816Y521393D01*
Y521685D01*
X879899Y521976D01*
X880024Y522226D01*
X880191Y522435D01*
G01X879816Y524993D02*
X882316D01*
X880524Y523451D01*
Y525535D01*
G01X880316Y526676D02*
X880024Y526926D01*
X879858Y527260D01*
X879816Y527635D01*
X879858Y527968D01*
X880066Y528301D01*
X880316Y528510D01*
X880566Y528551D01*
X880858Y528468D01*
X881066Y528176D01*
X881149Y527885D01*
Y527510D01*
G01Y527885D02*
X881274Y528135D01*
X881483Y528343D01*
X881733Y528426D01*
X881983Y528343D01*
X882191Y528135D01*
X882316Y527760D01*
X882274Y527385D01*
X882108Y527010D01*
G01X879816Y530610D02*
X880358Y530693D01*
X880816Y530818D01*
X881233Y530985D01*
X881691Y531193D01*
X882316Y531526D01*
Y529860D01*
G01X878108Y522310D02*
X878233Y522060D01*
X878316Y521768D01*
Y521435D01*
X878191Y521060D01*
X877983Y520768D01*
X877733Y520560D01*
X877316Y520393D01*
X876941Y520351D01*
X876566Y520435D01*
X876316Y520560D01*
X876066Y520810D01*
X875899Y521101D01*
X875816Y521393D01*
Y521685D01*
X875899Y521976D01*
X876024Y522226D01*
X876191Y522435D01*
G01X875816Y524993D02*
X878316D01*
X876524Y523451D01*
Y525535D01*
G01X875816Y528093D02*
X878316D01*
X876524Y526551D01*
Y528635D01*
G01X877899Y529901D02*
X878149Y530151D01*
X878274Y530443D01*
X878316Y530776D01*
X878233Y531193D01*
X878024Y531485D01*
X877774Y531568D01*
X877524Y531526D01*
X877316Y531360D01*
X876899Y530526D01*
X876608Y530151D01*
X876191Y529901D01*
X875816Y529818D01*
Y531568D01*
G01X890108Y522310D02*
X890233Y522060D01*
X890316Y521768D01*
Y521435D01*
X890191Y521060D01*
X889983Y520768D01*
X889733Y520560D01*
X889316Y520393D01*
X888941Y520351D01*
X888566Y520435D01*
X888316Y520560D01*
X888066Y520810D01*
X887899Y521101D01*
X887816Y521393D01*
Y521685D01*
X887899Y521976D01*
X888024Y522226D01*
X888191Y522435D01*
G01X887816Y524993D02*
X890316D01*
X888524Y523451D01*
Y525535D01*
G01X887816Y528093D02*
X890316D01*
X888524Y526551D01*
Y528635D01*
G01X888858Y529901D02*
X889149Y530193D01*
X889316Y530443D01*
X889399Y530776D01*
X889316Y531068D01*
X889149Y531276D01*
X888899Y531443D01*
X888608Y531485D01*
X888358Y531443D01*
X888108Y531276D01*
X887899Y531026D01*
X887816Y530735D01*
X887899Y530401D01*
X888149Y530110D01*
X888524Y529943D01*
X888941Y529901D01*
X889483Y529985D01*
X889774Y530110D01*
X890066Y530318D01*
X890274Y530610D01*
X890316Y530901D01*
X890233Y531193D01*
X890024Y531401D01*
G01X874108Y522310D02*
X874233Y522060D01*
X874316Y521768D01*
Y521435D01*
X874191Y521060D01*
X873983Y520768D01*
X873733Y520560D01*
X873316Y520393D01*
X872941Y520351D01*
X872566Y520435D01*
X872316Y520560D01*
X872066Y520810D01*
X871899Y521101D01*
X871816Y521393D01*
Y521685D01*
X871899Y521976D01*
X872024Y522226D01*
X872191Y522435D01*
G01X871816Y524993D02*
X874316D01*
X872524Y523451D01*
Y525535D01*
G01X872191Y526676D02*
X871983Y526926D01*
X871858Y527218D01*
X871816Y527593D01*
X871899Y527968D01*
X872066Y528260D01*
X872358Y528468D01*
X872691Y528510D01*
X873024Y528426D01*
X873233Y528218D01*
X873399Y527926D01*
X873441Y527635D01*
X873399Y527343D01*
X873233Y526968D01*
X874316Y527093D01*
Y528218D01*
G01X871816Y530693D02*
X871858Y530985D01*
X871983Y531318D01*
X872191Y531526D01*
X872483Y531610D01*
X872774Y531526D01*
X873024Y531276D01*
X873149Y530901D01*
Y530485D01*
X873233Y530235D01*
X873441Y530026D01*
X873733Y529943D01*
X874024Y530068D01*
X874233Y530360D01*
X874316Y530693D01*
X874233Y531026D01*
X874024Y531318D01*
X873733Y531443D01*
X873441Y531360D01*
X873233Y531151D01*
X873149Y530901D01*
Y530485D01*
X873024Y530110D01*
X872774Y529860D01*
X872483Y529776D01*
X872191Y529860D01*
X871983Y530068D01*
X871858Y530401D01*
X871816Y530693D01*
G01X886108Y522310D02*
X886233Y522060D01*
X886316Y521768D01*
Y521435D01*
X886191Y521060D01*
X885983Y520768D01*
X885733Y520560D01*
X885316Y520393D01*
X884941Y520351D01*
X884566Y520435D01*
X884316Y520560D01*
X884066Y520810D01*
X883899Y521101D01*
X883816Y521393D01*
Y521685D01*
X883899Y521976D01*
X884024Y522226D01*
X884191Y522435D01*
G01X883816Y524993D02*
X886316D01*
X884524Y523451D01*
Y525535D01*
G01X884191Y526676D02*
X883983Y526926D01*
X883858Y527218D01*
X883816Y527593D01*
X883899Y527968D01*
X884066Y528260D01*
X884358Y528468D01*
X884691Y528510D01*
X885024Y528426D01*
X885233Y528218D01*
X885399Y527926D01*
X885441Y527635D01*
X885399Y527343D01*
X885233Y526968D01*
X886316Y527093D01*
Y528218D01*
G01X884316Y529776D02*
X884024Y530026D01*
X883858Y530360D01*
X883816Y530735D01*
X883858Y531068D01*
X884066Y531401D01*
X884316Y531610D01*
X884566Y531651D01*
X884858Y531568D01*
X885066Y531276D01*
X885149Y530985D01*
Y530610D01*
G01Y530985D02*
X885274Y531235D01*
X885483Y531443D01*
X885733Y531526D01*
X885983Y531443D01*
X886191Y531235D01*
X886316Y530860D01*
X886274Y530485D01*
X886108Y530110D01*
G01X884849Y505935D02*
X885099Y506060D01*
X885391Y506143D01*
X885724D01*
X886099Y506018D01*
X886391Y505810D01*
X886599Y505560D01*
X886766Y505143D01*
X886808Y504768D01*
X886724Y504393D01*
X886599Y504143D01*
X886349Y503893D01*
X886058Y503726D01*
X885766Y503643D01*
X885474D01*
X885183Y503726D01*
X884933Y503851D01*
X884724Y504018D01*
G01X883583Y504143D02*
X883333Y503851D01*
X882999Y503685D01*
X882624Y503643D01*
X882291Y503685D01*
X881958Y503893D01*
X881749Y504143D01*
X881708Y504393D01*
X881791Y504685D01*
X882083Y504893D01*
X882374Y504976D01*
X882749D01*
G01X882374D02*
X882124Y505101D01*
X881916Y505310D01*
X881833Y505560D01*
X881916Y505810D01*
X882124Y506018D01*
X882499Y506143D01*
X882874Y506101D01*
X883249Y505935D01*
G01X880483Y504143D02*
X880233Y503851D01*
X879899Y503685D01*
X879524Y503643D01*
X879191Y503685D01*
X878858Y503893D01*
X878649Y504143D01*
X878608Y504393D01*
X878691Y504685D01*
X878983Y504893D01*
X879274Y504976D01*
X879649D01*
G01X879274D02*
X879024Y505101D01*
X878816Y505310D01*
X878733Y505560D01*
X878816Y505810D01*
X879024Y506018D01*
X879399Y506143D01*
X879774Y506101D01*
X880149Y505935D01*
G01X877174Y503935D02*
X876883Y503726D01*
X876549Y503643D01*
X876216Y503726D01*
X875924Y503976D01*
X875716Y504351D01*
X875633Y504726D01*
Y505185D01*
X875716Y505560D01*
X875924Y505893D01*
X876174Y506060D01*
X876466Y506143D01*
X876799Y506060D01*
X877049Y505893D01*
X877216Y505643D01*
X877299Y505310D01*
X877216Y505018D01*
X877008Y504726D01*
X876758Y504560D01*
X876466Y504518D01*
X876133Y504601D01*
X875883Y504810D01*
X875633Y505185D01*
G01X886599Y495643D02*
Y498143D01*
X885558D01*
X885224Y498018D01*
X885016Y497851D01*
X884933Y497518D01*
X885016Y497185D01*
X885266Y496976D01*
X885558Y496851D01*
X886599D01*
G01X885558D02*
X884933Y495643D01*
G01X883458Y496685D02*
X883166Y496976D01*
X882916Y497143D01*
X882583Y497226D01*
X882291Y497143D01*
X882083Y496976D01*
X881916Y496726D01*
X881874Y496435D01*
X881916Y496185D01*
X882083Y495935D01*
X882333Y495726D01*
X882624Y495643D01*
X882958Y495726D01*
X883249Y495976D01*
X883416Y496351D01*
X883458Y496768D01*
X883374Y497310D01*
X883249Y497601D01*
X883041Y497893D01*
X882749Y498101D01*
X882458Y498143D01*
X882166Y498060D01*
X881958Y497851D01*
G01X879566Y495643D02*
X879274Y495685D01*
X878941Y495810D01*
X878733Y496018D01*
X878649Y496310D01*
X878733Y496601D01*
X878983Y496851D01*
X879358Y496976D01*
X879774D01*
X880024Y497060D01*
X880233Y497268D01*
X880316Y497560D01*
X880191Y497851D01*
X879899Y498060D01*
X879566Y498143D01*
X879233Y498060D01*
X878941Y497851D01*
X878816Y497560D01*
X878899Y497268D01*
X879108Y497060D01*
X879358Y496976D01*
X879774D01*
X880149Y496851D01*
X880399Y496601D01*
X880483Y496310D01*
X880399Y496018D01*
X880191Y495810D01*
X879858Y495685D01*
X879566Y495643D01*
G01X876466D02*
Y498143D01*
X876966Y497643D01*
G01Y495643D02*
X875966D01*
G01X884849Y513935D02*
X885099Y514060D01*
X885391Y514143D01*
X885724D01*
X886099Y514018D01*
X886391Y513810D01*
X886599Y513560D01*
X886766Y513143D01*
X886808Y512768D01*
X886724Y512393D01*
X886599Y512143D01*
X886349Y511893D01*
X886058Y511726D01*
X885766Y511643D01*
X885474D01*
X885183Y511726D01*
X884933Y511851D01*
X884724Y512018D01*
G01X883583Y512143D02*
X883333Y511851D01*
X882999Y511685D01*
X882624Y511643D01*
X882291Y511685D01*
X881958Y511893D01*
X881749Y512143D01*
X881708Y512393D01*
X881791Y512685D01*
X882083Y512893D01*
X882374Y512976D01*
X882749D01*
G01X882374D02*
X882124Y513101D01*
X881916Y513310D01*
X881833Y513560D01*
X881916Y513810D01*
X882124Y514018D01*
X882499Y514143D01*
X882874Y514101D01*
X883249Y513935D01*
G01X879066Y511643D02*
Y514143D01*
X880608Y512351D01*
X878524D01*
G01X876466Y511643D02*
Y514143D01*
X876966Y513643D01*
G01Y511643D02*
X875966D01*
G01X884849Y509935D02*
X885099Y510060D01*
X885391Y510143D01*
X885724D01*
X886099Y510018D01*
X886391Y509810D01*
X886599Y509560D01*
X886766Y509143D01*
X886808Y508768D01*
X886724Y508393D01*
X886599Y508143D01*
X886349Y507893D01*
X886058Y507726D01*
X885766Y507643D01*
X885474D01*
X885183Y507726D01*
X884933Y507851D01*
X884724Y508018D01*
G01X883583Y508143D02*
X883333Y507851D01*
X882999Y507685D01*
X882624Y507643D01*
X882291Y507685D01*
X881958Y507893D01*
X881749Y508143D01*
X881708Y508393D01*
X881791Y508685D01*
X882083Y508893D01*
X882374Y508976D01*
X882749D01*
G01X882374D02*
X882124Y509101D01*
X881916Y509310D01*
X881833Y509560D01*
X881916Y509810D01*
X882124Y510018D01*
X882499Y510143D01*
X882874Y510101D01*
X883249Y509935D01*
G01X880483Y508143D02*
X880233Y507851D01*
X879899Y507685D01*
X879524Y507643D01*
X879191Y507685D01*
X878858Y507893D01*
X878649Y508143D01*
X878608Y508393D01*
X878691Y508685D01*
X878983Y508893D01*
X879274Y508976D01*
X879649D01*
G01X879274D02*
X879024Y509101D01*
X878816Y509310D01*
X878733Y509560D01*
X878816Y509810D01*
X879024Y510018D01*
X879399Y510143D01*
X879774Y510101D01*
X880149Y509935D01*
G01X876466Y507643D02*
X876174Y507685D01*
X875841Y507810D01*
X875633Y508018D01*
X875549Y508310D01*
X875633Y508601D01*
X875883Y508851D01*
X876258Y508976D01*
X876674D01*
X876924Y509060D01*
X877133Y509268D01*
X877216Y509560D01*
X877091Y509851D01*
X876799Y510060D01*
X876466Y510143D01*
X876133Y510060D01*
X875841Y509851D01*
X875716Y509560D01*
X875799Y509268D01*
X876008Y509060D01*
X876258Y508976D01*
X876674D01*
X877049Y508851D01*
X877299Y508601D01*
X877383Y508310D01*
X877299Y508018D01*
X877091Y507810D01*
X876758Y507685D01*
X876466Y507643D01*
G01X886599Y502143D02*
Y499643D01*
X884933D01*
G01X882666D02*
Y502143D01*
X883166Y501643D01*
G01Y499643D02*
X882166D01*
G01X880483Y500018D02*
X880233Y499810D01*
X879941Y499685D01*
X879566Y499643D01*
X879191Y499726D01*
X878899Y499893D01*
X878691Y500185D01*
X878649Y500518D01*
X878733Y500851D01*
X878941Y501060D01*
X879233Y501226D01*
X879524Y501268D01*
X879816Y501226D01*
X880191Y501060D01*
X880066Y502143D01*
X878941D01*
G01X884849Y517935D02*
X885099Y518060D01*
X885391Y518143D01*
X885724D01*
X886099Y518018D01*
X886391Y517810D01*
X886599Y517560D01*
X886766Y517143D01*
X886808Y516768D01*
X886724Y516393D01*
X886599Y516143D01*
X886349Y515893D01*
X886058Y515726D01*
X885766Y515643D01*
X885474D01*
X885183Y515726D01*
X884933Y515851D01*
X884724Y516018D01*
G01X883583Y516143D02*
X883333Y515851D01*
X882999Y515685D01*
X882624Y515643D01*
X882291Y515685D01*
X881958Y515893D01*
X881749Y516143D01*
X881708Y516393D01*
X881791Y516685D01*
X882083Y516893D01*
X882374Y516976D01*
X882749D01*
G01X882374D02*
X882124Y517101D01*
X881916Y517310D01*
X881833Y517560D01*
X881916Y517810D01*
X882124Y518018D01*
X882499Y518143D01*
X882874Y518101D01*
X883249Y517935D01*
G01X879066Y515643D02*
Y518143D01*
X880608Y516351D01*
X878524D01*
G01X876466Y518143D02*
X876799Y518060D01*
X877049Y517851D01*
X877216Y517601D01*
X877341Y517268D01*
X877383Y516893D01*
X877341Y516518D01*
X877216Y516185D01*
X877049Y515935D01*
X876799Y515726D01*
X876466Y515643D01*
X876133Y515726D01*
X875883Y515935D01*
X875716Y516185D01*
X875591Y516518D01*
X875549Y516893D01*
X875591Y517268D01*
X875716Y517601D01*
X875883Y517851D01*
X876133Y518060D01*
X876466Y518143D01*
G01X880499Y576943D02*
Y579443D01*
X879458D01*
X879124Y579318D01*
X878916Y579151D01*
X878833Y578818D01*
X878916Y578485D01*
X879166Y578276D01*
X879458Y578151D01*
X880499D01*
G01X879458D02*
X878833Y576943D01*
G01X877483Y577318D02*
X877233Y577110D01*
X876941Y576985D01*
X876566Y576943D01*
X876191Y577026D01*
X875899Y577193D01*
X875691Y577485D01*
X875649Y577818D01*
X875733Y578151D01*
X875941Y578360D01*
X876233Y578526D01*
X876524Y578568D01*
X876816Y578526D01*
X877191Y578360D01*
X877066Y579443D01*
X875941D01*
G01X874174Y577235D02*
X873883Y577026D01*
X873549Y576943D01*
X873216Y577026D01*
X872924Y577276D01*
X872716Y577651D01*
X872633Y578026D01*
Y578485D01*
X872716Y578860D01*
X872924Y579193D01*
X873174Y579360D01*
X873466Y579443D01*
X873799Y579360D01*
X874049Y579193D01*
X874216Y578943D01*
X874299Y578610D01*
X874216Y578318D01*
X874008Y578026D01*
X873758Y577860D01*
X873466Y577818D01*
X873133Y577901D01*
X872883Y578110D01*
X872633Y578485D01*
G01X870366Y576943D02*
X870074Y576985D01*
X869741Y577110D01*
X869533Y577318D01*
X869449Y577610D01*
X869533Y577901D01*
X869783Y578151D01*
X870158Y578276D01*
X870574D01*
X870824Y578360D01*
X871033Y578568D01*
X871116Y578860D01*
X870991Y579151D01*
X870699Y579360D01*
X870366Y579443D01*
X870033Y579360D01*
X869741Y579151D01*
X869616Y578860D01*
X869699Y578568D01*
X869908Y578360D01*
X870158Y578276D01*
X870574D01*
X870949Y578151D01*
X871199Y577901D01*
X871283Y577610D01*
X871199Y577318D01*
X870991Y577110D01*
X870658Y576985D01*
X870366Y576943D01*
G01X899216Y552860D02*
X901716D01*
Y553901D01*
X901591Y554235D01*
X901424Y554443D01*
X901091Y554526D01*
X900758Y554443D01*
X900549Y554193D01*
X900424Y553901D01*
Y552860D01*
G01Y553901D02*
X899216Y554526D01*
G01X900258Y556001D02*
X900549Y556293D01*
X900716Y556543D01*
X900799Y556876D01*
X900716Y557168D01*
X900549Y557376D01*
X900299Y557543D01*
X900008Y557585D01*
X899758Y557543D01*
X899508Y557376D01*
X899299Y557126D01*
X899216Y556835D01*
X899299Y556501D01*
X899549Y556210D01*
X899924Y556043D01*
X900341Y556001D01*
X900883Y556085D01*
X901174Y556210D01*
X901466Y556418D01*
X901674Y556710D01*
X901716Y557001D01*
X901633Y557293D01*
X901424Y557501D01*
G01X899716Y558976D02*
X899424Y559226D01*
X899258Y559560D01*
X899216Y559935D01*
X899258Y560268D01*
X899466Y560601D01*
X899716Y560810D01*
X899966Y560851D01*
X900258Y560768D01*
X900466Y560476D01*
X900549Y560185D01*
Y559810D01*
G01Y560185D02*
X900674Y560435D01*
X900883Y560643D01*
X901133Y560726D01*
X901383Y560643D01*
X901591Y560435D01*
X901716Y560060D01*
X901674Y559685D01*
X901508Y559310D01*
G01X901716Y562993D02*
X901633Y562660D01*
X901424Y562410D01*
X901174Y562243D01*
X900841Y562118D01*
X900466Y562076D01*
X900091Y562118D01*
X899758Y562243D01*
X899508Y562410D01*
X899299Y562660D01*
X899216Y562993D01*
X899299Y563326D01*
X899508Y563576D01*
X899758Y563743D01*
X900091Y563868D01*
X900466Y563910D01*
X900841Y563868D01*
X901174Y563743D01*
X901424Y563576D01*
X901633Y563326D01*
X901716Y562993D01*
G01X896949Y556443D02*
Y558943D01*
X895908D01*
X895574Y558818D01*
X895366Y558651D01*
X895283Y558318D01*
X895366Y557985D01*
X895616Y557776D01*
X895908Y557651D01*
X896949D01*
G01X895908D02*
X895283Y556443D01*
G01X893933Y556818D02*
X893683Y556610D01*
X893391Y556485D01*
X893016Y556443D01*
X892641Y556526D01*
X892349Y556693D01*
X892141Y556985D01*
X892099Y557318D01*
X892183Y557651D01*
X892391Y557860D01*
X892683Y558026D01*
X892974Y558068D01*
X893266Y558026D01*
X893641Y557860D01*
X893516Y558943D01*
X892391D01*
G01X889916Y556443D02*
X889624Y556485D01*
X889291Y556610D01*
X889083Y556818D01*
X888999Y557110D01*
X889083Y557401D01*
X889333Y557651D01*
X889708Y557776D01*
X890124D01*
X890374Y557860D01*
X890583Y558068D01*
X890666Y558360D01*
X890541Y558651D01*
X890249Y558860D01*
X889916Y558943D01*
X889583Y558860D01*
X889291Y558651D01*
X889166Y558360D01*
X889249Y558068D01*
X889458Y557860D01*
X889708Y557776D01*
X890124D01*
X890499Y557651D01*
X890749Y557401D01*
X890833Y557110D01*
X890749Y556818D01*
X890541Y556610D01*
X890208Y556485D01*
X889916Y556443D01*
G01X886816D02*
X886524Y556485D01*
X886191Y556610D01*
X885983Y556818D01*
X885899Y557110D01*
X885983Y557401D01*
X886233Y557651D01*
X886608Y557776D01*
X887024D01*
X887274Y557860D01*
X887483Y558068D01*
X887566Y558360D01*
X887441Y558651D01*
X887149Y558860D01*
X886816Y558943D01*
X886483Y558860D01*
X886191Y558651D01*
X886066Y558360D01*
X886149Y558068D01*
X886358Y557860D01*
X886608Y557776D01*
X887024D01*
X887399Y557651D01*
X887649Y557401D01*
X887733Y557110D01*
X887649Y556818D01*
X887441Y556610D01*
X887108Y556485D01*
X886816Y556443D01*
G01X896949Y564443D02*
Y566943D01*
X895908D01*
X895574Y566818D01*
X895366Y566651D01*
X895283Y566318D01*
X895366Y565985D01*
X895616Y565776D01*
X895908Y565651D01*
X896949D01*
G01X895908D02*
X895283Y564443D01*
G01X893933Y564818D02*
X893683Y564610D01*
X893391Y564485D01*
X893016Y564443D01*
X892641Y564526D01*
X892349Y564693D01*
X892141Y564985D01*
X892099Y565318D01*
X892183Y565651D01*
X892391Y565860D01*
X892683Y566026D01*
X892974Y566068D01*
X893266Y566026D01*
X893641Y565860D01*
X893516Y566943D01*
X892391D01*
G01X889916Y564443D02*
X889624Y564485D01*
X889291Y564610D01*
X889083Y564818D01*
X888999Y565110D01*
X889083Y565401D01*
X889333Y565651D01*
X889708Y565776D01*
X890124D01*
X890374Y565860D01*
X890583Y566068D01*
X890666Y566360D01*
X890541Y566651D01*
X890249Y566860D01*
X889916Y566943D01*
X889583Y566860D01*
X889291Y566651D01*
X889166Y566360D01*
X889249Y566068D01*
X889458Y565860D01*
X889708Y565776D01*
X890124D01*
X890499Y565651D01*
X890749Y565401D01*
X890833Y565110D01*
X890749Y564818D01*
X890541Y564610D01*
X890208Y564485D01*
X889916Y564443D01*
G01X887524Y564735D02*
X887233Y564526D01*
X886899Y564443D01*
X886566Y564526D01*
X886274Y564776D01*
X886066Y565151D01*
X885983Y565526D01*
Y565985D01*
X886066Y566360D01*
X886274Y566693D01*
X886524Y566860D01*
X886816Y566943D01*
X887149Y566860D01*
X887399Y566693D01*
X887566Y566443D01*
X887649Y566110D01*
X887566Y565818D01*
X887358Y565526D01*
X887108Y565360D01*
X886816Y565318D01*
X886483Y565401D01*
X886233Y565610D01*
X885983Y565985D01*
G01X871416Y533810D02*
X873916D01*
Y534851D01*
X873791Y535185D01*
X873624Y535393D01*
X873291Y535476D01*
X872958Y535393D01*
X872749Y535143D01*
X872624Y534851D01*
Y533810D01*
G01Y534851D02*
X871416Y535476D01*
G01X871791Y536826D02*
X871583Y537076D01*
X871458Y537368D01*
X871416Y537743D01*
X871499Y538118D01*
X871666Y538410D01*
X871958Y538618D01*
X872291Y538660D01*
X872624Y538576D01*
X872833Y538368D01*
X872999Y538076D01*
X873041Y537785D01*
X872999Y537493D01*
X872833Y537118D01*
X873916Y537243D01*
Y538368D01*
G01X871708Y540135D02*
X871499Y540426D01*
X871416Y540760D01*
X871499Y541093D01*
X871749Y541385D01*
X872124Y541593D01*
X872499Y541676D01*
X872958D01*
X873333Y541593D01*
X873666Y541385D01*
X873833Y541135D01*
X873916Y540843D01*
X873833Y540510D01*
X873666Y540260D01*
X873416Y540093D01*
X873083Y540010D01*
X872791Y540093D01*
X872499Y540301D01*
X872333Y540551D01*
X872291Y540843D01*
X872374Y541176D01*
X872583Y541426D01*
X872958Y541676D01*
G01X873916Y543943D02*
X873833Y543610D01*
X873624Y543360D01*
X873374Y543193D01*
X873041Y543068D01*
X872666Y543026D01*
X872291Y543068D01*
X871958Y543193D01*
X871708Y543360D01*
X871499Y543610D01*
X871416Y543943D01*
X871499Y544276D01*
X871708Y544526D01*
X871958Y544693D01*
X872291Y544818D01*
X872666Y544860D01*
X873041Y544818D01*
X873374Y544693D01*
X873624Y544526D01*
X873833Y544276D01*
X873916Y543943D01*
G01X867416Y533810D02*
X869916D01*
Y534851D01*
X869791Y535185D01*
X869624Y535393D01*
X869291Y535476D01*
X868958Y535393D01*
X868749Y535143D01*
X868624Y534851D01*
Y533810D01*
G01Y534851D02*
X867416Y535476D01*
G01X867791Y536826D02*
X867583Y537076D01*
X867458Y537368D01*
X867416Y537743D01*
X867499Y538118D01*
X867666Y538410D01*
X867958Y538618D01*
X868291Y538660D01*
X868624Y538576D01*
X868833Y538368D01*
X868999Y538076D01*
X869041Y537785D01*
X868999Y537493D01*
X868833Y537118D01*
X869916Y537243D01*
Y538368D01*
G01X867708Y540135D02*
X867499Y540426D01*
X867416Y540760D01*
X867499Y541093D01*
X867749Y541385D01*
X868124Y541593D01*
X868499Y541676D01*
X868958D01*
X869333Y541593D01*
X869666Y541385D01*
X869833Y541135D01*
X869916Y540843D01*
X869833Y540510D01*
X869666Y540260D01*
X869416Y540093D01*
X869083Y540010D01*
X868791Y540093D01*
X868499Y540301D01*
X868333Y540551D01*
X868291Y540843D01*
X868374Y541176D01*
X868583Y541426D01*
X868958Y541676D01*
G01X867416Y543943D02*
X869916D01*
X869416Y543443D01*
G01X867416D02*
Y544443D01*
G01X883416Y533810D02*
X885916D01*
Y534851D01*
X885791Y535185D01*
X885624Y535393D01*
X885291Y535476D01*
X884958Y535393D01*
X884749Y535143D01*
X884624Y534851D01*
Y533810D01*
G01Y534851D02*
X883416Y535476D01*
G01X883791Y536826D02*
X883583Y537076D01*
X883458Y537368D01*
X883416Y537743D01*
X883499Y538118D01*
X883666Y538410D01*
X883958Y538618D01*
X884291Y538660D01*
X884624Y538576D01*
X884833Y538368D01*
X884999Y538076D01*
X885041Y537785D01*
X884999Y537493D01*
X884833Y537118D01*
X885916Y537243D01*
Y538368D01*
G01X883708Y540135D02*
X883499Y540426D01*
X883416Y540760D01*
X883499Y541093D01*
X883749Y541385D01*
X884124Y541593D01*
X884499Y541676D01*
X884958D01*
X885333Y541593D01*
X885666Y541385D01*
X885833Y541135D01*
X885916Y540843D01*
X885833Y540510D01*
X885666Y540260D01*
X885416Y540093D01*
X885083Y540010D01*
X884791Y540093D01*
X884499Y540301D01*
X884333Y540551D01*
X884291Y540843D01*
X884374Y541176D01*
X884583Y541426D01*
X884958Y541676D01*
G01X885499Y543151D02*
X885749Y543401D01*
X885874Y543693D01*
X885916Y544026D01*
X885833Y544443D01*
X885624Y544735D01*
X885374Y544818D01*
X885124Y544776D01*
X884916Y544610D01*
X884499Y543776D01*
X884208Y543401D01*
X883791Y543151D01*
X883416Y543068D01*
Y544818D01*
G01X879416Y533810D02*
X881916D01*
Y534851D01*
X881791Y535185D01*
X881624Y535393D01*
X881291Y535476D01*
X880958Y535393D01*
X880749Y535143D01*
X880624Y534851D01*
Y533810D01*
G01Y534851D02*
X879416Y535476D01*
G01X879791Y536826D02*
X879583Y537076D01*
X879458Y537368D01*
X879416Y537743D01*
X879499Y538118D01*
X879666Y538410D01*
X879958Y538618D01*
X880291Y538660D01*
X880624Y538576D01*
X880833Y538368D01*
X880999Y538076D01*
X881041Y537785D01*
X880999Y537493D01*
X880833Y537118D01*
X881916Y537243D01*
Y538368D01*
G01X879708Y540135D02*
X879499Y540426D01*
X879416Y540760D01*
X879499Y541093D01*
X879749Y541385D01*
X880124Y541593D01*
X880499Y541676D01*
X880958D01*
X881333Y541593D01*
X881666Y541385D01*
X881833Y541135D01*
X881916Y540843D01*
X881833Y540510D01*
X881666Y540260D01*
X881416Y540093D01*
X881083Y540010D01*
X880791Y540093D01*
X880499Y540301D01*
X880333Y540551D01*
X880291Y540843D01*
X880374Y541176D01*
X880583Y541426D01*
X880958Y541676D01*
G01X879916Y543026D02*
X879624Y543276D01*
X879458Y543610D01*
X879416Y543985D01*
X879458Y544318D01*
X879666Y544651D01*
X879916Y544860D01*
X880166Y544901D01*
X880458Y544818D01*
X880666Y544526D01*
X880749Y544235D01*
Y543860D01*
G01Y544235D02*
X880874Y544485D01*
X881083Y544693D01*
X881333Y544776D01*
X881583Y544693D01*
X881791Y544485D01*
X881916Y544110D01*
X881874Y543735D01*
X881708Y543360D01*
G01X896949Y552443D02*
Y554943D01*
X895908D01*
X895574Y554818D01*
X895366Y554651D01*
X895283Y554318D01*
X895366Y553985D01*
X895616Y553776D01*
X895908Y553651D01*
X896949D01*
G01X895908D02*
X895283Y552443D01*
G01X893933Y552818D02*
X893683Y552610D01*
X893391Y552485D01*
X893016Y552443D01*
X892641Y552526D01*
X892349Y552693D01*
X892141Y552985D01*
X892099Y553318D01*
X892183Y553651D01*
X892391Y553860D01*
X892683Y554026D01*
X892974Y554068D01*
X893266Y554026D01*
X893641Y553860D01*
X893516Y554943D01*
X892391D01*
G01X890624Y552735D02*
X890333Y552526D01*
X889999Y552443D01*
X889666Y552526D01*
X889374Y552776D01*
X889166Y553151D01*
X889083Y553526D01*
Y553985D01*
X889166Y554360D01*
X889374Y554693D01*
X889624Y554860D01*
X889916Y554943D01*
X890249Y554860D01*
X890499Y554693D01*
X890666Y554443D01*
X890749Y554110D01*
X890666Y553818D01*
X890458Y553526D01*
X890208Y553360D01*
X889916Y553318D01*
X889583Y553401D01*
X889333Y553610D01*
X889083Y553985D01*
G01X886316Y552443D02*
Y554943D01*
X887858Y553151D01*
X885774D01*
G01X875416Y533810D02*
X877916D01*
Y534851D01*
X877791Y535185D01*
X877624Y535393D01*
X877291Y535476D01*
X876958Y535393D01*
X876749Y535143D01*
X876624Y534851D01*
Y533810D01*
G01Y534851D02*
X875416Y535476D01*
G01X875791Y536826D02*
X875583Y537076D01*
X875458Y537368D01*
X875416Y537743D01*
X875499Y538118D01*
X875666Y538410D01*
X875958Y538618D01*
X876291Y538660D01*
X876624Y538576D01*
X876833Y538368D01*
X876999Y538076D01*
X877041Y537785D01*
X876999Y537493D01*
X876833Y537118D01*
X877916Y537243D01*
Y538368D01*
G01X875708Y540135D02*
X875499Y540426D01*
X875416Y540760D01*
X875499Y541093D01*
X875749Y541385D01*
X876124Y541593D01*
X876499Y541676D01*
X876958D01*
X877333Y541593D01*
X877666Y541385D01*
X877833Y541135D01*
X877916Y540843D01*
X877833Y540510D01*
X877666Y540260D01*
X877416Y540093D01*
X877083Y540010D01*
X876791Y540093D01*
X876499Y540301D01*
X876333Y540551D01*
X876291Y540843D01*
X876374Y541176D01*
X876583Y541426D01*
X876958Y541676D01*
G01X875791Y543026D02*
X875583Y543276D01*
X875458Y543568D01*
X875416Y543943D01*
X875499Y544318D01*
X875666Y544610D01*
X875958Y544818D01*
X876291Y544860D01*
X876624Y544776D01*
X876833Y544568D01*
X876999Y544276D01*
X877041Y543985D01*
X876999Y543693D01*
X876833Y543318D01*
X877916Y543443D01*
Y544568D01*
G01X896949Y560443D02*
Y562943D01*
X895908D01*
X895574Y562818D01*
X895366Y562651D01*
X895283Y562318D01*
X895366Y561985D01*
X895616Y561776D01*
X895908Y561651D01*
X896949D01*
G01X895908D02*
X895283Y560443D01*
G01X893808Y561485D02*
X893516Y561776D01*
X893266Y561943D01*
X892933Y562026D01*
X892641Y561943D01*
X892433Y561776D01*
X892266Y561526D01*
X892224Y561235D01*
X892266Y560985D01*
X892433Y560735D01*
X892683Y560526D01*
X892974Y560443D01*
X893308Y560526D01*
X893599Y560776D01*
X893766Y561151D01*
X893808Y561568D01*
X893724Y562110D01*
X893599Y562401D01*
X893391Y562693D01*
X893099Y562901D01*
X892808Y562943D01*
X892516Y562860D01*
X892308Y562651D01*
G01X890833Y560943D02*
X890583Y560651D01*
X890249Y560485D01*
X889874Y560443D01*
X889541Y560485D01*
X889208Y560693D01*
X888999Y560943D01*
X888958Y561193D01*
X889041Y561485D01*
X889333Y561693D01*
X889624Y561776D01*
X889999D01*
G01X889624D02*
X889374Y561901D01*
X889166Y562110D01*
X889083Y562360D01*
X889166Y562610D01*
X889374Y562818D01*
X889749Y562943D01*
X890124Y562901D01*
X890499Y562735D01*
G01X886899Y560443D02*
X886816Y560985D01*
X886691Y561443D01*
X886524Y561860D01*
X886316Y562318D01*
X885983Y562943D01*
X887649D01*
G01X880499Y580943D02*
Y583443D01*
X879458D01*
X879124Y583318D01*
X878916Y583151D01*
X878833Y582818D01*
X878916Y582485D01*
X879166Y582276D01*
X879458Y582151D01*
X880499D01*
G01X879458D02*
X878833Y580943D01*
G01X877358Y581985D02*
X877066Y582276D01*
X876816Y582443D01*
X876483Y582526D01*
X876191Y582443D01*
X875983Y582276D01*
X875816Y582026D01*
X875774Y581735D01*
X875816Y581485D01*
X875983Y581235D01*
X876233Y581026D01*
X876524Y580943D01*
X876858Y581026D01*
X877149Y581276D01*
X877316Y581651D01*
X877358Y582068D01*
X877274Y582610D01*
X877149Y582901D01*
X876941Y583193D01*
X876649Y583401D01*
X876358Y583443D01*
X876066Y583360D01*
X875858Y583151D01*
G01X874258Y583026D02*
X874008Y583276D01*
X873716Y583401D01*
X873383Y583443D01*
X872966Y583360D01*
X872674Y583151D01*
X872591Y582901D01*
X872633Y582651D01*
X872799Y582443D01*
X873633Y582026D01*
X874008Y581735D01*
X874258Y581318D01*
X874341Y580943D01*
X872591D01*
G01X871283Y581318D02*
X871033Y581110D01*
X870741Y580985D01*
X870366Y580943D01*
X869991Y581026D01*
X869699Y581193D01*
X869491Y581485D01*
X869449Y581818D01*
X869533Y582151D01*
X869741Y582360D01*
X870033Y582526D01*
X870324Y582568D01*
X870616Y582526D01*
X870991Y582360D01*
X870866Y583443D01*
X869741D01*
G01X879666Y571443D02*
Y568943D01*
G01X880624Y571443D02*
X878708D01*
G01X877399Y568943D02*
Y571443D01*
X876399D01*
X876066Y571318D01*
X875816Y571026D01*
X875733Y570693D01*
X875816Y570360D01*
X876024Y570110D01*
X876399Y569985D01*
X877399D01*
G01X873466Y568943D02*
Y571443D01*
X873966Y570943D01*
G01Y568943D02*
X872966D01*
G01X870366D02*
Y571443D01*
X870866Y570943D01*
G01Y568943D02*
X869866D01*
G01X867266D02*
Y571443D01*
X867766Y570943D01*
G01Y568943D02*
X866766D01*
G01X896116Y570943D02*
Y568443D01*
G01X897074Y570943D02*
X895158D01*
G01X893849Y568443D02*
Y570943D01*
X892849D01*
X892516Y570818D01*
X892266Y570526D01*
X892183Y570193D01*
X892266Y569860D01*
X892474Y569610D01*
X892849Y569485D01*
X893849D01*
G01X889916Y568443D02*
Y570943D01*
X890416Y570443D01*
G01Y568443D02*
X889416D01*
G01X886816D02*
Y570943D01*
X887316Y570443D01*
G01Y568443D02*
X886316D01*
G01X884633Y568943D02*
X884383Y568651D01*
X884049Y568485D01*
X883674Y568443D01*
X883341Y568485D01*
X883008Y568693D01*
X882799Y568943D01*
X882758Y569193D01*
X882841Y569485D01*
X883133Y569693D01*
X883424Y569776D01*
X883799D01*
G01X883424D02*
X883174Y569901D01*
X882966Y570110D01*
X882883Y570360D01*
X882966Y570610D01*
X883174Y570818D01*
X883549Y570943D01*
X883924Y570901D01*
X884299Y570735D01*
G01X869916Y553193D02*
X867416D01*
G01X869916Y552235D02*
Y554151D01*
G01X867416Y555460D02*
X869916D01*
Y556460D01*
X869791Y556793D01*
X869499Y557043D01*
X869166Y557126D01*
X868833Y557043D01*
X868583Y556835D01*
X868458Y556460D01*
Y555460D01*
G01X867416Y559393D02*
X869916D01*
X869416Y558893D01*
G01X867416D02*
Y559893D01*
G01Y562493D02*
X869916D01*
X869416Y561993D01*
G01X867416D02*
Y562993D01*
G01X867791Y564676D02*
X867583Y564926D01*
X867458Y565218D01*
X867416Y565593D01*
X867499Y565968D01*
X867666Y566260D01*
X867958Y566468D01*
X868291Y566510D01*
X868624Y566426D01*
X868833Y566218D01*
X868999Y565926D01*
X869041Y565635D01*
X868999Y565343D01*
X868833Y564968D01*
X869916Y565093D01*
Y566218D01*
G01X889916Y534643D02*
X887416D01*
G01X889916Y533685D02*
Y535601D01*
G01X887416Y536910D02*
X889916D01*
Y537910D01*
X889791Y538243D01*
X889499Y538493D01*
X889166Y538576D01*
X888833Y538493D01*
X888583Y538285D01*
X888458Y537910D01*
Y536910D01*
G01X887416Y540843D02*
X889916D01*
X889416Y540343D01*
G01X887416D02*
Y541343D01*
G01X889499Y543151D02*
X889749Y543401D01*
X889874Y543693D01*
X889916Y544026D01*
X889833Y544443D01*
X889624Y544735D01*
X889374Y544818D01*
X889124Y544776D01*
X888916Y544610D01*
X888499Y543776D01*
X888208Y543401D01*
X887791Y543151D01*
X887416Y543068D01*
Y544818D01*
G01X889916Y547043D02*
X889833Y546710D01*
X889624Y546460D01*
X889374Y546293D01*
X889041Y546168D01*
X888666Y546126D01*
X888291Y546168D01*
X887958Y546293D01*
X887708Y546460D01*
X887499Y546710D01*
X887416Y547043D01*
X887499Y547376D01*
X887708Y547626D01*
X887958Y547793D01*
X888291Y547918D01*
X888666Y547960D01*
X889041Y547918D01*
X889374Y547793D01*
X889624Y547626D01*
X889833Y547376D01*
X889916Y547043D01*
G01X877916Y553193D02*
X875416D01*
G01X877916Y552235D02*
Y554151D01*
G01X875416Y555460D02*
X877916D01*
Y556460D01*
X877791Y556793D01*
X877499Y557043D01*
X877166Y557126D01*
X876833Y557043D01*
X876583Y556835D01*
X876458Y556460D01*
Y555460D01*
G01X875416Y559393D02*
X877916D01*
X877416Y558893D01*
G01X875416D02*
Y559893D01*
G01X877499Y561701D02*
X877749Y561951D01*
X877874Y562243D01*
X877916Y562576D01*
X877833Y562993D01*
X877624Y563285D01*
X877374Y563368D01*
X877124Y563326D01*
X876916Y563160D01*
X876499Y562326D01*
X876208Y561951D01*
X875791Y561701D01*
X875416Y561618D01*
Y563368D01*
G01X877499Y564801D02*
X877749Y565051D01*
X877874Y565343D01*
X877916Y565676D01*
X877833Y566093D01*
X877624Y566385D01*
X877374Y566468D01*
X877124Y566426D01*
X876916Y566260D01*
X876499Y565426D01*
X876208Y565051D01*
X875791Y564801D01*
X875416Y564718D01*
Y566468D01*
G01X881916Y553193D02*
X879416D01*
G01X881916Y552235D02*
Y554151D01*
G01X879416Y555460D02*
X881916D01*
Y556460D01*
X881791Y556793D01*
X881499Y557043D01*
X881166Y557126D01*
X880833Y557043D01*
X880583Y556835D01*
X880458Y556460D01*
Y555460D01*
G01X879416Y559393D02*
X881916D01*
X881416Y558893D01*
G01X879416D02*
Y559893D01*
G01X881499Y561701D02*
X881749Y561951D01*
X881874Y562243D01*
X881916Y562576D01*
X881833Y562993D01*
X881624Y563285D01*
X881374Y563368D01*
X881124Y563326D01*
X880916Y563160D01*
X880499Y562326D01*
X880208Y561951D01*
X879791Y561701D01*
X879416Y561618D01*
Y563368D01*
G01Y566093D02*
X881916D01*
X880124Y564551D01*
Y566635D01*
G01X873916Y553193D02*
X871416D01*
G01X873916Y552235D02*
Y554151D01*
G01X871416Y555460D02*
X873916D01*
Y556460D01*
X873791Y556793D01*
X873499Y557043D01*
X873166Y557126D01*
X872833Y557043D01*
X872583Y556835D01*
X872458Y556460D01*
Y555460D01*
G01X871416Y559393D02*
X873916D01*
X873416Y558893D01*
G01X871416D02*
Y559893D01*
G01X873499Y561701D02*
X873749Y561951D01*
X873874Y562243D01*
X873916Y562576D01*
X873833Y562993D01*
X873624Y563285D01*
X873374Y563368D01*
X873124Y563326D01*
X872916Y563160D01*
X872499Y562326D01*
X872208Y561951D01*
X871791Y561701D01*
X871416Y561618D01*
Y563368D01*
G01X872458Y564801D02*
X872749Y565093D01*
X872916Y565343D01*
X872999Y565676D01*
X872916Y565968D01*
X872749Y566176D01*
X872499Y566343D01*
X872208Y566385D01*
X871958Y566343D01*
X871708Y566176D01*
X871499Y565926D01*
X871416Y565635D01*
X871499Y565301D01*
X871749Y565010D01*
X872124Y564843D01*
X872541Y564801D01*
X873083Y564885D01*
X873374Y565010D01*
X873666Y565218D01*
X873874Y565510D01*
X873916Y565801D01*
X873833Y566093D01*
X873624Y566301D01*
G01X879666Y575443D02*
Y572943D01*
G01X880624Y575443D02*
X878708D01*
G01X877399Y572943D02*
Y575443D01*
X876399D01*
X876066Y575318D01*
X875816Y575026D01*
X875733Y574693D01*
X875816Y574360D01*
X876024Y574110D01*
X876399Y573985D01*
X877399D01*
G01X873466Y572943D02*
Y575443D01*
X873966Y574943D01*
G01Y572943D02*
X872966D01*
G01X871158Y575026D02*
X870908Y575276D01*
X870616Y575401D01*
X870283Y575443D01*
X869866Y575360D01*
X869574Y575151D01*
X869491Y574901D01*
X869533Y574651D01*
X869699Y574443D01*
X870533Y574026D01*
X870908Y573735D01*
X871158Y573318D01*
X871241Y572943D01*
X869491D01*
G01X867974Y573235D02*
X867683Y573026D01*
X867349Y572943D01*
X867016Y573026D01*
X866724Y573276D01*
X866516Y573651D01*
X866433Y574026D01*
Y574485D01*
X866516Y574860D01*
X866724Y575193D01*
X866974Y575360D01*
X867266Y575443D01*
X867599Y575360D01*
X867849Y575193D01*
X868016Y574943D01*
X868099Y574610D01*
X868016Y574318D01*
X867808Y574026D01*
X867558Y573860D01*
X867266Y573818D01*
X866933Y573901D01*
X866683Y574110D01*
X866433Y574485D01*
G01X894483Y534243D02*
X891983D01*
G01X894483Y533285D02*
Y535201D01*
G01X891983Y536510D02*
X894483D01*
Y537510D01*
X894358Y537843D01*
X894066Y538093D01*
X893733Y538176D01*
X893400Y538093D01*
X893150Y537885D01*
X893025Y537510D01*
Y536510D01*
G01X891983Y540443D02*
X894483D01*
X893983Y539943D01*
G01X891983D02*
Y540943D01*
G01Y544043D02*
X894483D01*
X892691Y542501D01*
Y544585D01*
G01X894066Y545851D02*
X894316Y546101D01*
X894441Y546393D01*
X894483Y546726D01*
X894400Y547143D01*
X894191Y547435D01*
X893941Y547518D01*
X893691Y547476D01*
X893483Y547310D01*
X893066Y546476D01*
X892775Y546101D01*
X892358Y545851D01*
X891983Y545768D01*
Y547518D01*
G01X881816Y593743D02*
Y591243D01*
G01X882774Y593743D02*
X880858D01*
G01X879549Y591243D02*
Y593743D01*
X878549D01*
X878216Y593618D01*
X877966Y593326D01*
X877883Y592993D01*
X877966Y592660D01*
X878174Y592410D01*
X878549Y592285D01*
X879549D01*
G01X875616Y591243D02*
Y593743D01*
X876116Y593243D01*
G01Y591243D02*
X875116D01*
G01X873433Y591618D02*
X873183Y591410D01*
X872891Y591285D01*
X872516Y591243D01*
X872141Y591326D01*
X871849Y591493D01*
X871641Y591785D01*
X871599Y592118D01*
X871683Y592451D01*
X871891Y592660D01*
X872183Y592826D01*
X872474Y592868D01*
X872766Y592826D01*
X873141Y592660D01*
X873016Y593743D01*
X871891D01*
G01X870333Y591618D02*
X870083Y591410D01*
X869791Y591285D01*
X869416Y591243D01*
X869041Y591326D01*
X868749Y591493D01*
X868541Y591785D01*
X868499Y592118D01*
X868583Y592451D01*
X868791Y592660D01*
X869083Y592826D01*
X869374Y592868D01*
X869666Y592826D01*
X870041Y592660D01*
X869916Y593743D01*
X868791D01*
G01X884799Y626643D02*
Y629143D01*
X883758D01*
X883424Y629018D01*
X883216Y628851D01*
X883133Y628518D01*
X883216Y628185D01*
X883466Y627976D01*
X883758Y627851D01*
X884799D01*
G01X883758D02*
X883133Y626643D01*
G01X881658Y627685D02*
X881366Y627976D01*
X881116Y628143D01*
X880783Y628226D01*
X880491Y628143D01*
X880283Y627976D01*
X880116Y627726D01*
X880074Y627435D01*
X880116Y627185D01*
X880283Y626935D01*
X880533Y626726D01*
X880824Y626643D01*
X881158Y626726D01*
X881449Y626976D01*
X881616Y627351D01*
X881658Y627768D01*
X881574Y628310D01*
X881449Y628601D01*
X881241Y628893D01*
X880949Y629101D01*
X880658Y629143D01*
X880366Y629060D01*
X880158Y628851D01*
G01X877266Y626643D02*
Y629143D01*
X878808Y627351D01*
X876724D01*
G01X874666Y626643D02*
X874374Y626685D01*
X874041Y626810D01*
X873833Y627018D01*
X873749Y627310D01*
X873833Y627601D01*
X874083Y627851D01*
X874458Y627976D01*
X874874D01*
X875124Y628060D01*
X875333Y628268D01*
X875416Y628560D01*
X875291Y628851D01*
X874999Y629060D01*
X874666Y629143D01*
X874333Y629060D01*
X874041Y628851D01*
X873916Y628560D01*
X873999Y628268D01*
X874208Y628060D01*
X874458Y627976D01*
X874874D01*
X875249Y627851D01*
X875499Y627601D01*
X875583Y627310D01*
X875499Y627018D01*
X875291Y626810D01*
X874958Y626685D01*
X874666Y626643D01*
G54D16*
G01X66350Y579700D02*
X62350D01*
G01X52050Y582250D02*
Y578250D01*
G01X44668Y569316D02*
Y565316D01*
G01X102674Y533824D02*
Y537824D01*
G01X139887Y563291D02*
X143887D01*
G01X142037Y552286D02*
X146037D01*
G01X131100Y594300D02*
X127100D01*
G01X143189Y593537D02*
X139189D01*
G01X99700Y713000D02*
Y714100D01*
G01Y710300D02*
Y711400D01*
G01X202700Y522200D02*
X206700D01*
G01X193400Y522300D02*
X197400D01*
G01X198055Y522151D02*
X202055D01*
G01X211445Y522249D02*
X207445D01*
G01X193250Y561250D02*
Y557250D01*
G01X150840Y552335D02*
X146840D01*
G01X197259Y579497D02*
Y575497D01*
G01X155495Y552366D02*
X151495D01*
G01X144567Y563191D02*
X148567D01*
G01X149257Y563223D02*
X153257D01*
G01X178348Y566251D02*
Y570251D01*
G01X179505Y578591D02*
X183505D01*
G01X189289Y580625D02*
Y584625D01*
G01X199830Y585440D02*
Y581440D01*
G01X182400Y557200D02*
Y561200D01*
G01X187930Y554000D02*
Y550000D01*
G01X177260Y617380D02*
Y613380D01*
G01X187880Y613540D02*
Y617540D01*
G01X158964Y720268D02*
X162964D01*
G01X212100Y522300D02*
X216100D01*
G01X219750Y607150D02*
Y611150D01*
G01X230384Y624409D02*
X226384D01*
G01X337400Y676100D02*
X340400Y679100D01*
G01X337400Y676100D02*
X334400Y679100D01*
G01X330900D02*
X353400D01*
G01X330900Y659600D02*
X343900D01*
G01X330900Y679100D02*
Y659600D01*
G01X377600Y601400D02*
X373600D01*
G01X351200Y634900D02*
X347200D01*
G01X356000D02*
X352000D01*
G01X381814Y627080D02*
Y631080D01*
G01X343900Y659600D02*
Y679100D01*
G01X443900Y34700D02*
X447900D01*
G01X505895Y57597D02*
X509895D01*
G01X494000Y53415D02*
X498000D01*
G01X705780Y318840D02*
X704680D01*
G01X708480D02*
X707380D01*
G01X687700Y306800D02*
X683700D01*
G01X692620Y320940D02*
X688620D01*
G01X698000Y545100D02*
X699100D01*
G01X695300D02*
X696400D01*
G01X707306Y600299D02*
X708406D01*
G01X704606D02*
X705706D01*
G01X696899Y609558D02*
Y605558D01*
G01X760300Y187200D02*
Y183200D01*
G01X792037Y204518D02*
Y200518D01*
G01X777800Y204500D02*
Y200500D01*
G01X796726Y365556D02*
X792726D01*
G01X761900Y489600D02*
X757900D01*
G01X806362Y204483D02*
Y200483D01*
G01X834000Y330500D02*
Y334500D01*
M02*
